G04 ================== begin FILE IDENTIFICATION RECORD ==================*
G04 Layout Name:  E:/<user>/9332_F0TG_MB_C/brd/0417/9332_F0TG_MB_C_V02_0417_0820.brd*
G04 Film Name:    gnd3*
G04 File Format:  Gerber RS274X*
G04 File Origin:  Cadence Allegro 17.2-S081*
G04 Origin Date:  Wed Apr 19 14:50:08 2023*
G04 *
G04 Layer:  DRAWING FORMAT/TITLE_BLOCK_A*
G04 Layer:  PIN/SPECIAL_DRILL*
G04 Layer:  VIA CLASS/GND3*
G04 Layer:  PIN/GND3*
G04 Layer:  MANUFACTURING/PHOTOPLOT_OUTLINE*
G04 Layer:  ETCH/GND3*
G04 Layer:  DRAWING FORMAT/TITLE_BLOCK*
G04 Layer:  DRAWING FORMAT/TITLE_DATA_GND3*
G04 *
G04 Offset:    (0.00 0.00)*
G04 Mirror:    No*
G04 Mode:      Negative*
G04 Rotation:  0*
G04 FullContactRelief:  No*
G04 UndefLineWidth:     6.00*
G04 ================== end FILE IDENTIFICATION RECORD ====================*
%FSLAX25Y25*MOIN*%
%IR0*IPPOS*OFA0.00000B0.00000*MIA0B0*SFA1.00000B1.00000*%
%ADD14C,.03*%
%ADD40C,.06*%
%ADD30C,.024*%
%ADD67C,.052*%
%ADD25C,.061*%
%AMMACRO53*
4,1,36,0.0,.01,
-.001736,.009848,
-.00342,.009397,
-.005,.00866,
-.006428,.00766,
-.00766,.006428,
-.00866,.005,
-.009397,.00342,
-.009848,.001736,
-.01,0.0,
-.009848,-.001736,
-.009397,-.00342,
-.00866,-.005,
-.00766,-.006428,
-.006428,-.00766,
-.005,-.00866,
-.00342,-.009397,
-.001736,-.009848,
0.0,-.01,
.001736,-.009848,
.00342,-.009397,
.005,-.00866,
.006428,-.00766,
.00766,-.006428,
.00866,-.005,
.009397,-.00342,
.009848,-.001736,
.01,0.0,
.009848,.001736,
.009397,.00342,
.00866,.005,
.00766,.006428,
.006428,.00766,
.005,.00866,
.00342,.009397,
.001736,.009848,
0.0,.01,
0.0*
%
%ADD53MACRO53*%
%ADD42C,.071*%
%ADD23C,.026*%
%ADD63C,.064*%
%AMMACRO28*
4,1,36,.0025,0.0,
.002462,.000434,
.002349,.000855,
.002165,.00125,
.001915,.001607,
.001607,.001915,
.00125,.002165,
.000855,.002349,
.000434,.002462,
0.0,.0025,
-.000434,.002462,
-.000855,.002349,
-.00125,.002165,
-.001607,.001915,
-.001915,.001607,
-.002165,.00125,
-.002349,.000855,
-.002462,.000434,
-.0025,0.0,
-.002462,-.000434,
-.002349,-.000855,
-.002165,-.00125,
-.001915,-.001607,
-.001607,-.001915,
-.00125,-.002165,
-.000855,-.002349,
-.000434,-.002462,
0.0,-.0025,
.000434,-.002462,
.000855,-.002349,
.00125,-.002165,
.001607,-.001915,
.001915,-.001607,
.002165,-.00125,
.002349,-.000855,
.002462,-.000434,
.0025,0.0,
135.*
%
%ADD28MACRO28*%
%ADD24C,.028*%
%AMMACRO19*
4,1,36,.0025,0.0,
.002462,.000434,
.002349,.000855,
.002165,.00125,
.001915,.001607,
.001607,.001915,
.00125,.002165,
.000855,.002349,
.000434,.002462,
0.0,.0025,
-.000434,.002462,
-.000855,.002349,
-.00125,.002165,
-.001607,.001915,
-.001915,.001607,
-.002165,.00125,
-.002349,.000855,
-.002462,.000434,
-.0025,0.0,
-.002462,-.000434,
-.002349,-.000855,
-.002165,-.00125,
-.001915,-.001607,
-.001607,-.001915,
-.00125,-.002165,
-.000855,-.002349,
-.000434,-.002462,
0.0,-.0025,
.000434,-.002462,
.000855,-.002349,
.00125,-.002165,
.001607,-.001915,
.001915,-.001607,
.002165,-.00125,
.002349,-.000855,
.002462,-.000434,
.0025,0.0,
180.*
%
%ADD19MACRO19*%
%AMMACRO17*
4,1,36,.0025,0.0,
.002462,.000434,
.002349,.000855,
.002165,.00125,
.001915,.001607,
.001607,.001915,
.00125,.002165,
.000855,.002349,
.000434,.002462,
0.0,.0025,
-.000434,.002462,
-.000855,.002349,
-.00125,.002165,
-.001607,.001915,
-.001915,.001607,
-.002165,.00125,
-.002349,.000855,
-.002462,.000434,
-.0025,0.0,
-.002462,-.000434,
-.002349,-.000855,
-.002165,-.00125,
-.001915,-.001607,
-.001607,-.001915,
-.00125,-.002165,
-.000855,-.002349,
-.000434,-.002462,
0.0,-.0025,
.000434,-.002462,
.000855,-.002349,
.00125,-.002165,
.001607,-.001915,
.001915,-.001607,
.002165,-.00125,
.002349,-.000855,
.002462,-.000434,
.0025,0.0,
225.*
%
%ADD17MACRO17*%
%AMMACRO10*
4,1,36,.0025,0.0,
.002462,.000434,
.002349,.000855,
.002165,.00125,
.001915,.001607,
.001607,.001915,
.00125,.002165,
.000855,.002349,
.000434,.002462,
0.0,.0025,
-.000434,.002462,
-.000855,.002349,
-.00125,.002165,
-.001607,.001915,
-.001915,.001607,
-.002165,.00125,
-.002349,.000855,
-.002462,.000434,
-.0025,0.0,
-.002462,-.000434,
-.002349,-.000855,
-.002165,-.00125,
-.001915,-.001607,
-.001607,-.001915,
-.00125,-.002165,
-.000855,-.002349,
-.000434,-.002462,
0.0,-.0025,
.000434,-.002462,
.000855,-.002349,
.00125,-.002165,
.001607,-.001915,
.001915,-.001607,
.002165,-.00125,
.002349,-.000855,
.002462,-.000434,
.0025,0.0,
270.*
%
%ADD10MACRO10*%
%AMMACRO81*
4,1,36,.003,0.0,
.002954,.000521,
.002819,.001026,
.002598,.0015,
.002298,.001928,
.001928,.002298,
.0015,.002598,
.001026,.002819,
.000521,.002954,
0.0,.003,
-.000521,.002954,
-.001026,.002819,
-.0015,.002598,
-.001928,.002298,
-.002298,.001928,
-.002598,.0015,
-.002819,.001026,
-.002954,.000521,
-.003,0.0,
-.002954,-.000521,
-.002819,-.001026,
-.002598,-.0015,
-.002298,-.001928,
-.001928,-.002298,
-.0015,-.002598,
-.001026,-.002819,
-.000521,-.002954,
0.0,-.003,
.000521,-.002954,
.001026,-.002819,
.0015,-.002598,
.001928,-.002298,
.002298,-.001928,
.002598,-.0015,
.002819,-.001026,
.002954,-.000521,
.003,0.0,
270.*
%
%ADD81MACRO81*%
%AMMACRO43*
4,1,36,-.0025,0.0,
-.002462,.000434,
-.002349,.000855,
-.002165,.00125,
-.001915,.001607,
-.001607,.001915,
-.00125,.002165,
-.000855,.002349,
-.000434,.002462,
0.0,.0025,
.000434,.002462,
.000855,.002349,
.00125,.002165,
.001607,.001915,
.001915,.001607,
.002165,.00125,
.002349,.000855,
.002462,.000434,
.0025,0.0,
.002462,-.000434,
.002349,-.000855,
.002165,-.00125,
.001915,-.001607,
.001607,-.001915,
.00125,-.002165,
.000855,-.002349,
.000434,-.002462,
0.0,-.0025,
-.000434,-.002462,
-.000855,-.002349,
-.00125,-.002165,
-.001607,-.001915,
-.001915,-.001607,
-.002165,-.00125,
-.002349,-.000855,
-.002462,-.000434,
-.0025,0.0,
180.*
%
%ADD43MACRO43*%
%AMMACRO32*
4,1,36,.003,0.0,
.002954,.000521,
.002819,.001026,
.002598,.0015,
.002298,.001928,
.001928,.002298,
.0015,.002598,
.001026,.002819,
.000521,.002954,
0.0,.003,
-.000521,.002954,
-.001026,.002819,
-.0015,.002598,
-.001928,.002298,
-.002298,.001928,
-.002598,.0015,
-.002819,.001026,
-.002954,.000521,
-.003,0.0,
-.002954,-.000521,
-.002819,-.001026,
-.002598,-.0015,
-.002298,-.001928,
-.001928,-.002298,
-.0015,-.002598,
-.001026,-.002819,
-.000521,-.002954,
0.0,-.003,
.000521,-.002954,
.001026,-.002819,
.0015,-.002598,
.001928,-.002298,
.002298,-.001928,
.002598,-.0015,
.002819,-.001026,
.002954,-.000521,
.003,0.0,
180.*
%
%ADD32MACRO32*%
%ADD22C,.074*%
%ADD20C,.0263*%
%AMMACRO80*
4,1,36,-.003,0.0,
-.002954,.000521,
-.002819,.001026,
-.002598,.0015,
-.002298,.001928,
-.001928,.002298,
-.0015,.002598,
-.001026,.002819,
-.000521,.002954,
0.0,.003,
.000521,.002954,
.001026,.002819,
.0015,.002598,
.001928,.002298,
.002298,.001928,
.002598,.0015,
.002819,.001026,
.002954,.000521,
.003,0.0,
.002954,-.000521,
.002819,-.001026,
.002598,-.0015,
.002298,-.001928,
.001928,-.002298,
.0015,-.002598,
.001026,-.002819,
.000521,-.002954,
0.0,-.003,
-.000521,-.002954,
-.001026,-.002819,
-.0015,-.002598,
-.001928,-.002298,
-.002298,-.001928,
-.002598,-.0015,
-.002819,-.001026,
-.002954,-.000521,
-.003,0.0,
270.*
%
%ADD80MACRO80*%
%ADD79C,.0435*%
%ADD66C,.075*%
%ADD61C,.06015*%
%ADD47C,.066*%
%ADD50C,.076*%
%ADD49C,.095*%
%ADD31C,.0248*%
%ADD73C,.087*%
%ADD34C,.03417*%
%AMMACRO13*
4,1,18,.09673,.06845,
.107147,.050613,
.114308,.031238,
.117996,.010914,
.118098,-.009741,
.114613,-.030101,
.107644,-.049546,
.097406,-.067485,
.09673,-.06845,
.10175,-.07347,
.112962,-.054685,
.120742,-.034239,
.124853,-.012752,
.125171,.009122,
.121685,.030719,
.114502,.051383,
.10384,.070486,
.10175,.07347,
.09673,.06845,
0.0*
4,1,18,.06845,-.09673,
.050613,-.107147,
.031238,-.114308,
.010914,-.117996,
-.009741,-.118098,
-.030101,-.114613,
-.049546,-.107644,
-.067485,-.097406,
-.06845,-.09673,
-.07347,-.10175,
-.054685,-.112962,
-.034239,-.120742,
-.012752,-.124853,
.009122,-.125171,
.030719,-.121685,
.051383,-.114502,
.070486,-.10384,
.07347,-.10175,
.06845,-.09673,
0.0*
4,1,18,-.09673,-.06845,
-.107147,-.050613,
-.114308,-.031238,
-.117996,-.010914,
-.118098,.009741,
-.114613,.030101,
-.107644,.049546,
-.097406,.067485,
-.09673,.06845,
-.10175,.07347,
-.112962,.054685,
-.120742,.034239,
-.124853,.012752,
-.125171,-.009122,
-.121685,-.030719,
-.114502,-.051383,
-.10384,-.070486,
-.10175,-.07347,
-.09673,-.06845,
0.0*
4,1,18,-.06845,.09673,
-.050613,.107147,
-.031238,.114308,
-.010914,.117996,
.009741,.118098,
.030101,.114613,
.049546,.107644,
.067485,.097406,
.06845,.09673,
.07347,.10175,
.054685,.112962,
.034239,.120742,
.012752,.124853,
-.009122,.125171,
-.030719,.121685,
-.051383,.114502,
-.070486,.10384,
-.07347,.10175,
-.06845,.09673,
0.0*
%
%ADD13MACRO13*%
%AMMACRO36*
4,1,16,.0711,.04282,
.077455,.029823,
.081457,.01592,
.082984,.001533,
.08199,-.0129,
.078504,-.026942,
.072633,-.040164,
.0711,-.04282,
.07619,-.04791,
.083352,-.033952,
.087981,-.018962,
.089937,-.003396,
.089161,.012273,
.085675,.027569,
.079586,.042027,
.07619,.04791,
.0711,.04282,
0.0*
4,1,16,.04282,-.0711,
.029823,-.077455,
.01592,-.081457,
.001533,-.082984,
-.0129,-.08199,
-.026942,-.078504,
-.040164,-.072633,
-.04282,-.0711,
-.04791,-.07619,
-.033952,-.083352,
-.018962,-.087981,
-.003396,-.089937,
.012273,-.089161,
.027569,-.085675,
.042027,-.079586,
.04791,-.07619,
.04282,-.0711,
0.0*
4,1,16,-.0711,-.04282,
-.077455,-.029823,
-.081457,-.01592,
-.082984,-.001533,
-.08199,.0129,
-.078504,.026942,
-.072633,.040164,
-.0711,.04282,
-.07619,.04791,
-.083352,.033952,
-.087981,.018962,
-.089937,.003396,
-.089161,-.012273,
-.085675,-.027569,
-.079586,-.042027,
-.07619,-.04791,
-.0711,-.04282,
0.0*
4,1,16,-.04282,.0711,
-.029823,.077455,
-.01592,.081457,
-.001533,.082984,
.0129,.08199,
.026942,.078504,
.040164,.072633,
.04282,.0711,
.04791,.07619,
.033952,.083352,
.018962,.087981,
.003396,.089937,
-.012273,.089161,
-.027569,.085675,
-.042027,.079586,
-.04791,.07619,
-.04282,.0711,
0.0*
%
%ADD36MACRO36*%
%AMMACRO64*
4,1,16,.02584,.01524,
.028094,.010521,
.029494,.005483,
.029998,.000278,
.029591,-.004935,
.028284,-.009999,
.026118,-.014758,
.02584,-.01524,
.03092,-.02032,
.033979,-.014642,
.036005,-.008519,
.036938,-.002138,
.036748,.004309,
.035441,.010625,
.033058,.016618,
.03092,.02032,
.02584,.01524,
90.*
4,1,16,.01524,-.02584,
.010521,-.028094,
.005483,-.029494,
.000278,-.029998,
-.004935,-.029591,
-.009999,-.028284,
-.014758,-.026118,
-.01524,-.02584,
-.02032,-.03092,
-.014642,-.033979,
-.008519,-.036005,
-.002138,-.036938,
.004309,-.036748,
.010625,-.035441,
.016618,-.033058,
.02032,-.03092,
.01524,-.02584,
90.*
4,1,16,-.02584,-.01524,
-.028094,-.010521,
-.029494,-.005483,
-.029998,-.000278,
-.029591,.004935,
-.028284,.009999,
-.026118,.014758,
-.02584,.01524,
-.03092,.02032,
-.033979,.014642,
-.036005,.008519,
-.036938,.002138,
-.036748,-.004309,
-.035441,-.010625,
-.033058,-.016618,
-.03092,-.02032,
-.02584,-.01524,
90.*
4,1,16,-.01524,.02584,
-.010521,.028094,
-.005483,.029494,
-.000278,.029998,
.004935,.029591,
.009999,.028284,
.014758,.026118,
.01524,.02584,
.02032,.03092,
.014642,.033979,
.008519,.036005,
.002138,.036938,
-.004309,.036748,
-.010625,.035441,
-.016618,.033058,
-.02032,.03092,
-.01524,.02584,
90.*
%
%ADD64MACRO64*%
%AMMACRO46*
4,1,15,.02438,.01377,
.026401,.009327,
.027619,.004601,
.027999,-.000265,
.027527,-.005123,
.02622,-.009825,
.02438,-.01377,
.02948,-.01887,
.032309,-.013464,
.034156,-.007649,
.034965,-.001602,
.034712,.004494,
.033405,.010454,
.031082,.016095,
.02948,.01887,
.02438,.01377,
90.*
4,1,15,.01377,-.02438,
.009327,-.026401,
.004601,-.027619,
-.000265,-.027999,
-.005123,-.027527,
-.009825,-.02622,
-.01377,-.02438,
-.01887,-.02948,
-.013464,-.032309,
-.007649,-.034156,
-.001602,-.034965,
.004494,-.034712,
.010454,-.033405,
.016095,-.031082,
.01887,-.02948,
.01377,-.02438,
90.*
4,1,15,-.02438,-.01377,
-.026401,-.009327,
-.027619,-.004601,
-.027999,.000265,
-.027527,.005123,
-.02622,.009825,
-.02438,.01377,
-.02948,.01887,
-.032309,.013464,
-.034156,.007649,
-.034965,.001602,
-.034712,-.004494,
-.033405,-.010454,
-.031082,-.016095,
-.02948,-.01887,
-.02438,-.01377,
90.*
4,1,15,-.01377,.02438,
-.009327,.026401,
-.004601,.027619,
.000265,.027999,
.005123,.027527,
.009825,.02622,
.01377,.02438,
.01887,.02948,
.013464,.032309,
.007649,.034156,
.001602,.034965,
-.004494,.034712,
-.010454,.033405,
-.016095,.031082,
-.01887,.02948,
-.01377,.02438,
90.*
%
%ADD46MACRO46*%
%AMMACRO16*
4,1,16,.07001,.04172,
.076191,.028929,
.080057,.015259,
.08149,.001126,
.080448,-.013042,
.076961,-.026814,
.071136,-.03977,
.07001,-.04172,
.0751,-.04682,
.082089,-.033068,
.086584,-.018311,
.088449,-.002997,
.087625,.012407,
.08414,.027435,
.078097,.041629,
.0751,.04682,
.07001,.04172,
0.0*
4,1,16,.04172,-.07001,
.028929,-.076191,
.015259,-.080057,
.001126,-.08149,
-.013042,-.080448,
-.026814,-.076961,
-.03977,-.071136,
-.04172,-.07001,
-.04682,-.0751,
-.033068,-.082089,
-.018311,-.086584,
-.002997,-.088449,
.012407,-.087625,
.027435,-.08414,
.041629,-.078097,
.04682,-.0751,
.04172,-.07001,
0.0*
4,1,16,-.07001,-.04172,
-.076191,-.028929,
-.080057,-.015259,
-.08149,-.001126,
-.080448,.013042,
-.076961,.026814,
-.071136,.03977,
-.07001,.04172,
-.0751,.04682,
-.082089,.033068,
-.086584,.018311,
-.088449,.002997,
-.087625,-.012407,
-.08414,-.027435,
-.078097,-.041629,
-.0751,-.04682,
-.07001,-.04172,
0.0*
4,1,16,-.04172,.07001,
-.028929,.076191,
-.015259,.080057,
-.001126,.08149,
.013042,.080448,
.026814,.076961,
.03977,.071136,
.04172,.07001,
.04682,.0751,
.033068,.082089,
.018311,.086584,
.002997,.088449,
-.012407,.087625,
-.027435,.08414,
-.041629,.078097,
-.04682,.0751,
-.04172,.07001,
0.0*
%
%ADD16MACRO16*%
%AMMACRO65*
4,1,15,.02142,.01082,
.022973,.006936,
.023829,.002841,
.02396,-.00134,
.023364,-.00548,
.022057,-.009454,
.02142,-.01082,
.02657,-.01597,
.02894,-.011114,
.03043,-.005919,
.030995,-.000545,
.030619,.004845,
.029313,.010088,
.027115,.015025,
.02657,.01597,
.02142,.01082,
0.0*
4,1,15,.01082,-.02142,
.006936,-.022973,
.002841,-.023829,
-.00134,-.02396,
-.00548,-.023364,
-.009454,-.022057,
-.01082,-.02142,
-.01597,-.02657,
-.011114,-.02894,
-.005919,-.03043,
-.000545,-.030995,
.004845,-.030619,
.010088,-.029313,
.015025,-.027115,
.01597,-.02657,
.01082,-.02142,
0.0*
4,1,15,-.02142,-.01082,
-.022973,-.006936,
-.023829,-.002841,
-.02396,.00134,
-.023364,.00548,
-.022057,.009454,
-.02142,.01082,
-.02657,.01597,
-.02894,.011114,
-.03043,.005919,
-.030995,.000545,
-.030619,-.004845,
-.029313,-.010088,
-.027115,-.015025,
-.02657,-.01597,
-.02142,-.01082,
0.0*
4,1,15,-.01082,.02142,
-.006936,.022973,
-.002841,.023829,
.00134,.02396,
.00548,.023364,
.009454,.022057,
.01082,.02142,
.01597,.02657,
.011114,.02894,
.005919,.03043,
.000545,.030995,
-.004845,.030619,
-.010088,.029313,
-.015025,.027115,
-.01597,.02657,
-.01082,.02142,
0.0*
%
%ADD65MACRO65*%
%AMMACRO51*
4,1,15,.02475,.01414,
.026829,.009627,
.028094,.004822,
.028504,-.000129,
.028049,-.005077,
.026741,-.009871,
.02475,-.01414,
.02984,-.01923,
.032726,-.013756,
.034617,-.007864,
.035457,-.001734,
.03522,.00445,
.033912,.010498,
.031574,.016227,
.02984,.01923,
.02475,.01414,
0.0*
4,1,15,.01414,-.02475,
.009627,-.026829,
.004822,-.028094,
-.000129,-.028504,
-.005077,-.028049,
-.009871,-.026741,
-.01414,-.02475,
-.01923,-.02984,
-.013756,-.032726,
-.007864,-.034617,
-.001734,-.035457,
.00445,-.03522,
.010498,-.033912,
.016227,-.031574,
.01923,-.02984,
.01414,-.02475,
0.0*
4,1,15,-.02475,-.01414,
-.026829,-.009627,
-.028094,-.004822,
-.028504,.000129,
-.028049,.005077,
-.026741,.009871,
-.02475,.01414,
-.02984,.01923,
-.032726,.013756,
-.034617,.007864,
-.035457,.001734,
-.03522,-.00445,
-.033912,-.010498,
-.031574,-.016227,
-.02984,-.01923,
-.02475,-.01414,
0.0*
4,1,15,-.01414,.02475,
-.009627,.026829,
-.004822,.028094,
.000129,.028504,
.005077,.028049,
.009871,.026741,
.01414,.02475,
.01923,.02984,
.013756,.032726,
.007864,.034617,
.001734,.035457,
-.00445,.03522,
-.010498,.033912,
-.016227,.031574,
-.01923,.02984,
-.01414,.02475,
0.0*
%
%ADD51MACRO51*%
%AMMACRO76*
4,1,15,.03682,.01914,
.039584,.012455,
.041146,.005393,
.041457,-.001834,
.040509,-.009005,
.03833,-.015903,
.03682,-.01914,
.04197,-.0243,
.045552,-.016643,
.04775,-.00848,
.048497,-.000059,
.047771,.008363,
.045593,.016531,
.042029,.024197,
.04197,.0243,
.03682,.01914,
0.0*
4,1,15,.01914,-.03682,
.012455,-.039584,
.005393,-.041146,
-.001834,-.041457,
-.009005,-.040509,
-.015903,-.03833,
-.01914,-.03682,
-.0243,-.04197,
-.016643,-.045552,
-.00848,-.04775,
-.000059,-.048497,
.008363,-.047771,
.016531,-.045593,
.024197,-.042029,
.0243,-.04197,
.01914,-.03682,
0.0*
4,1,15,-.03682,-.01914,
-.039584,-.012455,
-.041146,-.005393,
-.041457,.001834,
-.040509,.009005,
-.03833,.015903,
-.03682,.01914,
-.04197,.0243,
-.045552,.016643,
-.04775,.00848,
-.048497,.000059,
-.047771,-.008363,
-.045593,-.016531,
-.042029,-.024197,
-.04197,-.0243,
-.03682,-.01914,
0.0*
4,1,15,-.01914,.03682,
-.012455,.039584,
-.005393,.041146,
.001834,.041457,
.009005,.040509,
.015903,.03833,
.01914,.03682,
.0243,.04197,
.016643,.045552,
.00848,.04775,
.000059,.048497,
-.008363,.047771,
-.016531,.045593,
-.024197,.042029,
-.0243,.04197,
-.01914,.03682,
0.0*
%
%ADD76MACRO76*%
%AMMACRO72*
4,1,36,.0025,0.0,
.002462,.000434,
.002349,.000855,
.002165,.00125,
.001915,.001607,
.001607,.001915,
.00125,.002165,
.000855,.002349,
.000434,.002462,
0.0,.0025,
-.000434,.002462,
-.000855,.002349,
-.00125,.002165,
-.001607,.001915,
-.001915,.001607,
-.002165,.00125,
-.002349,.000855,
-.002462,.000434,
-.0025,0.0,
-.002462,-.000434,
-.002349,-.000855,
-.002165,-.00125,
-.001915,-.001607,
-.001607,-.001915,
-.00125,-.002165,
-.000855,-.002349,
-.000434,-.002462,
0.0,-.0025,
.000434,-.002462,
.000855,-.002349,
.00125,-.002165,
.001607,-.001915,
.001915,-.001607,
.002165,-.00125,
.002349,-.000855,
.002462,-.000434,
.0025,0.0,
134.996*
%
%ADD72MACRO72*%
%AMMACRO74*
4,1,15,-.03682,.01914,
-.039584,.012455,
-.041146,.005393,
-.041457,-.001834,
-.040509,-.009005,
-.03833,-.015903,
-.03682,-.01914,
-.04197,-.0243,
-.045552,-.016643,
-.04775,-.00848,
-.048497,-.000059,
-.047771,.008363,
-.045593,.016531,
-.042029,.024197,
-.04197,.0243,
-.03682,.01914,
0.0*
4,1,15,-.01914,-.03682,
-.012455,-.039584,
-.005393,-.041146,
.001834,-.041457,
.009005,-.040509,
.015903,-.03833,
.01914,-.03682,
.0243,-.04197,
.016643,-.045552,
.00848,-.04775,
.000059,-.048497,
-.008363,-.047771,
-.016531,-.045593,
-.024197,-.042029,
-.0243,-.04197,
-.01914,-.03682,
0.0*
4,1,15,.03682,-.01914,
.039584,-.012455,
.041146,-.005393,
.041457,.001834,
.040509,.009005,
.03833,.015903,
.03682,.01914,
.04197,.0243,
.045552,.016643,
.04775,.00848,
.048497,.000059,
.047771,-.008363,
.045593,-.016531,
.042029,-.024197,
.04197,-.0243,
.03682,-.01914,
0.0*
4,1,15,.01914,.03682,
.012455,.039584,
.005393,.041146,
-.001834,.041457,
-.009005,.040509,
-.015903,.03833,
-.01914,.03682,
-.0243,.04197,
-.016643,.045552,
-.00848,.04775,
-.000059,.048497,
.008363,.047771,
.016531,.045593,
.024197,.042029,
.0243,.04197,
.01914,.03682,
0.0*
%
%ADD74MACRO74*%
%AMMACRO38*
4,1,36,.003,0.0,
.002954,.000521,
.002819,.001026,
.002598,.0015,
.002298,.001928,
.001928,.002298,
.0015,.002598,
.001026,.002819,
.000521,.002954,
0.0,.003,
-.000521,.002954,
-.001026,.002819,
-.0015,.002598,
-.001928,.002298,
-.002298,.001928,
-.002598,.0015,
-.002819,.001026,
-.002954,.000521,
-.003,0.0,
-.002954,-.000521,
-.002819,-.001026,
-.002598,-.0015,
-.002298,-.001928,
-.001928,-.002298,
-.0015,-.002598,
-.001026,-.002819,
-.000521,-.002954,
0.0,-.003,
.000521,-.002954,
.001026,-.002819,
.0015,-.002598,
.001928,-.002298,
.002298,-.001928,
.002598,-.0015,
.002819,-.001026,
.002954,-.000521,
.003,0.0,
179.996*
%
%ADD38MACRO38*%
%ADD59O,.285X.23*%
%ADD71C,.142*%
%AMMACRO60*
4,1,36,0.0,.01,
-.001736,.009848,
-.00342,.009397,
-.005,.00866,
-.006428,.00766,
-.00766,.006428,
-.00866,.005,
-.009397,.00342,
-.009848,.001736,
-.01,0.0,
-.009848,-.001736,
-.009397,-.00342,
-.00866,-.005,
-.00766,-.006428,
-.006428,-.00766,
-.005,-.00866,
-.00342,-.009397,
-.001736,-.009848,
0.0,-.01,
.001736,-.009848,
.00342,-.009397,
.005,-.00866,
.006428,-.00766,
.00766,-.006428,
.00866,-.005,
.009397,-.00342,
.009848,-.001736,
.01,0.0,
.009848,.001736,
.009397,.00342,
.00866,.005,
.00766,.006428,
.006428,.00766,
.005,.00866,
.00342,.009397,
.001736,.009848,
0.0,.01,
180.*
%
%ADD60MACRO60*%
%ADD35O,.219X.156*%
%ADD11C,.125*%
%ADD27C,.424*%
%ADD18C,.155*%
%ADD52C,.291*%
%ADD54C,.247*%
%ADD45C,.256*%
%AMMACRO33*
4,1,36,0.0,.0085,
.001476,.008371,
.002907,.007987,
.00425,.007361,
.005464,.006511,
.006511,.005464,
.007361,.00425,
.007987,.002907,
.008371,.001476,
.0085,0.0,
.008371,-.001476,
.007987,-.002907,
.007361,-.00425,
.006511,-.005464,
.005464,-.006511,
.00425,-.007361,
.002907,-.007987,
.001476,-.008371,
0.0,-.0085,
-.001476,-.008371,
-.002907,-.007987,
-.00425,-.007361,
-.005464,-.006511,
-.006511,-.005464,
-.007361,-.00425,
-.007987,-.002907,
-.008371,-.001476,
-.0085,0.0,
-.008371,.001476,
-.007987,.002907,
-.007361,.00425,
-.006511,.005464,
-.005464,.006511,
-.00425,.007361,
-.002907,.007987,
-.001476,.008371,
0.0,.0085,
180.*
%
%ADD33MACRO33*%
%AMMACRO58*
4,1,20,-.0075,-.05555,
-.0075,-.06273,
-.013677,-.060878,
-.019439,-.057981,
-.024611,-.054127,
-.029034,-.049434,
-.032576,-.044045,
-.035127,-.038122,
-.036612,-.031846,
-.037,-.0265,
-.037,-.0075,
-.03,-.0075,
-.03,-.0265,
-.029544,-.03171,
-.028191,-.036762,
-.02598,-.041502,
-.022981,-.045786,
-.019282,-.049484,
-.014998,-.052484,
-.010258,-.054694,
-.0075,-.05555,
90.*
4,1,20,.0075,-.06273,
.0075,-.05555,
.01243,-.053806,
.016983,-.051232,
.02102,-.047906,
.024418,-.043931,
.027073,-.039425,
.028906,-.034527,
.029861,-.029385,
.03,-.0265,
.03,-.0075,
.037,-.0075,
.037,-.0265,
.036438,-.032925,
.034769,-.039154,
.032043,-.044999,
.028344,-.050282,
.023784,-.054842,
.018501,-.058541,
.012656,-.061266,
.0075,-.06273,
90.*
4,1,20,-.0075,.06273,
-.0075,.05555,
-.01243,.053806,
-.016983,.051232,
-.02102,.047906,
-.024418,.043931,
-.027073,.039425,
-.028906,.034527,
-.029861,.029385,
-.03,.0265,
-.03,.0075,
-.037,.0075,
-.037,.0265,
-.036438,.032925,
-.034769,.039154,
-.032043,.044999,
-.028344,.050282,
-.023784,.054842,
-.018501,.058541,
-.012656,.061266,
-.0075,.06273,
90.*
4,1,20,.0075,.05555,
.0075,.06273,
.013677,.060878,
.019439,.057981,
.024611,.054127,
.029034,.049434,
.032576,.044045,
.035127,.038122,
.036612,.031846,
.037,.0265,
.037,.0075,
.03,.0075,
.03,.0265,
.029544,.03171,
.028191,.036762,
.02598,.041502,
.022981,.045786,
.019282,.049484,
.014998,.052484,
.010258,.054694,
.0075,.05555,
90.*
%
%ADD58MACRO58*%
%AMMACRO15*
4,1,36,.0025,0.0,
.002462,.000434,
.002349,.000855,
.002165,.00125,
.001915,.001607,
.001607,.001915,
.00125,.002165,
.000855,.002349,
.000434,.002462,
0.0,.0025,
-.000434,.002462,
-.000855,.002349,
-.00125,.002165,
-.001607,.001915,
-.001915,.001607,
-.002165,.00125,
-.002349,.000855,
-.002462,.000434,
-.0025,0.0,
-.002462,-.000434,
-.002349,-.000855,
-.002165,-.00125,
-.001915,-.001607,
-.001607,-.001915,
-.00125,-.002165,
-.000855,-.002349,
-.000434,-.002462,
0.0,-.0025,
.000434,-.002462,
.000855,-.002349,
.00125,-.002165,
.001607,-.001915,
.001915,-.001607,
.002165,-.00125,
.002349,-.000855,
.002462,-.000434,
.0025,0.0,
90.*
%
%ADD15MACRO15*%
%AMMACRO55*
4,1,36,0.0,.019,
-.003299,.018711,
-.006498,.017854,
-.0095,.016454,
-.012213,.014555,
-.014555,.012213,
-.016454,.0095,
-.017854,.006498,
-.018711,.003299,
-.019,0.0,
-.018711,-.003299,
-.017854,-.006498,
-.016454,-.0095,
-.014555,-.012213,
-.012213,-.014555,
-.0095,-.016454,
-.006498,-.017854,
-.003299,-.018711,
0.0,-.019,
.003299,-.018711,
.006498,-.017854,
.0095,-.016454,
.012213,-.014555,
.014555,-.012213,
.016454,-.0095,
.017854,-.006498,
.018711,-.003299,
.019,0.0,
.018711,.003299,
.017854,.006498,
.016454,.0095,
.014555,.012213,
.012213,.014555,
.0095,.016454,
.006498,.017854,
.003299,.018711,
0.0,.019,
270.*
%
%ADD55MACRO55*%
%AMMACRO39*
4,1,36,.003,0.0,
.002954,.000521,
.002819,.001026,
.002598,.0015,
.002298,.001928,
.001928,.002298,
.0015,.002598,
.001026,.002819,
.000521,.002954,
0.0,.003,
-.000521,.002954,
-.001026,.002819,
-.0015,.002598,
-.001928,.002298,
-.002298,.001928,
-.002598,.0015,
-.002819,.001026,
-.002954,.000521,
-.003,0.0,
-.002954,-.000521,
-.002819,-.001026,
-.002598,-.0015,
-.002298,-.001928,
-.001928,-.002298,
-.0015,-.002598,
-.001026,-.002819,
-.000521,-.002954,
0.0,-.003,
.000521,-.002954,
.001026,-.002819,
.0015,-.002598,
.001928,-.002298,
.002298,-.001928,
.002598,-.0015,
.002819,-.001026,
.002954,-.000521,
.003,0.0,
90.*
%
%ADD39MACRO39*%
%AMMACRO12*
4,1,36,.0025,0.0,
.002462,.000434,
.002349,.000855,
.002165,.00125,
.001915,.001607,
.001607,.001915,
.00125,.002165,
.000855,.002349,
.000434,.002462,
0.0,.0025,
-.000434,.002462,
-.000855,.002349,
-.00125,.002165,
-.001607,.001915,
-.001915,.001607,
-.002165,.00125,
-.002349,.000855,
-.002462,.000434,
-.0025,0.0,
-.002462,-.000434,
-.002349,-.000855,
-.002165,-.00125,
-.001915,-.001607,
-.001607,-.001915,
-.00125,-.002165,
-.000855,-.002349,
-.000434,-.002462,
0.0,-.0025,
.000434,-.002462,
.000855,-.002349,
.00125,-.002165,
.001607,-.001915,
.001915,-.001607,
.002165,-.00125,
.002349,-.000855,
.002462,-.000434,
.0025,0.0,
0.0*
%
%ADD12MACRO12*%
%AMMACRO78*
4,1,36,-.003,0.0,
-.002954,.000521,
-.002819,.001026,
-.002598,.0015,
-.002298,.001928,
-.001928,.002298,
-.0015,.002598,
-.001026,.002819,
-.000521,.002954,
0.0,.003,
.000521,.002954,
.001026,.002819,
.0015,.002598,
.001928,.002298,
.002298,.001928,
.002598,.0015,
.002819,.001026,
.002954,.000521,
.003,0.0,
.002954,-.000521,
.002819,-.001026,
.002598,-.0015,
.002298,-.001928,
.001928,-.002298,
.0015,-.002598,
.001026,-.002819,
.000521,-.002954,
0.0,-.003,
-.000521,-.002954,
-.001026,-.002819,
-.0015,-.002598,
-.001928,-.002298,
-.002298,-.001928,
-.002598,-.0015,
-.002819,-.001026,
-.002954,-.000521,
-.003,0.0,
90.*
%
%ADD78MACRO78*%
%AMMACRO44*
4,1,36,-.0025,0.0,
-.002462,.000434,
-.002349,.000855,
-.002165,.00125,
-.001915,.001607,
-.001607,.001915,
-.00125,.002165,
-.000855,.002349,
-.000434,.002462,
0.0,.0025,
.000434,.002462,
.000855,.002349,
.00125,.002165,
.001607,.001915,
.001915,.001607,
.002165,.00125,
.002349,.000855,
.002462,.000434,
.0025,0.0,
.002462,-.000434,
.002349,-.000855,
.002165,-.00125,
.001915,-.001607,
.001607,-.001915,
.00125,-.002165,
.000855,-.002349,
.000434,-.002462,
0.0,-.0025,
-.000434,-.002462,
-.000855,-.002349,
-.00125,-.002165,
-.001607,-.001915,
-.001915,-.001607,
-.002165,-.00125,
-.002349,-.000855,
-.002462,-.000434,
-.0025,0.0,
0.0*
%
%ADD44MACRO44*%
%ADD37C,.188*%
%AMMACRO29*
4,1,36,.003,0.0,
.002954,.000521,
.002819,.001026,
.002598,.0015,
.002298,.001928,
.001928,.002298,
.0015,.002598,
.001026,.002819,
.000521,.002954,
0.0,.003,
-.000521,.002954,
-.001026,.002819,
-.0015,.002598,
-.001928,.002298,
-.002298,.001928,
-.002598,.0015,
-.002819,.001026,
-.002954,.000521,
-.003,0.0,
-.002954,-.000521,
-.002819,-.001026,
-.002598,-.0015,
-.002298,-.001928,
-.001928,-.002298,
-.0015,-.002598,
-.001026,-.002819,
-.000521,-.002954,
0.0,-.003,
.000521,-.002954,
.001026,-.002819,
.0015,-.002598,
.001928,-.002298,
.002298,-.001928,
.002598,-.0015,
.002819,-.001026,
.002954,-.000521,
.003,0.0,
0.0*
%
%ADD29MACRO29*%
%AMMACRO21*
4,1,16,.02584,.01524,
.028094,.010521,
.029494,.005483,
.029998,.000278,
.029591,-.004935,
.028284,-.009999,
.026118,-.014758,
.02584,-.01524,
.03092,-.02032,
.033979,-.014642,
.036005,-.008519,
.036938,-.002138,
.036748,.004309,
.035441,.010625,
.033058,.016618,
.03092,.02032,
.02584,.01524,
180.*
4,1,16,.01524,-.02584,
.010521,-.028094,
.005483,-.029494,
.000278,-.029998,
-.004935,-.029591,
-.009999,-.028284,
-.014758,-.026118,
-.01524,-.02584,
-.02032,-.03092,
-.014642,-.033979,
-.008519,-.036005,
-.002138,-.036938,
.004309,-.036748,
.010625,-.035441,
.016618,-.033058,
.02032,-.03092,
.01524,-.02584,
180.*
4,1,16,-.02584,-.01524,
-.028094,-.010521,
-.029494,-.005483,
-.029998,-.000278,
-.029591,.004935,
-.028284,.009999,
-.026118,.014758,
-.02584,.01524,
-.03092,.02032,
-.033979,.014642,
-.036005,.008519,
-.036938,.002138,
-.036748,-.004309,
-.035441,-.010625,
-.033058,-.016618,
-.03092,-.02032,
-.02584,-.01524,
180.*
4,1,16,-.01524,.02584,
-.010521,.028094,
-.005483,.029494,
-.000278,.029998,
.004935,.029591,
.009999,.028284,
.014758,.026118,
.01524,.02584,
.02032,.03092,
.014642,.033979,
.008519,.036005,
.002138,.036938,
-.004309,.036748,
-.010625,.035441,
-.016618,.033058,
-.02032,.03092,
-.01524,.02584,
180.*
%
%ADD21MACRO21*%
%AMMACRO62*
4,1,15,.02438,.01377,
.026401,.009327,
.027619,.004601,
.027999,-.000265,
.027527,-.005123,
.02622,-.009825,
.02438,-.01377,
.02948,-.01887,
.032309,-.013464,
.034156,-.007649,
.034965,-.001602,
.034712,.004494,
.033405,.010454,
.031082,.016095,
.02948,.01887,
.02438,.01377,
270.*
4,1,15,.01377,-.02438,
.009327,-.026401,
.004601,-.027619,
-.000265,-.027999,
-.005123,-.027527,
-.009825,-.02622,
-.01377,-.02438,
-.01887,-.02948,
-.013464,-.032309,
-.007649,-.034156,
-.001602,-.034965,
.004494,-.034712,
.010454,-.033405,
.016095,-.031082,
.01887,-.02948,
.01377,-.02438,
270.*
4,1,15,-.02438,-.01377,
-.026401,-.009327,
-.027619,-.004601,
-.027999,.000265,
-.027527,.005123,
-.02622,.009825,
-.02438,.01377,
-.02948,.01887,
-.032309,.013464,
-.034156,.007649,
-.034965,.001602,
-.034712,-.004494,
-.033405,-.010454,
-.031082,-.016095,
-.02948,-.01887,
-.02438,-.01377,
270.*
4,1,15,-.01377,.02438,
-.009327,.026401,
-.004601,.027619,
.000265,.027999,
.005123,.027527,
.009825,.02622,
.01377,.02438,
.01887,.02948,
.013464,.032309,
.007649,.034156,
.001602,.034965,
-.004494,.034712,
-.010454,.033405,
-.016095,.031082,
-.01887,.02948,
-.01377,.02438,
270.*
%
%ADD62MACRO62*%
%AMMACRO41*
4,1,15,.02438,.01377,
.026401,.009327,
.027619,.004601,
.027999,-.000265,
.027527,-.005123,
.02622,-.009825,
.02438,-.01377,
.02948,-.01887,
.032309,-.013464,
.034156,-.007649,
.034965,-.001602,
.034712,.004494,
.033405,.010454,
.031082,.016095,
.02948,.01887,
.02438,.01377,
180.*
4,1,15,.01377,-.02438,
.009327,-.026401,
.004601,-.027619,
-.000265,-.027999,
-.005123,-.027527,
-.009825,-.02622,
-.01377,-.02438,
-.01887,-.02948,
-.013464,-.032309,
-.007649,-.034156,
-.001602,-.034965,
.004494,-.034712,
.010454,-.033405,
.016095,-.031082,
.01887,-.02948,
.01377,-.02438,
180.*
4,1,15,-.02438,-.01377,
-.026401,-.009327,
-.027619,-.004601,
-.027999,.000265,
-.027527,.005123,
-.02622,.009825,
-.02438,.01377,
-.02948,.01887,
-.032309,.013464,
-.034156,.007649,
-.034965,.001602,
-.034712,-.004494,
-.033405,-.010454,
-.031082,-.016095,
-.02948,-.01887,
-.02438,-.01377,
180.*
4,1,15,-.01377,.02438,
-.009327,.026401,
-.004601,.027619,
.000265,.027999,
.005123,.027527,
.009825,.02622,
.01377,.02438,
.01887,.02948,
.013464,.032309,
.007649,.034156,
.001602,.034965,
-.004494,.034712,
-.010454,.033405,
-.016095,.031082,
-.01887,.02948,
-.01377,.02438,
180.*
%
%ADD41MACRO41*%
%AMMACRO26*
4,1,20,-.039,.0245,
-.038408,.031272,
-.036648,.037838,
-.033775,.043999,
-.029876,.049567,
-.02507,.054374,
-.019501,.058273,
-.01334,.061146,
-.0075,.06277,
-.0075,.05561,
-.012788,.053835,
-.017688,.051168,
-.02205,.047691,
-.025742,.04351,
-.028652,.038751,
-.030691,.033558,
-.031798,.028091,
-.032,.0245,
-.032,.0075,
-.039,.0075,
-.039,.0245,
90.*
4,1,20,-.039,-.0075,
-.032,-.0075,
-.032,-.0245,
-.031514,-.030057,
-.03007,-.035445,
-.027713,-.040501,
-.024513,-.04507,
-.020569,-.049015,
-.015999,-.052214,
-.010944,-.054572,
-.0075,-.05561,
-.0075,-.06277,
-.014032,-.060887,
-.020137,-.057898,
-.025631,-.053894,
-.030345,-.048997,
-.034138,-.043356,
-.036894,-.037142,
-.038529,-.030544,
-.039,-.0245,
-.039,-.0075,
90.*
4,1,20,.0075,.06277,
.014032,.060887,
.020137,.057898,
.025631,.053894,
.030345,.048997,
.034138,.043356,
.036894,.037142,
.038529,.030544,
.039,.0245,
.039,.0075,
.032,.0075,
.032,.0245,
.031514,.030057,
.03007,.035445,
.027713,.040501,
.024513,.04507,
.020569,.049015,
.015999,.052214,
.010944,.054572,
.0075,.05561,
.0075,.06277,
90.*
4,1,20,.0075,-.05561,
.012788,-.053835,
.017688,-.051168,
.02205,-.047691,
.025742,-.04351,
.028652,-.038751,
.030691,-.033558,
.031798,-.028091,
.032,-.0245,
.032,-.0075,
.039,-.0075,
.039,-.0245,
.038408,-.031272,
.036648,-.037838,
.033775,-.043999,
.029876,-.049567,
.02507,-.054374,
.019501,-.058273,
.01334,-.061146,
.0075,-.06277,
.0075,-.05561,
90.*
%
%ADD26MACRO26*%
%AMMACRO70*
4,1,15,.02475,.01414,
.026829,.009627,
.028094,.004822,
.028504,-.000129,
.028049,-.005077,
.026741,-.009871,
.02475,-.01414,
.02984,-.01923,
.032726,-.013756,
.034617,-.007864,
.035457,-.001734,
.03522,.00445,
.033912,.010498,
.031574,.016227,
.02984,.01923,
.02475,.01414,
270.*
4,1,15,.01414,-.02475,
.009627,-.026829,
.004822,-.028094,
-.000129,-.028504,
-.005077,-.028049,
-.009871,-.026741,
-.01414,-.02475,
-.01923,-.02984,
-.013756,-.032726,
-.007864,-.034617,
-.001734,-.035457,
.00445,-.03522,
.010498,-.033912,
.016227,-.031574,
.01923,-.02984,
.01414,-.02475,
270.*
4,1,15,-.02475,-.01414,
-.026829,-.009627,
-.028094,-.004822,
-.028504,.000129,
-.028049,.005077,
-.026741,.009871,
-.02475,.01414,
-.02984,.01923,
-.032726,.013756,
-.034617,.007864,
-.035457,.001734,
-.03522,-.00445,
-.033912,-.010498,
-.031574,-.016227,
-.02984,-.01923,
-.02475,-.01414,
270.*
4,1,15,-.01414,.02475,
-.009627,.026829,
-.004822,.028094,
.000129,.028504,
.005077,.028049,
.009871,.026741,
.01414,.02475,
.01923,.02984,
.013756,.032726,
.007864,.034617,
.001734,.035457,
-.00445,.03522,
-.010498,.033912,
-.016227,.031574,
-.01923,.02984,
-.01414,.02475,
270.*
%
%ADD70MACRO70*%
%AMMACRO69*
4,1,15,.02142,.01082,
.022973,.006936,
.023829,.002841,
.02396,-.00134,
.023364,-.00548,
.022057,-.009454,
.02142,-.01082,
.02657,-.01597,
.02894,-.011114,
.03043,-.005919,
.030995,-.000545,
.030619,.004845,
.029313,.010088,
.027115,.015025,
.02657,.01597,
.02142,.01082,
180.*
4,1,15,.01082,-.02142,
.006936,-.022973,
.002841,-.023829,
-.00134,-.02396,
-.00548,-.023364,
-.009454,-.022057,
-.01082,-.02142,
-.01597,-.02657,
-.011114,-.02894,
-.005919,-.03043,
-.000545,-.030995,
.004845,-.030619,
.010088,-.029313,
.015025,-.027115,
.01597,-.02657,
.01082,-.02142,
180.*
4,1,15,-.02142,-.01082,
-.022973,-.006936,
-.023829,-.002841,
-.02396,.00134,
-.023364,.00548,
-.022057,.009454,
-.02142,.01082,
-.02657,.01597,
-.02894,.011114,
-.03043,.005919,
-.030995,.000545,
-.030619,-.004845,
-.029313,-.010088,
-.027115,-.015025,
-.02657,-.01597,
-.02142,-.01082,
180.*
4,1,15,-.01082,.02142,
-.006936,.022973,
-.002841,.023829,
.00134,.02396,
.00548,.023364,
.009454,.022057,
.01082,.02142,
.01597,.02657,
.011114,.02894,
.005919,.03043,
.000545,.030995,
-.004845,.030619,
-.010088,.029313,
-.015025,.027115,
-.01597,.02657,
-.01082,.02142,
180.*
%
%ADD69MACRO69*%
%AMMACRO68*
4,1,15,.02475,.01414,
.026829,.009627,
.028094,.004822,
.028504,-.000129,
.028049,-.005077,
.026741,-.009871,
.02475,-.01414,
.02984,-.01923,
.032726,-.013756,
.034617,-.007864,
.035457,-.001734,
.03522,.00445,
.033912,.010498,
.031574,.016227,
.02984,.01923,
.02475,.01414,
180.*
4,1,15,.01414,-.02475,
.009627,-.026829,
.004822,-.028094,
-.000129,-.028504,
-.005077,-.028049,
-.009871,-.026741,
-.01414,-.02475,
-.01923,-.02984,
-.013756,-.032726,
-.007864,-.034617,
-.001734,-.035457,
.00445,-.03522,
.010498,-.033912,
.016227,-.031574,
.01923,-.02984,
.01414,-.02475,
180.*
4,1,15,-.02475,-.01414,
-.026829,-.009627,
-.028094,-.004822,
-.028504,.000129,
-.028049,.005077,
-.026741,.009871,
-.02475,.01414,
-.02984,.01923,
-.032726,.013756,
-.034617,.007864,
-.035457,.001734,
-.03522,-.00445,
-.033912,-.010498,
-.031574,-.016227,
-.02984,-.01923,
-.02475,-.01414,
180.*
4,1,15,-.01414,.02475,
-.009627,.026829,
-.004822,.028094,
.000129,.028504,
.005077,.028049,
.009871,.026741,
.01414,.02475,
.01923,.02984,
.013756,.032726,
.007864,.034617,
.001734,.035457,
-.00445,.03522,
-.010498,.033912,
-.016227,.031574,
-.01923,.02984,
-.01414,.02475,
180.*
%
%ADD68MACRO68*%
%AMMACRO56*
4,1,18,.07103,.05689,
.07983,.043691,
.086204,.029165,
.089959,.013753,
.09098,-.002077,
.089237,-.017844,
.084783,-.033069,
.077753,-.047289,
.07103,-.05689,
.07601,-.06186,
.085597,-.047721,
.092583,-.032132,
.096757,-.015567,
.09799,.001471,
.096246,.018464,
.091577,.034897,
.084126,.050269,
.07601,.06186,
.07103,.05689,
270.*
4,1,18,.05689,-.07103,
.043691,-.07983,
.029165,-.086204,
.013753,-.089959,
-.002077,-.09098,
-.017844,-.089237,
-.033069,-.084783,
-.047289,-.077753,
-.05689,-.07103,
-.06186,-.07601,
-.047721,-.085597,
-.032132,-.092583,
-.015567,-.096757,
.001471,-.09799,
.018464,-.096246,
.034897,-.091577,
.050269,-.084126,
.06186,-.07601,
.05689,-.07103,
270.*
4,1,18,-.07103,-.05689,
-.07983,-.043691,
-.086204,-.029165,
-.089959,-.013753,
-.09098,.002077,
-.089237,.017844,
-.084783,.033069,
-.077753,.047289,
-.07103,.05689,
-.07601,.06186,
-.085597,.047721,
-.092583,.032132,
-.096757,.015567,
-.09799,-.001471,
-.096246,-.018464,
-.091577,-.034897,
-.084126,-.050269,
-.07601,-.06186,
-.07103,-.05689,
270.*
4,1,18,-.05689,.07103,
-.043691,.07983,
-.029165,.086204,
-.013753,.089959,
.002077,.09098,
.017844,.089237,
.033069,.084783,
.047289,.077753,
.05689,.07103,
.06186,.07601,
.047721,.085597,
.032132,.092583,
.015567,.096757,
-.001471,.09799,
-.018464,.096246,
-.034897,.091577,
-.050269,.084126,
-.06186,.07601,
-.05689,.07103,
270.*
%
%ADD56MACRO56*%
%AMMACRO48*
4,1,16,.02657,.01597,
.02894,.011114,
.03043,.005919,
.030995,.000545,
.030619,-.004845,
.029313,-.010088,
.027115,-.015025,
.02657,-.01597,
.03164,-.02104,
.034813,-.015226,
.036928,-.00895,
.037921,-.002401,
.037762,.00422,
.036455,.010713,
.034041,.016881,
.03164,.02104,
.02657,.01597,
180.*
4,1,16,.01597,-.02657,
.011114,-.02894,
.005919,-.03043,
.000545,-.030995,
-.004845,-.030619,
-.010088,-.029313,
-.015025,-.027115,
-.01597,-.02657,
-.02104,-.03164,
-.015226,-.034813,
-.00895,-.036928,
-.002401,-.037921,
.00422,-.037762,
.010713,-.036455,
.016881,-.034041,
.02104,-.03164,
.01597,-.02657,
180.*
4,1,16,-.02657,-.01597,
-.02894,-.011114,
-.03043,-.005919,
-.030995,-.000545,
-.030619,.004845,
-.029313,.010088,
-.027115,.015025,
-.02657,.01597,
-.03164,.02104,
-.034813,.015226,
-.036928,.00895,
-.037921,.002401,
-.037762,-.00422,
-.036455,-.010713,
-.034041,-.016881,
-.03164,-.02104,
-.02657,-.01597,
180.*
4,1,16,-.01597,.02657,
-.011114,.02894,
-.005919,.03043,
-.000545,.030995,
.004845,.030619,
.010088,.029313,
.015025,.027115,
.01597,.02657,
.02104,.03164,
.015226,.034813,
.00895,.036928,
.002401,.037921,
-.00422,.037762,
-.010713,.036455,
-.016881,.034041,
-.02104,.03164,
-.01597,.02657,
180.*
%
%ADD48MACRO48*%
%AMMACRO57*
4,1,15,.04124,.02356,
.044705,.016041,
.046811,.008034,
.047495,-.000216,
.046736,-.008461,
.044557,-.016448,
.04124,-.02356,
.04635,-.02867,
.050624,-.020186,
.05336,-.011088,
.054475,-.001654,
.053935,.007831,
.051756,.017077,
.048004,.025805,
.04635,.02867,
.04124,.02356,
0.0*
4,1,15,.02356,-.04124,
.016041,-.044705,
.008034,-.046811,
-.000216,-.047495,
-.008461,-.046736,
-.016448,-.044557,
-.02356,-.04124,
-.02867,-.04635,
-.020186,-.050624,
-.011088,-.05336,
-.001654,-.054475,
.007831,-.053935,
.017077,-.051756,
.025805,-.048004,
.02867,-.04635,
.02356,-.04124,
0.0*
4,1,15,-.04124,-.02356,
-.044705,-.016041,
-.046811,-.008034,
-.047495,.000216,
-.046736,.008461,
-.044557,.016448,
-.04124,.02356,
-.04635,.02867,
-.050624,.020186,
-.05336,.011088,
-.054475,.001654,
-.053935,-.007831,
-.051756,-.017077,
-.048004,-.025805,
-.04635,-.02867,
-.04124,-.02356,
0.0*
4,1,15,-.02356,.04124,
-.016041,.044705,
-.008034,.046811,
.000216,.047495,
.008461,.046736,
.016448,.044557,
.02356,.04124,
.02867,.04635,
.020186,.050624,
.011088,.05336,
.001654,.054475,
-.007831,.053935,
-.017077,.051756,
-.025805,.048004,
-.02867,.04635,
-.02356,.04124,
0.0*
%
%ADD57MACRO57*%
%AMMACRO77*
4,1,15,.03682,.01914,
.039584,.012455,
.041146,.005393,
.041457,-.001834,
.040509,-.009005,
.03833,-.015903,
.03682,-.01914,
.04197,-.0243,
.045552,-.016643,
.04775,-.00848,
.048497,-.000059,
.047771,.008363,
.045593,.016531,
.042029,.024197,
.04197,.0243,
.03682,.01914,
180.*
4,1,15,.01914,-.03682,
.012455,-.039584,
.005393,-.041146,
-.001834,-.041457,
-.009005,-.040509,
-.015903,-.03833,
-.01914,-.03682,
-.0243,-.04197,
-.016643,-.045552,
-.00848,-.04775,
-.000059,-.048497,
.008363,-.047771,
.016531,-.045593,
.024197,-.042029,
.0243,-.04197,
.01914,-.03682,
180.*
4,1,15,-.03682,-.01914,
-.039584,-.012455,
-.041146,-.005393,
-.041457,.001834,
-.040509,.009005,
-.03833,.015903,
-.03682,.01914,
-.04197,.0243,
-.045552,.016643,
-.04775,.00848,
-.048497,.000059,
-.047771,-.008363,
-.045593,-.016531,
-.042029,-.024197,
-.04197,-.0243,
-.03682,-.01914,
180.*
4,1,15,-.01914,.03682,
-.012455,.039584,
-.005393,.041146,
.001834,.041457,
.009005,.040509,
.015903,.03833,
.01914,.03682,
.0243,.04197,
.016643,.045552,
.00848,.04775,
.000059,.048497,
-.008363,.047771,
-.016531,.045593,
-.024197,.042029,
-.0243,.04197,
-.01914,.03682,
180.*
%
%ADD77MACRO77*%
%AMMACRO75*
4,1,15,-.03682,.01914,
-.039584,.012455,
-.041146,.005393,
-.041457,-.001834,
-.040509,-.009005,
-.03833,-.015903,
-.03682,-.01914,
-.04197,-.0243,
-.045552,-.016643,
-.04775,-.00848,
-.048497,-.000059,
-.047771,.008363,
-.045593,.016531,
-.042029,.024197,
-.04197,.0243,
-.03682,.01914,
180.*
4,1,15,-.01914,-.03682,
-.012455,-.039584,
-.005393,-.041146,
.001834,-.041457,
.009005,-.040509,
.015903,-.03833,
.01914,-.03682,
.0243,-.04197,
.016643,-.045552,
.00848,-.04775,
.000059,-.048497,
-.008363,-.047771,
-.016531,-.045593,
-.024197,-.042029,
-.0243,-.04197,
-.01914,-.03682,
180.*
4,1,15,.03682,-.01914,
.039584,-.012455,
.041146,-.005393,
.041457,.001834,
.040509,.009005,
.03833,.015903,
.03682,.01914,
.04197,.0243,
.045552,.016643,
.04775,.00848,
.048497,.000059,
.047771,-.008363,
.045593,-.016531,
.042029,-.024197,
.04197,-.0243,
.03682,-.01914,
180.*
4,1,15,.01914,.03682,
.012455,.039584,
.005393,.041146,
-.001834,.041457,
-.009005,.040509,
-.015903,.03833,
-.01914,.03682,
-.0243,.04197,
-.016643,.045552,
-.00848,.04775,
-.000059,.048497,
.008363,.047771,
.016531,.045593,
.024197,.042029,
.0243,.04197,
.01914,.03682,
180.*
%
%ADD75MACRO75*%
%ADD82C,.006*%
%ADD87C,.024*%
%ADD108C,.07005*%
%ADD90C,.07006*%
%ADD86C,.07306*%
%ADD88C,.07616*%
%ADD89C,.07608*%
%ADD97C,.07808*%
%ADD95C,.09708*%
%ADD110C,.311*%
%ADD105O,.03004X.07004*%
%ADD100C,.11006*%
%ADD91O,.03004X.06404*%
%ADD109C,.31502*%
%ADD92O,.03006X.06406*%
%ADD111C,.16206*%
%ADD93O,.03004X.06904*%
%ADD101C,.43406*%
%ADD84O,.03404X.06804*%
%ADD83C,.16506*%
%ADD99O,.03006X.06906*%
%ADD96C,.25806*%
%ADD94O,.2363X.2993*%
%ADD85O,.03406X.06806*%
%ADD106C,.19815*%
%ADD104C,.19806*%
%ADD102C,.19807*%
%ADD103C,.19809*%
%ADD107C,.19786*%
%ADD98O,.43374X.77626*%
G75*
%LPD*%
G75*
G36*
G01X-476840Y-884638D02*
X5911000D01*
Y2768362D01*
X-476840D01*
Y-884638D01*
G37*
%LPC*%
G75*
G36*
G01X1007087Y132327D02*
G02X1009020Y130394I0J-1933D01*
G01Y46378D01*
G03X1018898Y36500I9878J0D01*
G01X1510244D01*
G02X1516114Y30630I0J-5870D01*
G01Y-1575D01*
G03X1525992Y-11453I9878J0D01*
G01X1796071D01*
G03X1805949Y-1575I0J9878D01*
G01Y30630D01*
G02X1811819Y36500I5870J0D01*
G01X1849606D01*
G02X1855476Y30630I0J-5870D01*
G01Y-40945D01*
G02X1849606Y-46815I-5870J0D01*
G01X7874D01*
G02X2004Y-40945I0J5870D01*
G01Y30630D01*
G02X7874Y36500I5870J0D01*
G01X35835D01*
G02X41705Y30630I0J-5870D01*
G01Y-1575D01*
G03X51583Y-11453I9878J0D01*
G01X321661D01*
G03X331539Y-1575I0J9878D01*
G01Y30630D01*
G02X337409Y36500I5870J0D01*
G01X480717D01*
G02X486587Y30630I0J-5870D01*
G01Y19212D01*
G03X496465Y9334I9878J0D01*
G01X766543D01*
G03X776421Y19212I0J9878D01*
G01Y30630D01*
G02X782291Y36500I5870J0D01*
G01X879134D01*
G03X889012Y46378I0J9878D01*
G01Y130394D01*
G02X890945Y132327I1933J0D01*
G01X1007087D01*
G37*
G36*
G01X1092027Y1738114D02*
X1824016D01*
G02X1829886Y1732244I0J-5870D01*
G01Y1612316D01*
G03X1832779Y1605332I9878J1D01*
G01X1839978Y1598133D01*
G02X1841697Y1593984I-4150J-4150D01*
G01Y326095D01*
G03X1844590Y319111I9878J1D01*
G01X1853757Y309944D01*
G02X1855476Y305795I-4150J-4150D01*
G01Y54252D01*
G02X1849606Y48382I-5870J0D01*
G01X1803945D01*
G03X1794067Y38504I0J-9878D01*
G01Y2204D01*
G02X1793867Y2004I-200J0D01*
G01X1528196D01*
G02X1527996Y2204I0J200D01*
G01Y38504D01*
G03X1518118Y48382I-9878J0D01*
G01X1026772D01*
G02X1020902Y54252I0J5870D01*
G01Y134331D01*
G03X1011024Y144209I-9878J0D01*
G01X887008D01*
G03X877130Y134331I0J-9878D01*
G01Y54252D01*
G02X871260Y48382I-5870J0D01*
G01X774417D01*
G03X764539Y38504I0J-9878D01*
G01Y22991D01*
G02X764339Y22791I-200J0D01*
G01X498669D01*
G02X498469Y22991I0J200D01*
G01Y38504D01*
G03X488591Y48382I-9878J0D01*
G01X329535D01*
G03X319657Y38504I0J-9878D01*
G01Y2204D01*
G02X319457Y2004I-200J0D01*
G01X53787D01*
G02X53587Y2204I0J200D01*
G01Y38504D01*
G03X43709Y48382I-9878J0D01*
G01X7874D01*
G02X2004Y54252I0J5870D01*
G01Y305795D01*
G02X3723Y309944I5869J-1D01*
G01X6985Y313206D01*
G03X9878Y320190I-6985J6985D01*
G01Y1588078D01*
G02X11597Y1592228I5870J-1D01*
G01X24701Y1605332D01*
G03X27595Y1612317I-6985J6986D01*
G01Y1732244D01*
G02X33465Y1738114I5870J0D01*
G01X765532D01*
G02X765732Y1737914I0J-200D01*
G01Y1736890D01*
G03X769705Y1732917I3973J0D01*
G01X1087854D01*
G03X1091827Y1736890I0J3973D01*
G01Y1737914D01*
G02X1092027Y1738114I200J0D01*
G37*
G36*
G01X1873228Y1820942D02*
X2093700D01*
G02X2099570Y1815072I0J-5870D01*
G01Y1791450D01*
G02X2093700Y1785580I-5870J0D01*
G01X2031574D01*
G03X2021696Y1775702I0J-9878D01*
G01Y1229954D01*
G03X2031574Y1220076I9878J0D01*
G01X2093700D01*
G02X2099570Y1214206I0J-5870D01*
G01Y-40945D01*
G02X2093700Y-46815I-5870J0D01*
G01X1873228D01*
G02X1867358Y-40945I0J5870D01*
G01Y305795D01*
G03X1862159Y318346I-17750J0D01*
G01X1855299Y325206D01*
G02X1853579Y329357I4150J4151D01*
G01Y1593984D01*
G03X1848380Y1606535I-17750J0D01*
G01X1843487Y1611428D01*
G02X1841768Y1615578I4151J4150D01*
G01Y1732244D01*
G02X1847638Y1738114I5870J0D01*
G01X1857480D01*
G03X1867358Y1747992I0J9878D01*
G01Y1815072D01*
G02X1873228Y1820942I5870J0D01*
G37*
%LPD*%
G75*
G36*
G01X81970Y18038D02*
G02Y21044I0J1503D01*
G01X85370D01*
G02Y18038I0J-1503D01*
G01X81970D01*
G37*
G36*
G01X96143D02*
G02Y21044I0J1503D01*
G01X99543D01*
G02Y18038I0J-1503D01*
G01X96143D01*
G37*
G36*
G01X110316D02*
G02Y21044I0J1503D01*
G01X113716D01*
G02Y18038I0J-1503D01*
G01X110316D01*
G37*
G36*
G01X124490D02*
G02Y21044I0J1503D01*
G01X127890D01*
G02Y18038I0J-1503D01*
G01X124490D01*
G37*
G36*
G01X160356D02*
G02Y21044I0J1503D01*
G01X163756D01*
G02Y18038I0J-1503D01*
G01X160356D01*
G37*
G36*
G01X174529D02*
G02Y21044I0J1503D01*
G01X177929D01*
G02Y18038I0J-1503D01*
G01X174529D01*
G37*
G36*
G01X204490D02*
G02Y21044I0J1503D01*
G01X207890D01*
G02Y18038I0J-1503D01*
G01X204490D01*
G37*
G36*
G01X218663D02*
G02Y21044I0J1503D01*
G01X222063D01*
G02Y18038I0J-1503D01*
G01X218663D01*
G37*
G36*
G01X1556379D02*
G02Y21044I0J1503D01*
G01X1559779D01*
G02Y18038I0J-1503D01*
G01X1556379D01*
G37*
G36*
G01X1570552D02*
G02Y21044I0J1503D01*
G01X1573952D01*
G02Y18038I0J-1503D01*
G01X1570552D01*
G37*
G36*
G01X1584725D02*
G02Y21044I0J1503D01*
G01X1588125D01*
G02Y18038I0J-1503D01*
G01X1584725D01*
G37*
G36*
G01X1598899D02*
G02Y21044I0J1503D01*
G01X1602299D01*
G02Y18038I0J-1503D01*
G01X1598899D01*
G37*
G36*
G01X1634765D02*
G02Y21044I0J1503D01*
G01X1638165D01*
G02Y18038I0J-1503D01*
G01X1634765D01*
G37*
G36*
G01X1648938D02*
G02Y21044I0J1503D01*
G01X1652338D01*
G02Y18038I0J-1503D01*
G01X1648938D01*
G37*
G36*
G01X1678899D02*
G02Y21044I0J1503D01*
G01X1682299D01*
G02Y18038I0J-1503D01*
G01X1678899D01*
G37*
G36*
G01X1693072D02*
G02Y21044I0J1503D01*
G01X1696472D01*
G02Y18038I0J-1503D01*
G01X1693072D01*
G37*
G36*
G01X280828Y24432D02*
G02Y27438I0J1503D01*
G01X284228D01*
G02Y24432I0J-1503D01*
G01X280828D01*
G37*
G36*
G01X74865Y24974D02*
G02Y27980I0J1503D01*
G01X78265D01*
G02Y24974I0J-1503D01*
G01X74865D01*
G37*
G36*
G01X89038D02*
G02Y27980I0J1503D01*
G01X92438D01*
G02Y24974I0J-1503D01*
G01X89038D01*
G37*
G36*
G01X103211D02*
G02Y27980I0J1503D01*
G01X106611D01*
G02Y24974I0J-1503D01*
G01X103211D01*
G37*
G36*
G01X117385D02*
G02Y27980I0J1503D01*
G01X120785D01*
G02Y24974I0J-1503D01*
G01X117385D01*
G37*
G36*
G01X153251D02*
G02Y27980I0J1503D01*
G01X156651D01*
G02Y24974I0J-1503D01*
G01X153251D01*
G37*
G36*
G01X167424D02*
G02Y27980I0J1503D01*
G01X170824D01*
G02Y24974I0J-1503D01*
G01X167424D01*
G37*
G36*
G01X197385D02*
G02Y27980I0J1503D01*
G01X200785D01*
G02Y24974I0J-1503D01*
G01X197385D01*
G37*
G36*
G01X211558D02*
G02Y27980I0J1503D01*
G01X214958D01*
G02Y24974I0J-1503D01*
G01X211558D01*
G37*
G36*
G01X225731D02*
G02Y27980I0J1503D01*
G01X229131D01*
G02Y24974I0J-1503D01*
G01X225731D01*
G37*
G36*
G01X1549274D02*
G02Y27980I0J1503D01*
G01X1552674D01*
G02Y24974I0J-1503D01*
G01X1549274D01*
G37*
G36*
G01X1563447D02*
G02Y27980I0J1503D01*
G01X1566847D01*
G02Y24974I0J-1503D01*
G01X1563447D01*
G37*
G36*
G01X1577620D02*
G02Y27980I0J1503D01*
G01X1581020D01*
G02Y24974I0J-1503D01*
G01X1577620D01*
G37*
G36*
G01X1591794D02*
G02Y27980I0J1503D01*
G01X1595194D01*
G02Y24974I0J-1503D01*
G01X1591794D01*
G37*
G36*
G01X1627660D02*
G02Y27980I0J1503D01*
G01X1631060D01*
G02Y24974I0J-1503D01*
G01X1627660D01*
G37*
G36*
G01X1641833D02*
G02Y27980I0J1503D01*
G01X1645233D01*
G02Y24974I0J-1503D01*
G01X1641833D01*
G37*
G36*
G01X1671794D02*
G02Y27980I0J1503D01*
G01X1675194D01*
G02Y24974I0J-1503D01*
G01X1671794D01*
G37*
G36*
G01X1685967D02*
G02Y27980I0J1503D01*
G01X1689367D01*
G02Y24974I0J-1503D01*
G01X1685967D01*
G37*
G36*
G01X1755238D02*
G02Y27980I0J1503D01*
G01X1758638D01*
G02Y24974I0J-1503D01*
G01X1755238D01*
G37*
G36*
G01X1700183Y25002D02*
G02Y28008I0J1503D01*
G01X1703583D01*
G02Y25002I0J-1503D01*
G01X1700183D01*
G37*
G36*
G01X519765Y38826D02*
G02Y41830I0J1502D01*
G01X523165D01*
G02Y38826I0J-1502D01*
G01X519765D01*
G37*
G36*
G01X670613Y40962D02*
G02Y43966I0J1502D01*
G01X674013D01*
G02Y40962I0J-1502D01*
G01X670613D01*
G37*
G36*
G01X512658Y45110D02*
G02Y48116I0J1503D01*
G01X516058D01*
G02Y45110I0J-1503D01*
G01X512658D01*
G37*
G36*
G01X533918Y45564D02*
G02Y48570I0J1503D01*
G01X537318D01*
G02Y45564I0J-1503D01*
G01X533918D01*
G37*
G36*
G01X225727Y49146D02*
G02Y52152I0J1503D01*
G01X229127D01*
G02Y49146I0J-1503D01*
G01X225727D01*
G37*
G36*
G01X280826D02*
G02Y52152I0J1503D01*
G01X284226D01*
G02Y49146I0J-1503D01*
G01X280826D01*
G37*
G36*
G01X1700136D02*
G02Y52152I0J1503D01*
G01X1703536D01*
G02Y49146I0J-1503D01*
G01X1700136D01*
G37*
G36*
G01X1755235D02*
G02Y52152I0J1503D01*
G01X1758635D01*
G02Y49146I0J-1503D01*
G01X1755235D01*
G37*
G36*
G01X262198Y54862D02*
G03X262334I68J188D01*
G02X263516Y55068I1184J-3297D01*
G02X266921Y52387I0J-3503D01*
G03X267021Y52257I195J46D01*
G02X268868Y49171I-1655J-3086D01*
G02X265365Y45668I-3503J0D01*
G02X263864Y46006I0J3503D01*
G03X263672Y45995I-86J-181D01*
G02X261816Y45462I-1857J2970D01*
G02X260634Y45668I2J3503D01*
G03X260498I-68J-188D01*
G02X259316Y45462I-1184J3297D01*
G02X257661Y45878I1J3503D01*
G03X257471I-95J-176D01*
G02X255816Y45462I-1656J3087D01*
G02X254161Y45878I1J3503D01*
G03X253971I-95J-176D01*
G02X252316Y45462I-1656J3087D01*
G02X250661Y45878I1J3503D01*
G03X250471I-95J-176D01*
G02X248816Y45462I-1656J3087D01*
G02X245314Y48965I1J3503D01*
G02X246959Y51935I3504J0D01*
G03X247051Y52075I-106J170D01*
G02X250516Y55068I3465J-509D01*
G02X252171Y54652I-1J-3503D01*
G03X252361I95J176D01*
G02X254016Y55068I1656J-3087D01*
G02X255671Y54652I-1J-3503D01*
G03X255861I95J176D01*
G02X257516Y55068I1656J-3087D01*
G02X259171Y54652I-1J-3503D01*
G03X259361I95J176D01*
G02X261016Y55068I1656J-3087D01*
G02X262198Y54862I-2J-3503D01*
G37*
G36*
G01X757202Y54804D02*
G02X758621Y55104I1418J-3202D01*
G02X762124Y51602I1J-3502D01*
G02X760383Y48575I-3502J0D01*
G01X760382Y48574D01*
G03X760284Y48421I101J-173D01*
G01X760252Y48099D01*
G03X760319Y47929I199J-20D01*
G02X754928Y47567I-2516J-2851D01*
G01X754962Y47606D01*
X754984Y47707D01*
X754852Y48131D01*
X754778Y48202D01*
X754728Y48215D01*
G02X752118Y51602I893J3387D01*
G02X755621Y55104I3503J-1D01*
G01X755623D01*
G02X757040Y54804I-1J-3502D01*
G03X757202I81J183D01*
G37*
G36*
G01X1728848Y55655D02*
X1728849Y55656D01*
G02X1729836Y56026I987J-1131D01*
G02X1731332Y54658I0J-1502D01*
G03X1731443Y54496I199J18D01*
G02X1733398Y51354I-1547J-3142D01*
G02X1733316Y50602I-3503J1D01*
G03X1733334Y50465I195J-44D01*
G02X1733744Y48822I-3093J-1644D01*
G02X1733586Y47785I-3503J3D01*
G01X1733567Y47725D01*
X1733604Y47607D01*
X1733950Y47338D01*
G03X1734177Y47325I123J158D01*
G02X1736004Y47840I1828J-2987D01*
G01X1736006D01*
G02X1739508Y44338I0J-3502D01*
G01Y44335D01*
G02X1739303Y43155I-3502J1D01*
G03Y43021I188J-67D01*
G02X1739508Y41841I-3297J-1181D01*
G01Y41838D01*
G02X1732504I-3502J0D01*
G01Y41841D01*
G02X1732709Y43021I3502J-1D01*
G03Y43155I-188J67D01*
G02X1732504Y44335I3297J1181D01*
G01Y44338D01*
G02X1732661Y45375I3503J0D01*
G01X1732680Y45435D01*
X1732643Y45553D01*
X1732297Y45822D01*
G03X1732070Y45835I-123J-158D01*
G02X1730241Y45320I-1828J2987D01*
G02X1728585Y45735I-2J3502D01*
G03X1728397I-94J-176D01*
G02X1726741Y45320I-1654J3087D01*
G02X1725085Y45735I-2J3502D01*
G03X1724897I-94J-176D01*
G02X1723241Y45320I-1654J3087D01*
G02X1719738Y48822I-1J3502D01*
G02X1721117Y51607I3503J0D01*
G03X1721195Y51749I-121J159D01*
G02X1724685Y54956I3490J-295D01*
G02X1725575Y54842I4J-3502D01*
G03X1725722Y54860I51J193D01*
G01X1725828Y54918D01*
G03X1725920Y55026I-96J175D01*
G02X1727336Y56026I1416J-503D01*
G02X1728323Y55656I0J-1501D01*
G01X1728324D01*
Y55655D01*
G03X1728454Y55607I130J152D01*
G01X1728718D01*
G03X1728848Y55655I0J200D01*
G37*
G36*
G01X1734796Y54421D02*
G02X1734590Y55603I3297J1184D01*
G02X1741596I3503J0D01*
G02X1741390Y54421I-3503J2D01*
G03Y54285I188J-68D01*
G02X1741596Y53103I-3297J-1184D01*
G02X1734590I-3503J0D01*
G02X1734796Y54285I3503J-2D01*
G03Y54421I-188J68D01*
G37*
G36*
G01X1770792Y63032D02*
Y63033D01*
G02X1777796I3502J0D01*
G01Y63032D01*
G02X1777516Y61661I-3502J1D01*
G03Y61505I184J-78D01*
G02X1777796Y60133I-3222J-1372D01*
G01Y60129D01*
G02X1777507Y58738I-3502J2D01*
G03Y58579I183J-79D01*
G02X1777794Y57191I-3216J-1389D01*
G02X1770788I-3503J0D01*
G02X1771078Y58586I3503J-1D01*
G03X1771079Y58745I-183J81D01*
G02X1770792Y60133I3215J1388D01*
G02X1771072Y61505I3502J0D01*
G03Y61661I-184J78D01*
G02X1770792Y63032I3222J1372D01*
G37*
G36*
G01X763221Y68634D02*
G02X766724Y65132I1J-3502D01*
G02X766134Y63188I-3503J2D01*
G03X766107Y63026I167J-111D01*
G02X766224Y62132I-3386J-898D01*
G02X762721Y58630I-3503J1D01*
G01X762718D01*
G02X761538Y58835I1J3502D01*
G03X761404I-67J-188D01*
G02X760221Y58630I-1181J3297D01*
G02X759038Y58835I-2J3502D01*
G03X758904I-67J-188D01*
G02X757721Y58630I-1181J3297D01*
G02X754218Y62132I-1J3502D01*
G02X754424Y63314I3503J-2D01*
G03Y63450I-188J68D01*
G02X754218Y64632I3297J1184D01*
G02X757721Y68134I3503J-1D01*
G01X757724D01*
G02X758904Y67929I-1J-3502D01*
G03X759038I67J188D01*
G02X760221Y68134I1181J-3297D01*
G02X761115Y68018I0J-3502D01*
G03X761277Y68045I51J194D01*
G02X763221Y68634I1944J-2913D01*
G37*
G36*
G01X304943Y68370D02*
G03X305084Y68377I61J190D01*
G02X306468Y68662I1384J-3217D01*
G01X306470D01*
G02Y61658I0J-3502D01*
G01X306466D01*
G02X305379Y61832I3J3502D01*
G03X305238Y61825I-61J-190D01*
G02X303854Y61540I-1384J3217D01*
G01X303852D01*
G02Y68544I0J3502D01*
G01X303856D01*
G02X304943Y68370I-3J-3502D01*
G37*
G36*
G01X61157Y67838D02*
G02Y70842I0J1502D01*
G01X64557D01*
G02Y67838I0J-1502D01*
G01X61157D01*
G37*
G36*
G01X83157D02*
G02Y70842I0J1502D01*
G01X86557D01*
G02Y67838I0J-1502D01*
G01X83157D01*
G37*
G36*
G01X105157D02*
G02Y70842I0J1502D01*
G01X108557D01*
G02Y67838I0J-1502D01*
G01X105157D01*
G37*
G36*
G01X172361D02*
G02Y70842I0J1502D01*
G01X175761D01*
G02Y67838I0J-1502D01*
G01X172361D01*
G37*
G36*
G01X194361D02*
G02Y70842I0J1502D01*
G01X197761D01*
G02Y67838I0J-1502D01*
G01X194361D01*
G37*
G36*
G01X1535566D02*
G02Y70842I0J1502D01*
G01X1538966D01*
G02Y67838I0J-1502D01*
G01X1535566D01*
G37*
G36*
G01X1557566D02*
G02Y70842I0J1502D01*
G01X1560966D01*
G02Y67838I0J-1502D01*
G01X1557566D01*
G37*
G36*
G01X1579566D02*
G02Y70842I0J1502D01*
G01X1582966D01*
G02Y67838I0J-1502D01*
G01X1579566D01*
G37*
G36*
G01X1646770D02*
G02Y70842I0J1502D01*
G01X1650170D01*
G02Y67838I0J-1502D01*
G01X1646770D01*
G37*
G36*
G01X1668770D02*
G02Y70842I0J1502D01*
G01X1672170D01*
G02Y67838I0J-1502D01*
G01X1668770D01*
G37*
G36*
G01X127153Y67840D02*
G02Y70846I0J1503D01*
G01X130553D01*
G02Y67840I0J-1503D01*
G01X127153D01*
G37*
G36*
G01X149153D02*
G02Y70846I0J1503D01*
G01X152553D01*
G02Y67840I0J-1503D01*
G01X149153D01*
G37*
G36*
G01X216491D02*
G02Y70846I0J1503D01*
G01X219891D01*
G02Y67840I0J-1503D01*
G01X216491D01*
G37*
G36*
G01X1601562D02*
G02Y70846I0J1503D01*
G01X1604962D01*
G02Y67840I0J-1503D01*
G01X1601562D01*
G37*
G36*
G01X1623562D02*
G02Y70846I0J1503D01*
G01X1626962D01*
G02Y67840I0J-1503D01*
G01X1623562D01*
G37*
G36*
G01X1690900D02*
G02Y70846I0J1503D01*
G01X1694300D01*
G02Y67840I0J-1503D01*
G01X1690900D01*
G37*
G36*
G01X1221518Y67427D02*
G02X1225540Y71450I4023J0D01*
G01X1225541D01*
G02Y63504I0J-3973D01*
G01X1225441D01*
G02X1221518Y67427I0J3923D01*
G37*
G36*
G01X519743Y69934D02*
G02Y72938I0J1502D01*
G01X523143D01*
G02Y69934I0J-1502D01*
G01X519743D01*
G37*
G36*
G01X541003D02*
G02Y72938I0J1502D01*
G01X544403D01*
G02Y69934I0J-1502D01*
G01X541003D01*
G37*
G36*
G01X555176D02*
G02Y72938I0J1502D01*
G01X558576D01*
G02Y69934I0J-1502D01*
G01X555176D01*
G37*
G36*
G01X311430Y70434D02*
G02X311150Y71806I3223J1372D01*
G02X318156I3503J0D01*
G02X317876Y70434I-3503J0D01*
G03Y70278I184J-78D01*
G02X318156Y68906I-3223J-1372D01*
G02X311150I-3503J0D01*
G02X311430Y70278I3503J0D01*
G03Y70434I-184J78D01*
G37*
G36*
G01X1776242Y72972D02*
Y72973D01*
G02X1783246I3502J0D01*
G01Y72972D01*
G02X1782966Y71601I-3502J1D01*
G03Y71445I184J-78D01*
G02X1783246Y70074I-3222J-1372D01*
G01Y70073D01*
G02X1776242I-3502J0D01*
G01Y70074D01*
G02X1776522Y71445I3502J-1D01*
G03Y71601I-184J78D01*
G02X1776242Y72972I3222J1372D01*
G37*
G36*
G01X94157Y73838D02*
G02Y76842I0J1502D01*
G01X97557D01*
G02Y73838I0J-1502D01*
G01X94157D01*
G37*
G36*
G01X116157D02*
G02Y76842I0J1502D01*
G01X119557D01*
G02Y73838I0J-1502D01*
G01X116157D01*
G37*
G36*
G01X138157D02*
G02Y76842I0J1502D01*
G01X141557D01*
G02Y73838I0J-1502D01*
G01X138157D01*
G37*
G36*
G01X161361D02*
G02Y76842I0J1502D01*
G01X164761D01*
G02Y73838I0J-1502D01*
G01X161361D01*
G37*
G36*
G01X205495D02*
G02Y76842I0J1502D01*
G01X208895D01*
G02Y73838I0J-1502D01*
G01X205495D01*
G37*
G36*
G01X227495D02*
G02Y76842I0J1502D01*
G01X230895D01*
G02Y73838I0J-1502D01*
G01X227495D01*
G37*
G36*
G01X1568566D02*
G02Y76842I0J1502D01*
G01X1571966D01*
G02Y73838I0J-1502D01*
G01X1568566D01*
G37*
G36*
G01X1590566D02*
G02Y76842I0J1502D01*
G01X1593966D01*
G02Y73838I0J-1502D01*
G01X1590566D01*
G37*
G36*
G01X1612566D02*
G02Y76842I0J1502D01*
G01X1615966D01*
G02Y73838I0J-1502D01*
G01X1612566D01*
G37*
G36*
G01X1635770D02*
G02Y76842I0J1502D01*
G01X1639170D01*
G02Y73838I0J-1502D01*
G01X1635770D01*
G37*
G36*
G01X1679904D02*
G02Y76842I0J1502D01*
G01X1683304D01*
G02Y73838I0J-1502D01*
G01X1679904D01*
G37*
G36*
G01X1701904D02*
G02Y76842I0J1502D01*
G01X1705304D01*
G02Y73838I0J-1502D01*
G01X1701904D01*
G37*
G36*
G01X72153Y73840D02*
G02Y76846I0J1503D01*
G01X75553D01*
G02Y73840I0J-1503D01*
G01X72153D01*
G37*
G36*
G01X183357D02*
G02Y76846I0J1503D01*
G01X186757D01*
G02Y73840I0J-1503D01*
G01X183357D01*
G37*
G36*
G01X1546562D02*
G02Y76846I0J1503D01*
G01X1549962D01*
G02Y73840I0J-1503D01*
G01X1546562D01*
G37*
G36*
G01X1657766D02*
G02Y76846I0J1503D01*
G01X1661166D01*
G02Y73840I0J-1503D01*
G01X1657766D01*
G37*
G36*
G01X547821Y77870D02*
G02Y80874I0J1502D01*
G01X551721D01*
G02Y77870I0J-1502D01*
G01X547821D01*
G37*
G36*
G01X259596Y78847D02*
G02X259390Y80029I3297J1184D01*
G02X266396I3503J0D01*
G02X266190Y78847I-3503J2D01*
G03Y78711I188J-68D01*
G02X266396Y77529I-3297J-1184D01*
G02X265926Y75777I-3503J1D01*
G03X265941Y75554I173J-100D01*
G02X266353Y74883I-2760J-2157D01*
G01Y74881D01*
G03X266515Y74768I181J86D01*
G01X266858Y74735D01*
G03X267037Y74814I19J199D01*
G01X267038Y74815D01*
G02X269860Y76244I2823J-2074D01*
G02Y69238I0J-3503D01*
G02X266689Y71254I0J3503D01*
G01Y71256D01*
G03X266527Y71369I-181J-86D01*
G01X266184Y71402D01*
G03X266005Y71323I-19J-199D01*
G01X266004Y71322D01*
G02X263182Y69894I-2822J2074D01*
G02X259680Y73396I0J3502D01*
G01Y73397D01*
G02X260149Y75148I3502J0D01*
G03X260134Y75371I-173J100D01*
G02X259390Y77529I2758J2158D01*
G02X259596Y78711I3503J-2D01*
G03Y78847I-188J68D01*
G37*
G36*
G01X1454786Y76366D02*
G02Y84312I0J3973D01*
G01X1454886D01*
G02X1458808Y80389I-1J-3923D01*
G02X1454786Y76366I-4022J-1D01*
G37*
G36*
G01X1738824Y84928D02*
G03X1739040Y84981I68J188D01*
G02X1741621Y86116I2581J-2367D01*
G02X1745124Y82613I0J-3503D01*
G02X1744918Y81431I-3503J2D01*
G03Y81295I188J-68D01*
G02X1745124Y80113I-3297J-1184D01*
G02X1744708Y78458I-3503J1D01*
G03Y78268I176J-95D01*
G02X1745124Y76613I-3087J-1656D01*
G02X1744918Y75431I-3503J2D01*
G03Y75295I188J-68D01*
G02X1745124Y74113I-3297J-1184D01*
G02X1741621Y70610I-3503J0D01*
G02X1740414Y70825I1J3503D01*
G03X1740198Y70772I-68J-188D01*
G02X1737617Y69638I-2580J2368D01*
G02X1734114Y73140I-1J3502D01*
G02X1734320Y74322I3503J-2D01*
G03Y74458I-188J68D01*
G02X1734114Y75640I3297J1184D01*
G02X1734530Y77295I3503J-1D01*
G03Y77485I-176J95D01*
G02X1734114Y79140I3087J1656D01*
G02X1734320Y80322I3503J-2D01*
G03Y80458I-188J68D01*
G02X1734114Y81640I3297J1184D01*
G02X1737617Y85142I3503J-1D01*
G01X1737620D01*
G02X1738824Y84928I-1J-3502D01*
G37*
G36*
G01X695374Y87282D02*
G03X695481Y87389I-77J184D01*
G02X698711Y89538I3230J-1353D01*
G02X702214Y86035I0J-3503D01*
G02X700174Y82852I-3503J0D01*
G03X700067Y82610I84J-182D01*
G02X700230Y81556I-3339J-1056D01*
G01Y81552D01*
G02X699726Y79743I-3501J1D01*
G03X699707Y79578I171J-103D01*
G02X699874Y78512I-3336J-1069D01*
G02X692868I-3503J0D01*
G02X693373Y80321I3502J-3D01*
G03X693392Y80486I-171J103D01*
G02X693226Y81552I3336J1065D01*
G02X693431Y82735I3502J2D01*
G03Y82869I-188J67D01*
G02X693226Y84049I3297J1181D01*
G01Y84052D01*
G02X695374Y87282I3503J0D01*
G37*
G36*
G01X452102Y87208D02*
G02Y90214I0J1503D01*
G01X455502D01*
G02Y87208I0J-1503D01*
G01X452102D01*
G37*
G36*
G01X537148Y89555D02*
G02X539273Y91680I1062J1062D01*
G01X541678Y89276D01*
G02X542118Y88214I-1063J-1063D01*
G01Y88213D01*
G02X540615Y86710I-1503J0D01*
G01X540614D01*
G02X539552Y87150I1J1503D01*
G01X537148Y89555D01*
G37*
G36*
G01X445014Y93182D02*
G02Y96186I0J1502D01*
G01X448414D01*
G02Y93182I0J-1502D01*
G01X445014D01*
G37*
G36*
G01X746532Y92887D02*
Y92888D01*
G02X753536I3502J0D01*
G01Y92887D01*
G02X753256Y91516I-3502J1D01*
G03Y91360I184J-78D01*
G02X753536Y89989I-3222J-1372D01*
G01Y89988D01*
G02X746532I-3502J0D01*
G01Y89989D01*
G02X746812Y91360I3502J-1D01*
G03Y91516I-184J78D01*
G02X746532Y92887I3222J1372D01*
G37*
G36*
G01X459056Y93598D02*
G02Y96604I0J1503D01*
G01X462456D01*
G02Y93598I0J-1503D01*
G01X459056D01*
G37*
G36*
G01X514240Y95644D02*
G02Y98648I0J1502D01*
G01X517640D01*
G02Y95644I0J-1502D01*
G01X514240D01*
G37*
G36*
G01X266571Y103752D02*
G03X266761I95J176D01*
G02X268416Y104168I1656J-3087D01*
G02X271908Y100934I0J-3502D01*
G03X271989Y100788I200J15D01*
G02X272651Y100153I-2073J-2823D01*
G03X272851Y100083I156J125D01*
G02X273616Y100168I767J-3418D01*
G02Y93162I0J-3503D01*
G02X270881Y94477I0J3502D01*
G03X270681Y94547I-156J-125D01*
G02X269916Y94462I-767J3418D01*
G02X268261Y94878I1J3503D01*
G03X268071I-95J-176D01*
G02X266416Y94462I-1656J3087D01*
G02X264761Y94878I1J3503D01*
G03X264571I-95J-176D01*
G02X262916Y94462I-1656J3087D01*
G02X259424Y97696I0J3502D01*
G03X259343Y97842I-200J-15D01*
G02X257914Y100665I2073J2823D01*
G02X261416Y104168I3502J1D01*
G02X263071Y103752I-1J-3503D01*
G03X263261I95J176D01*
G02X264916Y104168I1656J-3087D01*
G02X266571Y103752I-1J-3503D01*
G37*
G36*
G01X1741886Y105380D02*
G03X1742076I95J176D01*
G02X1743731Y105796I1656J-3087D01*
G02X1747049Y103414I0J-3502D01*
G03X1747141Y103303I190J64D01*
G02X1748844Y101047I-1706J-3059D01*
G03X1749019Y100894I195J46D01*
G02X1752188Y97408I-333J-3486D01*
G02X1748686Y93906I-3502J0D01*
G02X1745277Y96605I0J3502D01*
G03X1745102Y96758I-195J-46D01*
G02X1743779Y97157I330J3487D01*
G03X1743591I-94J-176D01*
G02X1741935Y96742I-1654J3087D01*
G02X1740279Y97157I-2J3502D01*
G03X1740091I-94J-176D01*
G02X1738437Y96742I-1654J3087D01*
G01X1738435D01*
G02X1735117Y99123I0J3502D01*
G03X1735025Y99234I-190J-64D01*
G02X1733228Y102293I1705J3059D01*
G02X1736731Y105796I3503J0D01*
G02X1738386Y105380I-1J-3503D01*
G03X1738576I95J176D01*
G02X1740231Y105796I1656J-3087D01*
G02X1741886Y105380I-1J-3503D01*
G37*
G36*
G01X696065Y107949D02*
G02X697721Y108364I1654J-3087D01*
G02X699377Y107949I2J-3502D01*
G03X699565I94J176D01*
G02X701219Y108364I1654J-3087D01*
G01X701221D01*
G02X704713Y105131I0J-3502D01*
G03X704794Y104985I200J15D01*
G02X705722Y103968I-2073J-2823D01*
G03X705938Y103876I171J103D01*
G02X706716Y103964I780J-3414D01*
G01X706721D01*
G02Y96960I0J-3502D01*
G02X703720Y98656I0J3503D01*
G03X703504Y98748I-171J-103D01*
G02X702721Y98660I-780J3414D01*
G02X701065Y99075I-2J3502D01*
G03X700877I-94J-176D01*
G02X699221Y98660I-1654J3087D01*
G02X697565Y99075I-2J3502D01*
G03X697377I-94J-176D01*
G02X695723Y98660I-1654J3087D01*
G01X695721D01*
G02X692229Y101893I0J3502D01*
G03X692148Y102039I-200J-15D01*
G02X690718Y104862I2071J2823D01*
G02X694221Y108364I3503J-1D01*
G01X694223D01*
G02X695877Y107949I0J-3502D01*
G03X696065I94J176D01*
G37*
G36*
G01X552105Y110700D02*
G02Y113706I0J1503D01*
G01X555505D01*
G02Y110700I0J-1503D01*
G01X552105D01*
G37*
G36*
G01X791363Y124244D02*
G03X791499I68J188D01*
G02X792681Y124450I1184J-3297D01*
G02Y117444I0J-3503D01*
G02X792393Y117456I2J3503D01*
G03X792191Y117331I-16J-199D01*
G02X788941Y115134I-3250J1305D01*
G02X787759Y115340I2J3503D01*
G03X787623I-68J-188D01*
G02X786441Y115134I-1184J3297D01*
G02X785259Y115340I2J3503D01*
G03X785123I-68J-188D01*
G02X783941Y115134I-1184J3297D01*
G02X782759Y115340I2J3503D01*
G03X782623I-68J-188D01*
G02X781441Y115134I-1184J3297D01*
G02Y122140I0J3503D01*
G02X781729Y122128I-2J-3503D01*
G03X781931Y122253I16J199D01*
G02X785181Y124450I3250J-1305D01*
G02X786363Y124244I-2J-3503D01*
G03X786499I68J188D01*
G02X787681Y124450I1184J-3297D01*
G02X788863Y124244I-2J-3503D01*
G03X788999I68J188D01*
G02X790181Y124450I1184J-3297D01*
G02X791363Y124244I-2J-3503D01*
G37*
G36*
G01X472895Y128518D02*
G02Y131522I0J1502D01*
G01X476295D01*
G02Y128518I0J-1502D01*
G01X472895D01*
G37*
G36*
G01X47255Y123148D02*
X51557Y127748D01*
G02X69964Y110535I9203J-8607D01*
G01X65662Y105934D01*
G02X47255Y123148I-9203J8607D01*
G37*
G36*
G01X490380Y129940D02*
G02Y132944I0J1502D01*
G01X493780D01*
G02Y129940I0J-1502D01*
G01X490380D01*
G37*
G36*
G01X482380Y140440D02*
G02Y143444I0J1502D01*
G01X485780D01*
G02Y140440I0J-1502D01*
G01X482380D01*
G37*
G36*
G01X779327Y150364D02*
G03X779471Y150499I-47J194D01*
G02X782819Y152974I3348J-1027D01*
G02X786322Y149471I0J-3503D01*
G02X783651Y146068I-3503J0D01*
G03X783507Y145933I47J-194D01*
G02X780159Y143458I-3348J1027D01*
G02X776656Y146961I0J3503D01*
G02X779327Y150364I3503J0D01*
G37*
G36*
G01X975691Y157718D02*
G02Y164722I0J3502D01*
G01X975693D01*
G02X978131Y163733I-1J-3502D01*
G01X978159Y163705D01*
X978231Y163676D01*
X978548Y163675D01*
G03X978686Y163730I0J200D01*
G01X978687Y163731D01*
G02X981112Y164706I2425J-2528D01*
G02Y157702I0J-3502D01*
G01X981110D01*
G02X978672Y158691I1J3502D01*
G01X978644Y158719D01*
X978572Y158748D01*
X978255Y158749D01*
G03X978117Y158694I0J-200D01*
G01X978116Y158693D01*
G02X975691Y157718I-2425J2528D01*
G37*
G36*
G01X959376Y169081D02*
G02X959170Y170263I3297J1184D01*
G02X966176I3503J0D01*
G02X965970Y169081I-3503J2D01*
G03Y168945I188J-68D01*
G02X966176Y167763I-3297J-1184D01*
G02X959170I-3503J0D01*
G02X959376Y168945I3503J-2D01*
G03Y169081I-188J68D01*
G37*
G36*
G01X946854Y179703D02*
G03X946999Y179709I65J189D01*
G02X948401Y180002I1402J-3210D01*
G02X951904Y176499I0J-3503D01*
G02X949342Y173125I-3503J0D01*
G03X949197Y172957I54J-193D01*
G02X945721Y169886I-3476J432D01*
G02X944539Y170092I2J3503D01*
G03X944403I-68J-188D01*
G02X943221Y169886I-1184J3297D01*
G02X942039Y170092I2J3503D01*
G03X941903I-68J-188D01*
G02X940721Y169886I-1184J3297D01*
G02X939510Y170103I3J3503D01*
G03X939372I-69J-188D01*
G02X938161Y169886I-1214J3286D01*
G02X937002Y170084I2J3503D01*
G03X936861Y170081I-67J-189D01*
G02X935551Y169826I-1312J3248D01*
G02X932048Y173329I0J3503D01*
G02X932313Y174663I3503J-2D01*
G03X932315Y174810I-185J76D01*
G02X932088Y176049I3276J1240D01*
G02X935591Y179552I3503J0D01*
G01X935592D01*
G02X936376Y179463I-1J-3503D01*
G03X936515Y179481I45J195D01*
G02X938161Y179892I1646J-3091D01*
G02X939372Y179675I-3J-3503D01*
G03X939510I69J188D01*
G02X940721Y179892I1214J-3286D01*
G02X941903Y179686I-2J-3503D01*
G03X942039I68J188D01*
G02X943221Y179892I1184J-3297D01*
G02X944403Y179686I-2J-3503D01*
G03X944539I68J188D01*
G02X945721Y179892I1184J-3297D01*
G02X946854Y179703I-2J-3503D01*
G37*
G36*
G01X365287Y173422D02*
G02Y197050I0J11814D01*
G01X371587D01*
G02Y173422I0J-11814D01*
G01X365287D01*
G37*
G36*
G01X247177Y172636D02*
G02Y197836I0J12600D01*
G01X253476D01*
G02Y172636I0J-12600D01*
G01X247177D01*
G37*
G36*
G01X987564Y209093D02*
G03X987721Y209152I15J199D01*
G02X990221Y210202I2501J-2453D01*
G02X993724Y206699I0J-3503D01*
G02X993308Y205044I-3503J1D01*
G03Y204854I176J-95D01*
G02X993724Y203199I-3087J-1656D01*
G02X993308Y201544I-3503J1D01*
G03Y201354I176J-95D01*
G02X993724Y199699I-3087J-1656D01*
G02X990221Y196196I-3503J0D01*
G02X989978Y196205I8J3503D01*
G03X989821Y196146I-15J-199D01*
G02X989542Y195890I-2504J2449D01*
G03X989471Y195701I126J-155D01*
G02X989524Y195099I-3450J-607D01*
G02X982518I-3503J0D01*
G02X983800Y197808I3503J0D01*
G03X983871Y197997I-126J155D01*
G02X983818Y198598I3450J607D01*
G01Y198600D01*
G02X983819Y198660I3503J-28D01*
G02X982055Y199171I59J3502D01*
G03X981837Y199165I-104J-170D01*
G02X979849Y198546I-1988J2884D01*
G02X977910Y199132I1J3503D01*
G03X977688I-111J-166D01*
G02X975749Y198546I-1940J2917D01*
G02X972359Y201167I0J3503D01*
G03X972153Y201317I-194J-50D01*
G02X971943Y201310I-222J3496D01*
G02X970051Y201866I2J3503D01*
G03X969835I-108J-169D01*
G02X967943Y201310I-1894J2947D01*
G02X964686Y203525I0J3502D01*
G03X964536Y203648I-186J-74D01*
G02X963305Y205125I271J1477D01*
G02X964807Y206627I1502J0D01*
G01X964833D01*
G03X965004Y206718I3J200D01*
G02X967943Y208316I2939J-1904D01*
G02X969835Y207760I-2J-3503D01*
G03X970051I108J169D01*
G02X971943Y208316I1894J-2947D01*
G02X974028Y207627I-1J-3503D01*
G01X974059Y207604D01*
X974131Y207584D01*
X974478Y207624D01*
X974544Y207658D01*
X974569Y207687D01*
G02X977221Y208902I2652J-2287D01*
G02X980718Y205584I0J-3502D01*
G03X980860Y205403I200J11D01*
G02X981673Y205040I-1010J-3354D01*
G03X981891Y205046I104J170D01*
G02X983641Y205656I1987J-2884D01*
G03X983827Y205842I-14J200D01*
G02X987321Y209102I3494J-242D01*
G02X987564Y209093I-8J-3503D01*
G37*
G36*
G01X860942Y329356D02*
G02Y332360I0J1502D01*
G01X864342D01*
G02Y329356I0J-1502D01*
G01X860942D01*
G37*
G36*
G01X920139Y309612D02*
G02X937341I8601J12042D01*
G01X920139D01*
G37*
G36*
G01X857187Y340708D02*
G02Y343712I0J1502D01*
G01X860587D01*
G02Y340708I0J-1502D01*
G01X857187D01*
G37*
G36*
G01X45960Y427304D02*
G02Y430308I0J1502D01*
G01X49360D01*
G02Y427304I0J-1502D01*
G01X45960D01*
G37*
G36*
G01X60921Y429304D02*
G02Y432308I0J1502D01*
G01X64821D01*
G02Y429304I0J-1502D01*
G01X60921D01*
G37*
G36*
G01X45812Y450100D02*
G02Y453104I0J1502D01*
G01X49212D01*
G02Y450100I0J-1502D01*
G01X45812D01*
G37*
G36*
G01X644414Y569666D02*
G02Y572672I0J1503D01*
G01X648314D01*
G02Y569666I0J-1503D01*
G01X644414D01*
G37*
G36*
G01X646358Y588814D02*
G02Y591818I0J1502D01*
G01X650258D01*
G02Y588814I0J-1502D01*
G01X646358D01*
G37*
G36*
G01X634794Y589002D02*
G02Y592006I0J1502D01*
G01X638694D01*
G02Y589002I0J-1502D01*
G01X634794D01*
G37*
G36*
G01X469014Y604311D02*
G03X469148I67J188D01*
G02X470331Y604516I1181J-3297D01*
G02X473834Y601014I1J-3502D01*
G02X473628Y599832I-3503J2D01*
G03Y599696I188J-68D01*
G02X473834Y598514I-3297J-1184D01*
G02X470331Y595012I-3503J1D01*
G01X470328D01*
G02X469148Y595217I1J3502D01*
G03X469014I-67J-188D01*
G02X467831Y595012I-1181J3297D01*
G02X466648Y595217I-2J3502D01*
G03X466514I-67J-188D01*
G02X465331Y595012I-1181J3297D01*
G02X464148Y595217I-2J3502D01*
G03X464014I-67J-188D01*
G02X462831Y595012I-1181J3297D01*
G02X461592Y595238I-1J3502D01*
G03X461450I-71J-187D01*
G02X460211Y595012I-1238J3276D01*
G02X459028Y595217I-2J3502D01*
G03X458894I-67J-188D01*
G02X457711Y595012I-1181J3297D01*
G02X454208Y598514I-1J3502D01*
G02X454414Y599696I3503J-2D01*
G03Y599832I-188J68D01*
G02X454208Y601014I3297J1184D01*
G02X457711Y604516I3503J-1D01*
G01X457714D01*
G02X458894Y604311I-1J-3502D01*
G03X459028I67J188D01*
G02X460211Y604516I1181J-3297D01*
G02X461450Y604290I1J-3502D01*
G03X461592I71J187D01*
G02X462831Y604516I1238J-3276D01*
G02X464014Y604311I2J-3502D01*
G03X464148I67J188D01*
G02X465331Y604516I1181J-3297D01*
G02X466514Y604311I2J-3502D01*
G03X466648I67J188D01*
G02X467831Y604516I1181J-3297D01*
G02X469014Y604311I2J-3502D01*
G37*
G36*
G01X509510Y613939D02*
Y613940D01*
G02X516514I3502J0D01*
G01Y613939D01*
G02X516234Y612568I-3502J1D01*
G03X516235Y612412I185J-77D01*
G02X516372Y612030I-3223J-1372D01*
G03X516544Y611887I192J56D01*
G02X517354Y611708I-338J-3451D01*
G03X517486I66J189D01*
G02X518635Y611904I1149J-3272D01*
G02Y604968I0J-3468D01*
G02X517486Y605164I0J3468D01*
G03X517354I-66J-189D01*
G02X516205Y604968I-1149J3272D01*
G02X515056Y605164I0J3468D01*
G03X514924I-66J-189D01*
G02X514513Y605048I-1146J3273D01*
G02X514514Y605003I-3501J-100D01*
G01Y604999D01*
G02X514234Y603629I-3503J2D01*
G03Y603473I184J-78D01*
G02X514514Y602101I-3223J-1372D01*
G02X511011Y598598I-3503J0D01*
G02X508840Y599353I1J3503D01*
G03X508609Y599365I-124J-157D01*
G02X506745Y598828I-1864J2967D01*
G02X503242Y602331I0J3503D01*
G02X503522Y603703I3503J0D01*
G03Y603859I-184J78D01*
G02X503242Y605231I3223J1372D01*
G02X503522Y606603I3503J0D01*
G03Y606759I-184J78D01*
G02X503242Y608131I3223J1372D01*
G02X506745Y611634I3503J0D01*
G02X508871Y610914I-1J-3503D01*
G01X508916Y610880D01*
X509025Y610868D01*
X509449Y611065D01*
X509511Y611157D01*
X509514Y611212D01*
G02X509790Y612412I3498J-173D01*
G03Y612568I-184J78D01*
G02X509510Y613939I3222J1372D01*
G37*
G36*
G01X1525960Y621415D02*
G03X1526094I67J188D01*
G02X1527277Y621620I1181J-3297D01*
G02X1530780Y618118I1J-3502D01*
G02X1530574Y616936I-3503J2D01*
G03Y616800I188J-68D01*
G02X1530780Y615618I-3297J-1184D01*
G02X1530569Y614421I-3503J0D01*
G03Y614285I188J-68D01*
G02X1530780Y613088I-3292J-1197D01*
G02X1530574Y611906I-3503J2D01*
G03Y611770I188J-68D01*
G02X1530780Y610588I-3297J-1184D01*
G02X1530556Y609358I-3503J2D01*
G03Y609218I188J-70D01*
G02X1530780Y607988I-3279J-1232D01*
G02X1530574Y606806I-3503J2D01*
G03Y606670I188J-68D01*
G02X1530780Y605488I-3297J-1184D01*
G02X1527277Y601986I-3503J1D01*
G01X1527274D01*
G02X1526094Y602191I1J3502D01*
G03X1525960I-67J-188D01*
G02X1524777Y601986I-1181J3297D01*
G02X1521274Y605488I-1J3502D01*
G02X1521480Y606670I3503J-2D01*
G03Y606806I-188J68D01*
G02X1521274Y607988I3297J1184D01*
G02X1521498Y609218I3503J-2D01*
G03Y609358I-188J70D01*
G02X1521274Y610588I3279J1232D01*
G02X1521480Y611770I3503J-2D01*
G03Y611906I-188J68D01*
G02X1521274Y613088I3297J1184D01*
G02X1521485Y614285I3503J0D01*
G03Y614421I-188J68D01*
G02X1521274Y615618I3292J1197D01*
G02X1521480Y616800I3503J-2D01*
G03Y616936I-188J68D01*
G02X1521274Y618118I3297J1184D01*
G02X1524777Y621620I3503J-1D01*
G01X1524780D01*
G02X1525960Y621415I-1J-3502D01*
G37*
G36*
G01X1357462Y632413D02*
Y632414D01*
G02X1364466I3502J0D01*
G01Y632413D01*
G02X1364186Y631042I-3502J1D01*
G03X1364187Y630886I185J-77D01*
G02X1364411Y630133I-3224J-1369D01*
G03X1364567Y629973I197J36D01*
G02X1365006Y629851I-707J-3395D01*
G03X1365138I66J189D01*
G02X1366283Y630046I1146J-3272D01*
G01X1366287D01*
G02Y623112I0J-3467D01*
G01X1366283D01*
G02X1365138Y623307I1J3467D01*
G03X1365006I-66J-189D01*
G02X1363857Y623112I-1146J3272D01*
G02X1362708Y623307I-3J3467D01*
G03X1362576I-66J-189D01*
G02X1362165Y623191I-1146J3273D01*
G02X1362166Y623146I-3501J-100D01*
G01Y623142D01*
G02X1361886Y621772I-3503J2D01*
G03Y621616I184J-78D01*
G02X1362166Y620244I-3223J-1372D01*
G02X1358663Y616742I-3503J1D01*
G01X1358662D01*
G02X1356492Y617496I1J3502D01*
G03X1356261Y617508I-124J-157D01*
G02X1354397Y616972I-1862J2967D01*
G02X1350894Y620474I-1J3502D01*
G02X1351174Y621846I3503J0D01*
G03Y622002I-184J78D01*
G02X1350894Y623374I3223J1372D01*
G02X1351174Y624746I3503J0D01*
G03Y624902I-184J78D01*
G02X1350894Y626274I3223J1372D01*
G02X1354397Y629776I3503J-1D01*
G02X1357197Y628378I0J-3503D01*
G03X1357316Y628302I160J120D01*
G02X1357363Y628292I-705J-3431D01*
G01X1357522Y628461D01*
G03X1357570Y628647I-146J137D01*
G02X1357462Y629514I3394J863D01*
G02X1357742Y630886I3502J0D01*
G03Y631042I-184J78D01*
G02X1357462Y632413I3222J1372D01*
G37*
G36*
G01X1701661Y643052D02*
G02Y646056I0J1502D01*
G01X1705561D01*
G02Y643052I0J-1502D01*
G01X1701661D01*
G37*
G36*
G01X1620462Y642739D02*
Y642741D01*
G02X1627466I3502J0D01*
G01Y642739D01*
G02X1627166Y641322I-3502J1D01*
G03Y641160I183J-81D01*
G02X1627387Y640480I-3203J-1417D01*
G03X1627543Y640326I196J42D01*
G02X1628006Y640199I-684J-3400D01*
G03X1628138I66J189D01*
G02X1629283Y640394I1146J-3272D01*
G01X1629287D01*
G02Y633460I0J-3467D01*
G01X1629283D01*
G02X1628138Y633655I1J3467D01*
G03X1628006I-66J-189D01*
G02X1626857Y633460I-1146J3272D01*
G02X1625708Y633655I-3J3467D01*
G03X1625576I-66J-189D01*
G02X1625165Y633539I-1146J3273D01*
G02X1625166Y633494I-3501J-100D01*
G01Y633490D01*
G02X1624886Y632120I-3503J2D01*
G03Y631964I184J-78D01*
G02X1625166Y630592I-3223J-1372D01*
G02X1621663Y627090I-3503J1D01*
G01X1621662D01*
G02X1619492Y627844I1J3502D01*
G03X1619261Y627856I-124J-157D01*
G02X1617397Y627320I-1862J2967D01*
G02X1613894Y630822I-1J3502D01*
G02X1614174Y632194I3503J0D01*
G03Y632350I-184J78D01*
G02X1613894Y633722I3223J1372D01*
G02X1614174Y635094I3503J0D01*
G03Y635250I-184J78D01*
G02X1613894Y636622I3223J1372D01*
G02X1617397Y640124I3503J-1D01*
G01X1617398D01*
G02X1620198Y638726I0J-3504D01*
G03X1620316Y638650I160J119D01*
G02X1620330Y638647I-727J-3426D01*
G01X1620490Y638813D01*
G03X1620542Y638994I-143J139D01*
G02X1620462Y639741I3422J744D01*
G02X1620762Y641160I3502J1D01*
G03Y641322I-183J81D01*
G02X1620462Y642739I3202J1418D01*
G37*
G36*
G01X353915Y649354D02*
G02X355195Y649596I1279J-3260D01*
G02X358698Y646094I1J-3502D01*
G02X358517Y644986I-3502J3D01*
G03X358522Y644848I190J-62D01*
G02X358778Y643534I-3247J-1315D01*
G02X358572Y642352I-3503J2D01*
G03Y642216I188J-68D01*
G02X358778Y641034I-3297J-1184D01*
G02X355275Y637532I-3503J1D01*
G01X355272D01*
G02X354096Y637736I2J3502D01*
G03X353955Y637734I-68J-188D01*
G02X352675Y637492I-1279J3260D01*
G02X351492Y637697I-2J3502D01*
G03X351358I-67J-188D01*
G02X350175Y637492I-1181J3297D01*
G02X348992Y637697I-2J3502D01*
G03X348858I-67J-188D01*
G02X347675Y637492I-1181J3297D01*
G02X346492Y637697I-2J3502D01*
G03X346358I-67J-188D01*
G02X345175Y637492I-1181J3297D01*
G02X343992Y637697I-2J3502D01*
G03X343858I-67J-188D01*
G02X342675Y637492I-1181J3297D01*
G02X339172Y640994I-1J3502D01*
G02X339378Y642176I3503J-2D01*
G03Y642312I-188J68D01*
G02X339172Y643494I3297J1184D01*
G02X339353Y644602I3502J-3D01*
G03X339348Y644740I-190J62D01*
G02X339092Y646054I3247J1315D01*
G02X342595Y649556I3503J-1D01*
G01X342598D01*
G02X343778Y649351I-1J-3502D01*
G03X343912I67J188D01*
G02X345095Y649556I1181J-3297D01*
G02X346278Y649351I2J-3502D01*
G03X346412I67J188D01*
G02X347595Y649556I1181J-3297D01*
G02X348778Y649351I2J-3502D01*
G03X348912I67J188D01*
G02X350095Y649556I1181J-3297D01*
G02X351278Y649351I2J-3502D01*
G03X351412I67J188D01*
G02X352595Y649556I1181J-3297D01*
G02X353774Y649352I1J-3502D01*
G03X353915Y649354I68J188D01*
G37*
G36*
G01X476310Y648139D02*
Y648140D01*
G02X483314I3502J0D01*
G01Y648139D01*
G02X483034Y646768I-3502J1D01*
G03X483035Y646612I185J-77D01*
G02X483202Y646120I-3224J-1369D01*
G03X483369Y645972I194J50D01*
G02X484054Y645808I-461J-3437D01*
G03X484186I66J189D01*
G02X485335Y646004I1149J-3272D01*
G02Y639068I0J-3468D01*
G02X484186Y639264I0J3468D01*
G03X484054I-66J-189D01*
G02X482905Y639068I-1149J3272D01*
G02X481756Y639264I0J3468D01*
G03X481624I-66J-189D01*
G02X481213Y639148I-1146J3273D01*
G02X481214Y639103I-3501J-100D01*
G01Y639099D01*
G02X480934Y637729I-3503J2D01*
G03Y637573I184J-78D01*
G02X481214Y636201I-3223J-1372D01*
G02X477711Y632698I-3503J0D01*
G02X475540Y633453I1J3503D01*
G03X475309Y633465I-124J-157D01*
G02X473445Y632928I-1864J2967D01*
G02X469942Y636431I0J3503D01*
G02X470222Y637803I3503J0D01*
G03Y637959I-184J78D01*
G02X469942Y639331I3223J1372D01*
G02X470222Y640703I3503J0D01*
G03Y640859I-184J78D01*
G02X469942Y642231I3223J1372D01*
G02X473445Y645734I3503J0D01*
G02X475657Y644947I0J-3502D01*
G03X475869Y644921I127J155D01*
G01X476196Y645075D01*
G03X476310Y645255I-86J181D01*
G02X476590Y646612I3502J-15D01*
G03Y646768I-184J78D01*
G02X476310Y648139I3222J1372D01*
G37*
G36*
G01X1452863Y653667D02*
G02X1454046Y653872I1181J-3297D01*
G02X1455229Y653667I2J-3502D01*
G03X1455363I67J188D01*
G02X1456541Y653872I1181J-3297D01*
G01X1456546D01*
G02X1457918Y653592I0J-3502D01*
G03X1458074I78J184D01*
G02X1459445Y653872I1372J-3222D01*
G01X1459446D01*
G02X1462948Y650370I0J-3502D01*
G01Y650365D01*
G02X1462701Y649077I-3502J4D01*
G03X1462699Y648936I186J-73D01*
G02X1462898Y647770I-3303J-1164D01*
G02X1462693Y646587I-3502J-2D01*
G03Y646453I188J-67D01*
G02X1462898Y645273I-3297J-1181D01*
G01Y645270D01*
G02X1459396Y641768I-3502J0D01*
G01X1459395D01*
G02X1458024Y642048I1J3502D01*
G03X1457868I-78J-184D01*
G02X1456496Y641768I-1372J3222D01*
G01X1456491D01*
G02X1455313Y641973I3J3502D01*
G03X1455179I-67J-188D01*
G02X1453996Y641768I-1181J3297D01*
G02X1452813Y641973I-2J3502D01*
G03X1452679I-67J-188D01*
G02X1451496Y641768I-1181J3297D01*
G02X1450313Y641973I-2J3502D01*
G03X1450179I-67J-188D01*
G02X1448996Y641768I-1181J3297D01*
G02X1447757Y641994I-1J3502D01*
G03X1447615I-71J-187D01*
G02X1446376Y641768I-1238J3276D01*
G02X1445193Y641973I-2J3502D01*
G03X1445059I-67J-188D01*
G02X1443879Y641768I-1181J3297D01*
G01X1443876D01*
G02X1440374Y645270I0J3502D01*
G01Y645273D01*
G02X1440579Y646453I3502J-1D01*
G03Y646587I-188J67D01*
G02X1440374Y647770I3297J1181D01*
G02X1440621Y649063I3502J1D01*
G03X1440623Y649204I-186J73D01*
G02X1440424Y650366I3303J1164D01*
G01Y650370D01*
G02X1443926Y653872I3502J0D01*
G01X1443929D01*
G02X1445109Y653667I-1J-3502D01*
G03X1445243I67J188D01*
G02X1446426Y653872I1181J-3297D01*
G02X1447665Y653646I1J-3502D01*
G03X1447807I71J187D01*
G02X1449046Y653872I1238J-3276D01*
G02X1450229Y653667I2J-3502D01*
G03X1450363I67J188D01*
G02X1451546Y653872I1181J-3297D01*
G02X1452729Y653667I2J-3502D01*
G03X1452863I67J188D01*
G37*
G36*
G01X1587462Y661739D02*
Y661741D01*
G02X1594466I3502J0D01*
G01Y661739D01*
G02X1594166Y660322I-3502J1D01*
G03Y660160I183J-81D01*
G02X1594387Y659480I-3203J-1417D01*
G03X1594543Y659326I196J42D01*
G02X1595006Y659199I-684J-3400D01*
G03X1595138I66J189D01*
G02X1596283Y659394I1146J-3272D01*
G01X1596287D01*
G02Y652460I0J-3467D01*
G01X1596283D01*
G02X1595138Y652655I1J3467D01*
G03X1595006I-66J-189D01*
G02X1593857Y652460I-1146J3272D01*
G02X1592708Y652655I-3J3467D01*
G03X1592576I-66J-189D01*
G02X1592165Y652539I-1146J3273D01*
G02X1592166Y652494I-3501J-100D01*
G01Y652490D01*
G02X1591886Y651120I-3503J2D01*
G03Y650964I184J-78D01*
G02X1592166Y649592I-3223J-1372D01*
G02X1588663Y646090I-3503J1D01*
G01X1588662D01*
G02X1586492Y646844I1J3502D01*
G03X1586261Y646856I-124J-157D01*
G02X1584397Y646320I-1862J2967D01*
G02X1580894Y649822I-1J3502D01*
G02X1581174Y651194I3503J0D01*
G03Y651350I-184J78D01*
G02X1580894Y652722I3223J1372D01*
G02X1581174Y654094I3503J0D01*
G03Y654250I-184J78D01*
G02X1580894Y655622I3223J1372D01*
G02X1584397Y659124I3503J-1D01*
G01X1584398D01*
G02X1587198Y657726I0J-3504D01*
G03X1587316Y657650I160J119D01*
G02X1587330Y657647I-727J-3426D01*
G01X1587490Y657813D01*
G03X1587542Y657994I-143J139D01*
G02X1587462Y658741I3422J744D01*
G02X1587762Y660160I3502J1D01*
G03Y660322I-183J81D01*
G02X1587462Y661739I3202J1418D01*
G37*
G36*
G01X246810Y663079D02*
Y663080D01*
G02X253814I3502J0D01*
G01Y663079D01*
G02X253534Y661708I-3502J1D01*
G03X253535Y661552I185J-77D01*
G02X253756Y660818I-3223J-1371D01*
G03X253917Y660658I197J37D01*
G02X254454Y660517I-609J-3414D01*
G03X254586I66J189D01*
G02X255731Y660712I1146J-3272D01*
G01X255735D01*
G02Y653778I0J-3467D01*
G01X255731D01*
G02X254586Y653973I1J3467D01*
G03X254454I-66J-189D01*
G02X253305Y653778I-1146J3272D01*
G02X252156Y653973I-3J3467D01*
G03X252024I-66J-189D01*
G02X251613Y653857I-1146J3273D01*
G02X251614Y653812I-3501J-100D01*
G01Y653808D01*
G02X251334Y652438I-3503J2D01*
G03Y652282I184J-78D01*
G02X251614Y650910I-3223J-1372D01*
G02X248111Y647408I-3503J1D01*
G01X248110D01*
G02X245940Y648162I1J3502D01*
G03X245709Y648174I-124J-157D01*
G02X243845Y647638I-1862J2967D01*
G02X240342Y651140I-1J3502D01*
G02X240622Y652512I3503J0D01*
G03Y652668I-184J78D01*
G02X240342Y654040I3223J1372D01*
G02X240622Y655412I3503J0D01*
G03Y655568I-184J78D01*
G02X240342Y656940I3223J1372D01*
G02X243845Y660442I3503J-1D01*
G01X243846D01*
G02X246158Y659570I0J-3502D01*
G01X246204Y659529D01*
X246324Y659514D01*
X246711Y659708D01*
G03X246821Y659902I-89J179D01*
G02X246810Y660179I3491J277D01*
G01Y660180D01*
G02X247090Y661552I3502J0D01*
G03Y661708I-184J78D01*
G02X246810Y663079I3222J1372D01*
G37*
G36*
G01X1390162Y665283D02*
Y665284D01*
G02X1397166I3502J0D01*
G01Y665283D01*
G02X1396886Y663912I-3502J1D01*
G03Y663756I184J-78D01*
G02X1397105Y663033I-3223J-1371D01*
G03X1397261Y662874I197J37D01*
G02X1397706Y662751I-699J-3396D01*
G03X1397838I66J189D01*
G02X1398983Y662946I1146J-3272D01*
G01X1398987D01*
G02Y656012I0J-3467D01*
G01X1398983D01*
G02X1397838Y656207I1J3467D01*
G03X1397706I-66J-189D01*
G02X1396557Y656012I-1146J3272D01*
G02X1395408Y656207I-3J3467D01*
G03X1395276I-66J-189D01*
G02X1394865Y656091I-1146J3273D01*
G02X1394866Y656046I-3501J-100D01*
G01Y656042D01*
G02X1394586Y654672I-3503J2D01*
G03Y654516I184J-78D01*
G02X1394866Y653144I-3223J-1372D01*
G02X1391363Y649642I-3503J1D01*
G01X1391362D01*
G02X1389192Y650396I1J3502D01*
G03X1388961Y650408I-124J-157D01*
G02X1387097Y649872I-1862J2967D01*
G02X1383594Y653374I-1J3502D01*
G02X1383874Y654746I3503J0D01*
G03Y654902I-184J78D01*
G02X1383594Y656274I3223J1372D01*
G02X1383874Y657646I3503J0D01*
G03Y657802I-184J78D01*
G02X1383594Y659174I3223J1372D01*
G02X1387097Y662676I3503J-1D01*
G02X1389897Y661278I0J-3503D01*
G03X1390016Y661202I160J120D01*
G02X1390055Y661194I-684J-3435D01*
G01X1390214Y661362D01*
G03X1390263Y661547I-145J138D01*
G02X1390162Y662380I3401J835D01*
G01Y662384D01*
G02X1390442Y663756I3502J0D01*
G03Y663912I-184J78D01*
G02X1390162Y665283I3222J1372D01*
G37*
G36*
G01X635567Y670272D02*
G02Y673276I0J1502D01*
G01X638967D01*
G02Y670272I0J-1502D01*
G01X635567D01*
G37*
G36*
G01X443710Y674539D02*
Y674540D01*
G02X450714I3502J0D01*
G01Y674539D01*
G02X450434Y673168I-3502J1D01*
G03X450435Y673012I185J-77D01*
G02X450575Y672618I-3225J-1368D01*
G03X450742Y672476I192J56D01*
G02X451454Y672308I-436J-3440D01*
G03X451586I66J189D01*
G02X452735Y672504I1149J-3272D01*
G02Y665568I0J-3468D01*
G02X451586Y665764I0J3468D01*
G03X451454I-66J-189D01*
G02X450305Y665568I-1149J3272D01*
G02X449156Y665764I0J3468D01*
G03X449024I-66J-189D01*
G02X448613Y665648I-1146J3273D01*
G02X448614Y665603I-3501J-100D01*
G01Y665599D01*
G02X448334Y664229I-3503J2D01*
G03Y664073I184J-78D01*
G02X448614Y662701I-3223J-1372D01*
G02X445111Y659198I-3503J0D01*
G02X442940Y659953I1J3503D01*
G03X442709Y659965I-124J-157D01*
G02X440845Y659428I-1864J2967D01*
G02X437342Y662931I0J3503D01*
G02X437622Y664303I3503J0D01*
G03Y664459I-184J78D01*
G02X437342Y665831I3223J1372D01*
G02X437622Y667203I3503J0D01*
G03Y667359I-184J78D01*
G02X437342Y668731I3223J1372D01*
G02X440845Y672234I3503J0D01*
G02X443057Y671445I-2J-3502D01*
G01X443059D01*
Y671444D01*
G03X443267Y671418I125J156D01*
G01X443594Y671567D01*
G03X443711Y671743I-83J182D01*
G01Y671744D01*
G02X443990Y673012I3501J-106D01*
G03Y673168I-184J78D01*
G02X443710Y674539I3222J1372D01*
G37*
G36*
G01X1554692Y695499D02*
Y695501D01*
G02X1561696I3502J0D01*
G01Y695499D01*
G02X1561396Y694082I-3502J1D01*
G03Y693920I183J-81D01*
G02X1561616Y693249I-3201J-1421D01*
G03X1561772Y693095I196J42D01*
G02X1562236Y692968I-681J-3400D01*
G03X1562368I66J189D01*
G02X1563517Y693164I1149J-3272D01*
G02Y686228I0J-3468D01*
G02X1562368Y686424I0J3468D01*
G03X1562236I-66J-189D01*
G02X1561087Y686228I-1149J3272D01*
G02X1559938Y686424I0J3468D01*
G03X1559806I-66J-189D01*
G02X1559395Y686308I-1146J3273D01*
G02X1559396Y686263I-3501J-100D01*
G01Y686259D01*
G02X1559116Y684889I-3503J2D01*
G03Y684733I184J-78D01*
G02X1559396Y683361I-3223J-1372D01*
G02X1559161Y682101I-3503J1D01*
G03X1559168Y681940I186J-73D01*
G02X1559530Y680391I-3141J-1551D01*
G02X1556581Y676933I-3502J0D01*
G03X1556453Y676856I32J-198D01*
G02X1553657Y675462I-2797J2109D01*
G02X1550154Y678965I0J3503D01*
G02X1550455Y680384I3503J-2D01*
G03Y680546I-183J81D01*
G02X1550154Y681965I3202J1421D01*
G02X1550494Y683470I3503J0D01*
G03X1550498Y683634I-180J86D01*
G02X1550224Y684991I3229J1358D01*
G02X1550574Y686516I3503J-1D01*
G03X1550579Y686678I-180J87D01*
G02X1550324Y687989I3248J1312D01*
G01Y687991D01*
G02X1553827Y691494I3503J0D01*
G02X1554292Y691463I0J-3503D01*
G01X1554340Y691456D01*
X1554429Y691487D01*
X1554686Y691752D01*
G03X1554739Y691925I-144J139D01*
G02X1554692Y692501I3455J572D01*
G02X1554992Y693920I3502J1D01*
G03Y694082I-183J81D01*
G02X1554692Y695499I3202J1418D01*
G37*
G36*
G01X279540Y697279D02*
Y697280D01*
G02X286544I3502J0D01*
G01Y697279D01*
G02X286264Y695908I-3502J1D01*
G03Y695752I184J-78D01*
G02X286477Y695066I-3221J-1376D01*
G03X286638Y694908I196J39D01*
G02X287184Y694765I-603J-3415D01*
G03X287316I66J189D01*
G02X288461Y694960I1146J-3272D01*
G01X288465D01*
G02Y688026I0J-3467D01*
G01X288461D01*
G02X287316Y688221I1J3467D01*
G03X287184I-66J-189D01*
G02X286035Y688026I-1146J3272D01*
G02X284886Y688221I-3J3467D01*
G03X284754I-66J-189D01*
G02X284343Y688105I-1146J3273D01*
G02X284344Y688052I-3501J-93D01*
G01Y688050D01*
G02X284064Y686679I-3503J1D01*
G03Y686523I184J-78D01*
G02X284344Y685151I-3223J-1372D01*
G02X280841Y681648I-3503J0D01*
G02X278670Y682403I1J3503D01*
G03X278439Y682415I-124J-157D01*
G02X276575Y681878I-1864J2967D01*
G02X273072Y685381I0J3503D01*
G02X273352Y686753I3503J0D01*
G03Y686909I-184J78D01*
G02X273072Y688281I3223J1372D01*
G02X273352Y689653I3503J0D01*
G03Y689809I-184J78D01*
G02X273072Y691181I3223J1372D01*
G02X276575Y694684I3503J0D01*
G02X278885Y693814I0J-3502D01*
G01X278930Y693774D01*
X279050Y693758D01*
X279437Y693949D01*
G03X279548Y694142I-88J179D01*
G02X279540Y694377I3494J237D01*
G01Y694380D01*
G02X279820Y695752I3502J0D01*
G03Y695908I-184J78D01*
G02X279540Y697279I3222J1372D01*
G37*
G36*
G01X1422762Y697853D02*
Y697854D01*
G02X1429766I3502J0D01*
G01Y697853D01*
G02X1429486Y696482I-3502J1D01*
G03Y696326I184J-78D01*
G02X1429631Y695916I-3223J-1370D01*
G03X1429789Y695773I193J54D01*
G02X1430336Y695631I-595J-3416D01*
G03X1430468I66J189D01*
G02X1431613Y695826I1146J-3272D01*
G01X1431617D01*
G02Y688892I0J-3467D01*
G01X1431613D01*
G02X1430468Y689087I1J3467D01*
G03X1430336I-66J-189D01*
G02X1429187Y688892I-1146J3272D01*
G02X1428038Y689087I-3J3467D01*
G03X1427906I-66J-189D01*
G02X1427612Y688998I-1151J3271D01*
G03X1427461Y688794I49J-194D01*
G02X1427466Y688624I-3497J-188D01*
G02X1427186Y687252I-3503J0D01*
G03Y687096I184J-78D01*
G02X1427466Y685724I-3223J-1372D01*
G02X1423963Y682222I-3503J1D01*
G01X1423962D01*
G02X1421792Y682976I1J3502D01*
G03X1421561Y682988I-124J-157D01*
G02X1419697Y682452I-1862J2967D01*
G02X1416194Y685954I-1J3502D01*
G02X1416474Y687326I3503J0D01*
G03Y687482I-184J78D01*
G02X1416194Y688854I3223J1372D01*
G02X1416474Y690226I3503J0D01*
G03Y690382I-184J78D01*
G02X1416194Y691754I3223J1372D01*
G02X1419697Y695256I3503J-1D01*
G02X1422498Y693857I0J-3504D01*
G03X1422615Y693782I160J120D01*
G02X1422652Y693774I-722J-3427D01*
G01X1422812Y693943D01*
G03X1422861Y694127I-145J137D01*
G02X1422762Y694954I3405J827D01*
G01Y694955D01*
G02X1423042Y696326I3502J-1D01*
G03Y696482I-184J78D01*
G02X1422762Y697853I3222J1372D01*
G37*
G36*
G01X411210Y699439D02*
Y699440D01*
G02X418214I3502J0D01*
G01Y699439D01*
G02X417934Y698068I-3502J1D01*
G03X417935Y697912I185J-77D01*
G02X418145Y697237I-3223J-1373D01*
G03X418317Y697079I196J40D01*
G02X419054Y696908I-411J-3443D01*
G03X419186I66J189D01*
G02X420335Y697104I1149J-3272D01*
G02Y690168I0J-3468D01*
G02X419186Y690364I0J3468D01*
G03X419054I-66J-189D01*
G02X417905Y690168I-1149J3272D01*
G02X416756Y690364I0J3468D01*
G03X416624I-66J-189D01*
G02X416213Y690248I-1146J3273D01*
G02X416214Y690203I-3501J-100D01*
G01Y690199D01*
G02X415934Y688829I-3503J2D01*
G03Y688673I184J-78D01*
G02X416214Y687301I-3223J-1372D01*
G02X412711Y683798I-3503J0D01*
G02X410540Y684553I1J3503D01*
G03X410309Y684565I-124J-157D01*
G02X408445Y684028I-1864J2967D01*
G02X404942Y687531I0J3503D01*
G02X405222Y688903I3503J0D01*
G03Y689059I-184J78D01*
G02X404942Y690431I3223J1372D01*
G02X405222Y691803I3503J0D01*
G03Y691959I-184J78D01*
G02X404942Y693331I3223J1372D01*
G02X408445Y696834I3503J0D01*
G02X410567Y696116I-3J-3502D01*
G01X410569D01*
Y696115D01*
G03X410780Y696097I120J160D01*
G01X411102Y696262D01*
G03X411211Y696445I-91J178D01*
G02X411210Y696540I3501J84D01*
G02X411490Y697912I3502J0D01*
G03Y698068I-184J78D01*
G02X411210Y699439I3222J1372D01*
G37*
G36*
G01X378310Y717059D02*
Y717060D01*
G02X385314I3502J0D01*
G01Y717059D01*
G02X385034Y715688I-3502J1D01*
G03Y715532I184J-78D01*
G02X385207Y715020I-3221J-1374D01*
G03X385374Y714871I194J49D01*
G02X386054Y714708I-464J-3436D01*
G03X386186I66J189D01*
G02X387335Y714904I1149J-3272D01*
G02Y707968I0J-3468D01*
G02X386186Y708164I0J3468D01*
G03X386054I-66J-189D01*
G02X384905Y707968I-1149J3272D01*
G02X383756Y708164I0J3468D01*
G03X383624I-66J-189D01*
G02X383213Y708048I-1146J3273D01*
G02X383214Y708003I-3501J-100D01*
G01Y707999D01*
G02X382934Y706629I-3503J2D01*
G03Y706473I184J-78D01*
G02X383214Y705101I-3223J-1372D01*
G02X379711Y701598I-3503J0D01*
G02X377540Y702353I1J3503D01*
G03X377309Y702365I-124J-157D01*
G02X375445Y701828I-1864J2967D01*
G02X371942Y705331I0J3503D01*
G02X372222Y706703I3503J0D01*
G03Y706859I-184J78D01*
G02X371942Y708231I3223J1372D01*
G02X372222Y709603I3503J0D01*
G03Y709759I-184J78D01*
G02X371942Y711131I3223J1372D01*
G02X375445Y714634I3503J0D01*
G02X377657Y713847I0J-3502D01*
G01X377702Y713810D01*
X377816Y713796D01*
X378196Y713977D01*
G03X378310Y714157I-86J181D01*
G01Y714161D01*
G02X378590Y715532I3502J-1D01*
G03Y715688I-184J78D01*
G02X378310Y717059I3222J1372D01*
G37*
G36*
G01X345172Y715688D02*
G02X344892Y717060I3223J1372D01*
G02X351898I3503J0D01*
G02X351618Y715688I-3503J0D01*
G03Y715532I184J-78D01*
G02X351832Y714835I-3223J-1371D01*
G02X351862Y714836I130J-3464D01*
G01X351868D01*
G02X353014Y714640I-3J-3468D01*
G03X353146I66J189D01*
G02X354295Y714836I1149J-3272D01*
G02Y707900I0J-3468D01*
G02X353146Y708096I0J3468D01*
G03X353014I-66J-189D01*
G02X351865Y707900I-1149J3272D01*
G02X350716Y708096I0J3468D01*
G03X350584I-66J-189D01*
G02X350173Y707980I-1146J3273D01*
G02X350174Y707935I-3501J-100D01*
G01Y707931D01*
G02X349894Y706561I-3503J2D01*
G03Y706405I184J-78D01*
G02X350174Y705033I-3223J-1372D01*
G02X346671Y701530I-3503J0D01*
G02X344500Y702285I1J3503D01*
G03X344269Y702297I-124J-157D01*
G02X342405Y701760I-1864J2967D01*
G02X338902Y705263I0J3503D01*
G02X339182Y706635I3503J0D01*
G03Y706791I-184J78D01*
G02X338902Y708163I3223J1372D01*
G02X339182Y709535I3503J0D01*
G03Y709691I-184J78D01*
G02X338902Y711063I3223J1372D01*
G02X342405Y714566I3503J0D01*
G02X344283Y714019I-2J-3503D01*
G01X344328Y713990D01*
X344434Y713986D01*
X344789Y714169D01*
G03X344897Y714337I-92J178D01*
G02X345172Y715532I3498J-176D01*
G03Y715688I-184J78D01*
G37*
G36*
G01X1455554Y715722D02*
G02X1455274Y717094I3223J1372D01*
G02X1462280I3503J0D01*
G02X1462000Y715723I-3503J1D01*
G03Y715566I184J-78D01*
G02X1462059Y715418I-3223J-1371D01*
G03X1462235Y715288I188J70D01*
G02X1463194Y715098I-188J-3462D01*
G03X1463326I66J189D01*
G02X1464475Y715294I1149J-3272D01*
G02Y708358I0J-3468D01*
G02X1463326Y708554I0J3468D01*
G03X1463194I-66J-189D01*
G02X1462045Y708358I-1149J3272D01*
G02X1460896Y708554I0J3468D01*
G03X1460764I-66J-189D01*
G02X1460530Y708481I-1149J3272D01*
G03X1460383Y708283I53J-193D01*
G02X1460384Y708201I-3502J-84D01*
G02X1460104Y706829I-3503J0D01*
G03Y706673I184J-78D01*
G02X1460384Y705301I-3223J-1372D01*
G02X1458218Y702064I-3502J0D01*
G03X1458101Y701828I76J-185D01*
G02X1458218Y700932I-3386J-898D01*
G01Y700931D01*
G02X1451212I-3503J0D01*
G02X1451371Y701972I3503J-2D01*
G03X1451362Y702115I-191J60D01*
G01X1451313Y702222D01*
G03X1451211Y702323I-182J-82D01*
G02X1449112Y705531I1403J3209D01*
G02X1451314Y708783I3502J0D01*
G03X1451433Y709021I-74J186D01*
G02X1451312Y709931I3382J913D01*
G02X1454814Y713434I3503J0D01*
G01X1454816D01*
G02X1454883Y713433I-19J-3503D01*
G01X1454926Y713432D01*
X1455005Y713465D01*
X1455237Y713716D01*
G03X1455290Y713870I-146J136D01*
G02X1455274Y714194I3486J335D01*
G02X1455554Y715566I3503J0D01*
G03Y715722I-184J78D01*
G37*
G36*
G01X312410Y717399D02*
Y717400D01*
G02X319414I3502J0D01*
G01Y717399D01*
G02X319134Y716028I-3502J1D01*
G03X319135Y715872I185J-77D01*
G02X319346Y715189I-3224J-1370D01*
G03X319502Y715033I196J40D01*
G02X319954Y714908I-696J-3397D01*
G03X320086I66J189D01*
G02X321235Y715104I1149J-3272D01*
G02Y708168I0J-3468D01*
G02X320086Y708364I0J3468D01*
G03X319954I-66J-189D01*
G02X318805Y708168I-1149J3272D01*
G02X317656Y708364I0J3468D01*
G03X317524I-66J-189D01*
G02X317113Y708248I-1146J3273D01*
G02X317114Y708203I-3501J-100D01*
G01Y708199D01*
G02X316834Y706829I-3503J2D01*
G03Y706673I184J-78D01*
G02X317114Y705301I-3223J-1372D01*
G02X316143Y702881I-3503J1D01*
G03X316089Y702719I144J-138D01*
G02X316114Y702301I-3478J-418D01*
G02X313343Y698876I-3502J0D01*
G03X313226Y698802I42J-196D01*
G02X310445Y697428I-2782J2129D01*
G02X306942Y700931I0J3503D01*
G02X307243Y702350I3503J-2D01*
G03Y702512I-183J81D01*
G02X306942Y703931I3202J1421D01*
G02X307913Y706351I3503J-1D01*
G03X307967Y706513I-144J138D01*
G02X307942Y706931I3478J418D01*
G02X308292Y708456I3503J-1D01*
G03X308297Y708618I-180J87D01*
G02X308042Y709929I3248J1312D01*
G01Y709931D01*
G02X311545Y713434I3503J0D01*
G02X312019Y713401I-6J-3503D01*
G01X312067Y713394D01*
X312157Y713426D01*
X312415Y713696D01*
G03X312467Y713869I-145J138D01*
G01Y713870D01*
G02X312410Y714499I3445J629D01*
G01Y714500D01*
G02X312690Y715872I3502J0D01*
G03Y716028I-184J78D01*
G02X312410Y717399I3222J1372D01*
G37*
G36*
G01X1488762Y717443D02*
Y717444D01*
G02X1495766I3502J0D01*
G01Y717443D01*
G02X1495486Y716072I-3502J1D01*
G03X1495487Y715916I185J-77D01*
G02X1495706Y715190I-3224J-1369D01*
G03X1495862Y715031I197J37D01*
G02X1496306Y714908I-702J-3396D01*
G03X1496438I66J189D01*
G02X1497587Y715104I1149J-3272D01*
G02Y708168I0J-3468D01*
G02X1496438Y708364I0J3468D01*
G03X1496306I-66J-189D01*
G02X1495157Y708168I-1149J3272D01*
G02X1494008Y708364I0J3468D01*
G03X1493876I-66J-189D01*
G02X1493465Y708248I-1146J3273D01*
G02X1493466Y708203I-3501J-100D01*
G01Y708199D01*
G02X1493186Y706829I-3503J2D01*
G03Y706673I184J-78D01*
G02X1493466Y705301I-3223J-1372D01*
G02X1489963Y701798I-3503J0D01*
G02X1487792Y702553I1J3503D01*
G03X1487561Y702565I-124J-157D01*
G02X1485697Y702028I-1864J2967D01*
G02X1482194Y705531I0J3503D01*
G02X1482474Y706903I3503J0D01*
G03Y707059I-184J78D01*
G02X1482194Y708431I3223J1372D01*
G02X1482474Y709803I3503J0D01*
G03Y709959I-184J78D01*
G02X1482194Y711331I3223J1372D01*
G02X1485697Y714834I3503J0D01*
G02X1488498Y713434I0J-3502D01*
G03X1488615Y713359I160J120D01*
G02X1488655Y713350I-749J-3421D01*
G01X1488815Y713519D01*
G03X1488864Y713704I-146J138D01*
G02X1488762Y714542I3400J839D01*
G01Y714544D01*
G02X1489042Y715916I3502J0D01*
G03Y716072I-184J78D01*
G02X1488762Y717443I3222J1372D01*
G37*
G36*
G01X1521562D02*
Y717444D01*
G02X1528566I3502J0D01*
G01Y717443D01*
G02X1528286Y716072I-3502J1D01*
G03X1528287Y715916I185J-77D01*
G02X1528506Y715190I-3224J-1369D01*
G03X1528662Y715031I197J37D01*
G02X1529106Y714908I-702J-3396D01*
G03X1529238I66J189D01*
G02X1530387Y715104I1149J-3272D01*
G02Y708168I0J-3468D01*
G02X1529238Y708364I0J3468D01*
G03X1529106I-66J-189D01*
G02X1527957Y708168I-1149J3272D01*
G02X1526808Y708364I0J3468D01*
G03X1526676I-66J-189D01*
G02X1526265Y708248I-1146J3273D01*
G02X1526266Y708203I-3501J-100D01*
G01Y708199D01*
G02X1525986Y706829I-3503J2D01*
G03Y706673I184J-78D01*
G02X1526266Y705301I-3223J-1372D01*
G02X1522763Y701798I-3503J0D01*
G02X1520592Y702553I1J3503D01*
G03X1520361Y702565I-124J-157D01*
G02X1518497Y702028I-1864J2967D01*
G02X1514994Y705531I0J3503D01*
G02X1515274Y706903I3503J0D01*
G03Y707059I-184J78D01*
G02X1514994Y708431I3223J1372D01*
G02X1515274Y709803I3503J0D01*
G03Y709959I-184J78D01*
G02X1514994Y711331I3223J1372D01*
G02X1518497Y714834I3503J0D01*
G02X1521298Y713434I0J-3502D01*
G03X1521415Y713359I160J120D01*
G02X1521455Y713350I-749J-3421D01*
G01X1521615Y713519D01*
G03X1521664Y713704I-146J138D01*
G02X1521562Y714542I3400J839D01*
G01Y714544D01*
G02X1521842Y715916I3502J0D01*
G03Y716072I-184J78D01*
G02X1521562Y717443I3222J1372D01*
G37*
G36*
G01X869275Y748970D02*
G02Y751974I0J1502D01*
G01X873175D01*
G02Y748970I0J-1502D01*
G01X869275D01*
G37*
G36*
G01X1332812Y854880D02*
G02Y857886I0J1503D01*
G01X1336812D01*
G02Y854880I0J-1503D01*
G01X1332812D01*
G37*
G36*
G01X509572Y863824D02*
G02Y866830I0J1503D01*
G01X513572D01*
G02Y863824I0J-1503D01*
G01X509572D01*
G37*
G36*
G01X427130Y958146D02*
G02Y960550I0J1202D01*
G01X430831D01*
G02Y958146I0J-1202D01*
G01X427130D01*
G37*
G36*
G01X1425452Y958144D02*
G02Y960550I0J1203D01*
G01X1429153D01*
G02Y958144I0J-1203D01*
G01X1425452D01*
G37*
G36*
G01X1434704Y961334D02*
G02Y963738I0J1202D01*
G01X1438405D01*
G02Y961334I0J-1202D01*
G01X1434704D01*
G37*
G36*
G01X1445806D02*
G02Y963738I0J1202D01*
G01X1449507D01*
G02Y961334I0J-1202D01*
G01X1445806D01*
G37*
G36*
G01X1456909D02*
G02Y963738I0J1202D01*
G01X1460610D01*
G02Y961334I0J-1202D01*
G01X1456909D01*
G37*
G36*
G01X1468011D02*
G02Y963738I0J1202D01*
G01X1471712D01*
G02Y961334I0J-1202D01*
G01X1468011D01*
G37*
G36*
G01X384571D02*
G02Y963740I0J1203D01*
G01X388272D01*
G02Y961334I0J-1203D01*
G01X384571D01*
G37*
G36*
G01X395673D02*
G02Y963740I0J1203D01*
G01X399374D01*
G02Y961334I0J-1203D01*
G01X395673D01*
G37*
G36*
G01X406776D02*
G02Y963740I0J1203D01*
G01X410477D01*
G02Y961334I0J-1203D01*
G01X406776D01*
G37*
G36*
G01X417878D02*
G02Y963740I0J1203D01*
G01X421579D01*
G02Y961334I0J-1203D01*
G01X417878D01*
G37*
G36*
G01X427130Y964524D02*
G02Y966928I0J1202D01*
G01X430831D01*
G02Y964524I0J-1202D01*
G01X427130D01*
G37*
G36*
G01X1425452Y964522D02*
G02Y966928I0J1203D01*
G01X1429153D01*
G02Y964522I0J-1203D01*
G01X1425452D01*
G37*
G36*
G01X1434704Y967712D02*
G02Y970116I0J1202D01*
G01X1438405D01*
G02Y967712I0J-1202D01*
G01X1434704D01*
G37*
G36*
G01X1445806D02*
G02Y970116I0J1202D01*
G01X1449507D01*
G02Y967712I0J-1202D01*
G01X1445806D01*
G37*
G36*
G01X1456909D02*
G02Y970116I0J1202D01*
G01X1460610D01*
G02Y967712I0J-1202D01*
G01X1456909D01*
G37*
G36*
G01X1468011D02*
G02Y970116I0J1202D01*
G01X1471712D01*
G02Y967712I0J-1202D01*
G01X1468011D01*
G37*
G36*
G01X384571D02*
G02Y970118I0J1203D01*
G01X388272D01*
G02Y967712I0J-1203D01*
G01X384571D01*
G37*
G36*
G01X395673D02*
G02Y970118I0J1203D01*
G01X399374D01*
G02Y967712I0J-1203D01*
G01X395673D01*
G37*
G36*
G01X406776D02*
G02Y970118I0J1203D01*
G01X410477D01*
G02Y967712I0J-1203D01*
G01X406776D01*
G37*
G36*
G01X417878D02*
G02Y970118I0J1203D01*
G01X421579D01*
G02Y967712I0J-1203D01*
G01X417878D01*
G37*
G36*
G01X427130Y970902D02*
G02Y973306I0J1202D01*
G01X430831D01*
G02Y970902I0J-1202D01*
G01X427130D01*
G37*
G36*
G01X1425452Y970900D02*
G02Y973306I0J1203D01*
G01X1429153D01*
G02Y970900I0J-1203D01*
G01X1425452D01*
G37*
G36*
G01X1434704Y974090D02*
G02Y976494I0J1202D01*
G01X1438405D01*
G02Y974090I0J-1202D01*
G01X1434704D01*
G37*
G36*
G01X1445806D02*
G02Y976494I0J1202D01*
G01X1449507D01*
G02Y974090I0J-1202D01*
G01X1445806D01*
G37*
G36*
G01X1456909D02*
G02Y976494I0J1202D01*
G01X1460610D01*
G02Y974090I0J-1202D01*
G01X1456909D01*
G37*
G36*
G01X1468011D02*
G02Y976494I0J1202D01*
G01X1471712D01*
G02Y974090I0J-1202D01*
G01X1468011D01*
G37*
G36*
G01X384571D02*
G02Y976496I0J1203D01*
G01X388272D01*
G02Y974090I0J-1203D01*
G01X384571D01*
G37*
G36*
G01X395673D02*
G02Y976496I0J1203D01*
G01X399374D01*
G02Y974090I0J-1203D01*
G01X395673D01*
G37*
G36*
G01X406776D02*
G02Y976496I0J1203D01*
G01X410477D01*
G02Y974090I0J-1203D01*
G01X406776D01*
G37*
G36*
G01X417878D02*
G02Y976496I0J1203D01*
G01X421579D01*
G02Y974090I0J-1203D01*
G01X417878D01*
G37*
G36*
G01X427130Y977280D02*
G02Y979684I0J1202D01*
G01X430831D01*
G02Y977280I0J-1202D01*
G01X427130D01*
G37*
G36*
G01X1425452Y977278D02*
G02Y979684I0J1203D01*
G01X1429153D01*
G02Y977278I0J-1203D01*
G01X1425452D01*
G37*
G36*
G01X1361894Y1106578D02*
G02Y1108982I0J1202D01*
G01X1365595D01*
G02Y1106578I0J-1202D01*
G01X1361894D01*
G37*
G36*
G01X1372997D02*
G02Y1108982I0J1202D01*
G01X1376698D01*
G02Y1106578I0J-1202D01*
G01X1372997D01*
G37*
G36*
G01X1458090D02*
G02Y1108982I0J1202D01*
G01X1461791D01*
G02Y1106578I0J-1202D01*
G01X1458090D01*
G37*
G36*
G01X1469192D02*
G02Y1108982I0J1202D01*
G01X1472893D01*
G02Y1106578I0J-1202D01*
G01X1469192D01*
G37*
G36*
G01X385752D02*
G02Y1108984I0J1203D01*
G01X389453D01*
G02Y1106578I0J-1203D01*
G01X385752D01*
G37*
G36*
G01X396855D02*
G02Y1108984I0J1203D01*
G01X400556D01*
G02Y1106578I0J-1203D01*
G01X396855D01*
G37*
G36*
G01X481948D02*
G02Y1108984I0J1203D01*
G01X485649D01*
G02Y1106578I0J-1203D01*
G01X481948D01*
G37*
G36*
G01X493050D02*
G02Y1108984I0J1203D01*
G01X496751D01*
G02Y1106578I0J-1203D01*
G01X493050D01*
G37*
G36*
G01X428311Y1109768D02*
G02Y1112172I0J1202D01*
G01X432012D01*
G02Y1109768I0J-1202D01*
G01X428311D01*
G37*
G36*
G01X450491D02*
G02Y1112172I0J1202D01*
G01X454192D01*
G02Y1109768I0J-1202D01*
G01X450491D01*
G37*
G36*
G01X1404453Y1109766D02*
G02Y1112172I0J1203D01*
G01X1408154D01*
G02Y1109766I0J-1203D01*
G01X1404453D01*
G37*
G36*
G01X1426633D02*
G02Y1112172I0J1203D01*
G01X1430334D01*
G02Y1109766I0J-1203D01*
G01X1426633D01*
G37*
G36*
G01X1361894Y1112956D02*
G02Y1115360I0J1202D01*
G01X1365595D01*
G02Y1112956I0J-1202D01*
G01X1361894D01*
G37*
G36*
G01X1372997D02*
G02Y1115360I0J1202D01*
G01X1376698D01*
G02Y1112956I0J-1202D01*
G01X1372997D01*
G37*
G36*
G01X1384099D02*
G02Y1115360I0J1202D01*
G01X1387800D01*
G02Y1112956I0J-1202D01*
G01X1384099D01*
G37*
G36*
G01X1395201D02*
G02Y1115360I0J1202D01*
G01X1398902D01*
G02Y1112956I0J-1202D01*
G01X1395201D01*
G37*
G36*
G01X1435885D02*
G02Y1115360I0J1202D01*
G01X1439586D01*
G02Y1112956I0J-1202D01*
G01X1435885D01*
G37*
G36*
G01X1446987D02*
G02Y1115360I0J1202D01*
G01X1450688D01*
G02Y1112956I0J-1202D01*
G01X1446987D01*
G37*
G36*
G01X1458090D02*
G02Y1115360I0J1202D01*
G01X1461791D01*
G02Y1112956I0J-1202D01*
G01X1458090D01*
G37*
G36*
G01X1469192D02*
G02Y1115360I0J1202D01*
G01X1472893D01*
G02Y1112956I0J-1202D01*
G01X1469192D01*
G37*
G36*
G01X385752D02*
G02Y1115362I0J1203D01*
G01X389453D01*
G02Y1112956I0J-1203D01*
G01X385752D01*
G37*
G36*
G01X396855D02*
G02Y1115362I0J1203D01*
G01X400556D01*
G02Y1112956I0J-1203D01*
G01X396855D01*
G37*
G36*
G01X407957D02*
G02Y1115362I0J1203D01*
G01X411658D01*
G02Y1112956I0J-1203D01*
G01X407957D01*
G37*
G36*
G01X419059D02*
G02Y1115362I0J1203D01*
G01X422760D01*
G02Y1112956I0J-1203D01*
G01X419059D01*
G37*
G36*
G01X459743D02*
G02Y1115362I0J1203D01*
G01X463444D01*
G02Y1112956I0J-1203D01*
G01X459743D01*
G37*
G36*
G01X470845D02*
G02Y1115362I0J1203D01*
G01X474546D01*
G02Y1112956I0J-1203D01*
G01X470845D01*
G37*
G36*
G01X481948D02*
G02Y1115362I0J1203D01*
G01X485649D01*
G02Y1112956I0J-1203D01*
G01X481948D01*
G37*
G36*
G01X493050D02*
G02Y1115362I0J1203D01*
G01X496751D01*
G02Y1112956I0J-1203D01*
G01X493050D01*
G37*
G36*
G01X428311Y1116146D02*
G02Y1118550I0J1202D01*
G01X432012D01*
G02Y1116146I0J-1202D01*
G01X428311D01*
G37*
G36*
G01X450491D02*
G02Y1118550I0J1202D01*
G01X454192D01*
G02Y1116146I0J-1202D01*
G01X450491D01*
G37*
G36*
G01X1404453Y1116144D02*
G02Y1118550I0J1203D01*
G01X1408154D01*
G02Y1116144I0J-1203D01*
G01X1404453D01*
G37*
G36*
G01X1426633D02*
G02Y1118550I0J1203D01*
G01X1430334D01*
G02Y1116144I0J-1203D01*
G01X1426633D01*
G37*
G36*
G01X1361894Y1119334D02*
G02Y1121738I0J1202D01*
G01X1365595D01*
G02Y1119334I0J-1202D01*
G01X1361894D01*
G37*
G36*
G01X1372997D02*
G02Y1121738I0J1202D01*
G01X1376698D01*
G02Y1119334I0J-1202D01*
G01X1372997D01*
G37*
G36*
G01X1384099D02*
G02Y1121738I0J1202D01*
G01X1387800D01*
G02Y1119334I0J-1202D01*
G01X1384099D01*
G37*
G36*
G01X1395201D02*
G02Y1121738I0J1202D01*
G01X1398902D01*
G02Y1119334I0J-1202D01*
G01X1395201D01*
G37*
G36*
G01X1435885D02*
G02Y1121738I0J1202D01*
G01X1439586D01*
G02Y1119334I0J-1202D01*
G01X1435885D01*
G37*
G36*
G01X1446987D02*
G02Y1121738I0J1202D01*
G01X1450688D01*
G02Y1119334I0J-1202D01*
G01X1446987D01*
G37*
G36*
G01X1458090D02*
G02Y1121738I0J1202D01*
G01X1461791D01*
G02Y1119334I0J-1202D01*
G01X1458090D01*
G37*
G36*
G01X1469192D02*
G02Y1121738I0J1202D01*
G01X1472893D01*
G02Y1119334I0J-1202D01*
G01X1469192D01*
G37*
G36*
G01X385752D02*
G02Y1121740I0J1203D01*
G01X389453D01*
G02Y1119334I0J-1203D01*
G01X385752D01*
G37*
G36*
G01X396855D02*
G02Y1121740I0J1203D01*
G01X400556D01*
G02Y1119334I0J-1203D01*
G01X396855D01*
G37*
G36*
G01X407957D02*
G02Y1121740I0J1203D01*
G01X411658D01*
G02Y1119334I0J-1203D01*
G01X407957D01*
G37*
G36*
G01X419059D02*
G02Y1121740I0J1203D01*
G01X422760D01*
G02Y1119334I0J-1203D01*
G01X419059D01*
G37*
G36*
G01X459743D02*
G02Y1121740I0J1203D01*
G01X463444D01*
G02Y1119334I0J-1203D01*
G01X459743D01*
G37*
G36*
G01X470845D02*
G02Y1121740I0J1203D01*
G01X474546D01*
G02Y1119334I0J-1203D01*
G01X470845D01*
G37*
G36*
G01X481948D02*
G02Y1121740I0J1203D01*
G01X485649D01*
G02Y1119334I0J-1203D01*
G01X481948D01*
G37*
G36*
G01X493050D02*
G02Y1121740I0J1203D01*
G01X496751D01*
G02Y1119334I0J-1203D01*
G01X493050D01*
G37*
G36*
G01X428311Y1122524D02*
G02Y1124928I0J1202D01*
G01X432012D01*
G02Y1122524I0J-1202D01*
G01X428311D01*
G37*
G36*
G01X450491D02*
G02Y1124928I0J1202D01*
G01X454192D01*
G02Y1122524I0J-1202D01*
G01X450491D01*
G37*
G36*
G01X1404453Y1122522D02*
G02Y1124928I0J1203D01*
G01X1408154D01*
G02Y1122522I0J-1203D01*
G01X1404453D01*
G37*
G36*
G01X1426633D02*
G02Y1124928I0J1203D01*
G01X1430334D01*
G02Y1122522I0J-1203D01*
G01X1426633D01*
G37*
G36*
G01X1372997Y1125712D02*
G02Y1128116I0J1202D01*
G01X1376698D01*
G02Y1125712I0J-1202D01*
G01X1372997D01*
G37*
G36*
G01X1384099D02*
G02Y1128116I0J1202D01*
G01X1387800D01*
G02Y1125712I0J-1202D01*
G01X1384099D01*
G37*
G36*
G01X1395201D02*
G02Y1128116I0J1202D01*
G01X1398902D01*
G02Y1125712I0J-1202D01*
G01X1395201D01*
G37*
G36*
G01X1435885D02*
G02Y1128116I0J1202D01*
G01X1439586D01*
G02Y1125712I0J-1202D01*
G01X1435885D01*
G37*
G36*
G01X1446987D02*
G02Y1128116I0J1202D01*
G01X1450688D01*
G02Y1125712I0J-1202D01*
G01X1446987D01*
G37*
G36*
G01X1458090D02*
G02Y1128116I0J1202D01*
G01X1461791D01*
G02Y1125712I0J-1202D01*
G01X1458090D01*
G37*
G36*
G01X396855D02*
G02Y1128118I0J1203D01*
G01X400556D01*
G02Y1125712I0J-1203D01*
G01X396855D01*
G37*
G36*
G01X407957D02*
G02Y1128118I0J1203D01*
G01X411658D01*
G02Y1125712I0J-1203D01*
G01X407957D01*
G37*
G36*
G01X419059D02*
G02Y1128118I0J1203D01*
G01X422760D01*
G02Y1125712I0J-1203D01*
G01X419059D01*
G37*
G36*
G01X459743D02*
G02Y1128118I0J1203D01*
G01X463444D01*
G02Y1125712I0J-1203D01*
G01X459743D01*
G37*
G36*
G01X470845D02*
G02Y1128118I0J1203D01*
G01X474546D01*
G02Y1125712I0J-1203D01*
G01X470845D01*
G37*
G36*
G01X481948D02*
G02Y1128118I0J1203D01*
G01X485649D01*
G02Y1125712I0J-1203D01*
G01X481948D01*
G37*
G36*
G01X368726Y1212952D02*
G02Y1215958I0J1503D01*
G01X372126D01*
G02Y1212952I0J-1503D01*
G01X368726D01*
G37*
G36*
G01X1325972Y1332957D02*
Y1332959D01*
G02X1329474Y1336460I3502J-1D01*
G02X1331645Y1335705I-1J-3503D01*
G03X1331876Y1335693I124J157D01*
G02X1333740Y1336230I1864J-2967D01*
G02X1337242Y1332727I-1J-3503D01*
G01Y1332726D01*
G02X1336962Y1331355I-3502J1D01*
G03Y1331199I184J-78D01*
G02X1337242Y1329827I-3222J-1372D01*
G02X1336962Y1328455I-3502J0D01*
G03Y1328299I184J-78D01*
G02X1337242Y1326927I-3222J-1372D01*
G01Y1326925D01*
G02X1333740Y1323424I-3502J1D01*
G02X1331971Y1323904I1J3503D01*
G01X1331926Y1323930D01*
X1331823Y1323932D01*
X1331476Y1323750D01*
G03X1331370Y1323587I94J-177D01*
G02X1331099Y1322462I-3494J247D01*
G03X1331098Y1322306I184J-79D01*
G02X1331378Y1320935I-3222J-1372D01*
G01Y1320934D01*
G02X1324374I-3502J0D01*
G01Y1320935D01*
G02X1324654Y1322306I3502J-1D01*
G03X1324653Y1322462I-185J77D01*
G02X1324439Y1323158I3223J1372D01*
G02X1324280Y1323154I-167J3464D01*
G02X1323131Y1323350I0J3468D01*
G03X1322999I-66J-189D01*
G02X1321850Y1323154I-1149J3272D01*
G02Y1330090I0J3468D01*
G02X1322999Y1329894I0J-3468D01*
G03X1323131I66J189D01*
G02X1324280Y1330090I1149J-3272D01*
G02X1325429Y1329894I0J-3468D01*
G03X1325561I66J189D01*
G02X1325972Y1330010I1146J-3273D01*
G01Y1330057D01*
G02X1326252Y1331429I3502J0D01*
G03Y1331585I-184J78D01*
G02X1325972Y1332957I3222J1372D01*
G37*
G36*
G01X349842Y1332976D02*
G02X353345Y1336478I3503J-1D01*
G01X353346D01*
G02X355516Y1335724I-1J-3502D01*
G03X355747Y1335712I124J157D01*
G02X357611Y1336248I1862J-2967D01*
G02X361114Y1332746I1J-3502D01*
G02X360834Y1331374I-3503J0D01*
G03Y1331218I184J-78D01*
G02X361114Y1329846I-3223J-1372D01*
G02X360834Y1328474I-3503J0D01*
G03Y1328318I184J-78D01*
G02X361114Y1326946I-3223J-1372D01*
G02X357611Y1323444I-3503J1D01*
G01X357609D01*
G02X355729Y1323992I1J3502D01*
G01X355683Y1324021D01*
X355578Y1324026D01*
X355222Y1323842D01*
G03X355114Y1323675I92J-178D01*
G01Y1323674D01*
G02X354836Y1322471I-3463J167D01*
G03Y1322313I184J-79D01*
G02X355118Y1320945I-3185J-1370D01*
G01Y1320942D01*
G02X348184I-3467J0D01*
G01Y1320945D01*
G02X348466Y1322313I3467J-2D01*
G03Y1322471I-184J79D01*
G02X348248Y1323175I3185J1372D01*
G02X348151Y1323174I-84J3466D01*
G02X347002Y1323369I-3J3467D01*
G03X346870I-66J-189D01*
G02X345725Y1323174I-1146J3272D01*
G01X345721D01*
G02Y1330108I0J3467D01*
G01X345725D01*
G02X346870Y1329913I-1J-3467D01*
G03X347002I66J189D01*
G02X348151Y1330108I1146J-3272D01*
G02X349300Y1329913I3J-3467D01*
G03X349432I66J189D01*
G02X349843Y1330029I1146J-3273D01*
G02X349842Y1330074I3501J100D01*
G01Y1330078D01*
G02X350122Y1331448I3503J-2D01*
G03Y1331604I-184J78D01*
G02X349842Y1332976I3223J1372D01*
G37*
G36*
G01X1293068Y1333014D02*
G02X1296570Y1336516I3502J0D01*
G01X1296571D01*
G02X1298741Y1335762I-1J-3502D01*
G03X1298972Y1335750I124J157D01*
G02X1300833Y1336286I1862J-2967D01*
G01X1300836D01*
G02X1304338Y1332784I0J-3502D01*
G01Y1332783D01*
G02X1304058Y1331412I-3502J1D01*
G03Y1331256I184J-78D01*
G02X1304338Y1329884I-3222J-1372D01*
G02X1304058Y1328512I-3502J0D01*
G03Y1328356I184J-78D01*
G02X1304338Y1326985I-3222J-1372D01*
G01Y1326984D01*
G02X1300836Y1323482I-3502J0D01*
G02X1299056Y1323968I0J3503D01*
G03X1298860Y1323972I-102J-172D01*
G01X1298512Y1323785D01*
X1298456Y1323697D01*
X1298453Y1323645D01*
G02X1298178Y1322462I-3497J189D01*
G03Y1322306I184J-78D01*
G02X1298458Y1320935I-3222J-1372D01*
G01Y1320934D01*
G02X1291454I-3502J0D01*
G01Y1320935D01*
G02X1291734Y1322306I3502J-1D01*
G03Y1322462I-184J78D01*
G02X1291509Y1323214I3222J1374D01*
G02X1291376Y1323212I-119J3465D01*
G02X1290227Y1323407I-3J3467D01*
G03X1290095I-66J-189D01*
G02X1288950Y1323212I-1146J3272D01*
G01X1288946D01*
G02Y1330146I0J3467D01*
G01X1288950D01*
G02X1290095Y1329951I-1J-3467D01*
G03X1290227I66J189D01*
G02X1291376Y1330146I1146J-3272D01*
G02X1292525Y1329951I3J-3467D01*
G03X1292657I66J189D01*
G02X1293068Y1330067I1146J-3273D01*
G01Y1330114D01*
G02X1293348Y1331486I3502J0D01*
G03Y1331642I-184J78D01*
G02X1293068Y1333013I3222J1372D01*
G01Y1333014D01*
G37*
G36*
G01X317218Y1331661D02*
G02X316938Y1333033I3223J1372D01*
G02X320441Y1336536I3503J0D01*
G02X322612Y1335781I-1J-3503D01*
G03X322843Y1335769I124J157D01*
G02X324707Y1336306I1864J-2967D01*
G02X328210Y1332803I0J-3503D01*
G02X327930Y1331431I-3503J0D01*
G03Y1331275I184J-78D01*
G02X328210Y1329903I-3223J-1372D01*
G02X327930Y1328531I-3503J0D01*
G03Y1328375I184J-78D01*
G02X328210Y1327003I-3223J-1372D01*
G02X324707Y1323500I-3503J0D01*
G02X322884Y1324012I0J3503D01*
G01X322838Y1324040D01*
X322732Y1324043D01*
X322381Y1323853D01*
G03X322276Y1323684I95J-176D01*
G02X321996Y1322431I-3465J117D01*
G03Y1322273I184J-79D01*
G02X322278Y1320905I-3185J-1370D01*
G01Y1320902D01*
G02X315344I-3467J0D01*
G01Y1320905D01*
G02X315626Y1322273I3467J-2D01*
G03Y1322431I-184J79D01*
G02X315390Y1323233I3184J1373D01*
G02X315247Y1323230I-144J3465D01*
G02X314098Y1323426I0J3468D01*
G03X313966I-66J-189D01*
G02X312817Y1323230I-1149J3272D01*
G02Y1330166I0J3468D01*
G02X313966Y1329970I0J-3468D01*
G03X314098I66J189D01*
G02X315247Y1330166I1149J-3272D01*
G02X316396Y1329970I0J-3468D01*
G03X316528I66J189D01*
G02X316939Y1330086I1146J-3273D01*
G02X316938Y1330131I3501J100D01*
G01Y1330135D01*
G02X317218Y1331505I3503J-2D01*
G03Y1331661I-184J78D01*
G37*
G36*
G01X1260172Y1333042D02*
G02X1263674Y1336544I3502J0D01*
G01X1263675D01*
G02X1265845Y1335790I-1J-3502D01*
G03X1266076Y1335778I124J157D01*
G02X1267937Y1336314I1862J-2967D01*
G01X1267940D01*
G02X1271442Y1332812I0J-3502D01*
G01Y1332811D01*
G02X1271162Y1331440I-3502J1D01*
G03Y1331284I184J-78D01*
G02X1271442Y1329912I-3222J-1372D01*
G02X1271162Y1328540I-3502J0D01*
G03Y1328384I184J-78D01*
G02X1271442Y1327013I-3222J-1372D01*
G01Y1327012D01*
G02X1267940Y1323510I-3502J0D01*
G01X1267938D01*
G02X1266154Y1323999I1J3502D01*
G01X1266108Y1324026D01*
X1266003Y1324028D01*
X1265607Y1323810D01*
X1265552Y1323720D01*
X1265551Y1323667D01*
G02X1265273Y1322406I-3501J111D01*
G03X1265272Y1322250I184J-79D01*
G02X1265552Y1320879I-3222J-1372D01*
G01Y1320878D01*
G02X1258548I-3502J0D01*
G01Y1320879D01*
G02X1258828Y1322250I3502J-1D01*
G03Y1322406I-184J78D01*
G02X1258589Y1323241I3222J1374D01*
G02X1258481Y1323240I-86J3466D01*
G01X1258479D01*
G02X1257331Y1323435I-2J3467D01*
G03X1257199I-66J-189D01*
G02X1256054Y1323240I-1146J3272D01*
G01X1256050D01*
G02Y1330174I0J3467D01*
G01X1256054D01*
G02X1257199Y1329979I-1J-3467D01*
G03X1257331I66J189D01*
G02X1258480Y1330174I1146J-3272D01*
G02X1259629Y1329979I3J-3467D01*
G03X1259761I66J189D01*
G02X1260172Y1330095I1146J-3273D01*
G01Y1330142D01*
G02X1260452Y1331514I3502J0D01*
G03Y1331670I-184J78D01*
G02X1260172Y1333041I3222J1372D01*
G01Y1333042D01*
G37*
G36*
G01X284322Y1331689D02*
G02X284042Y1333061I3223J1372D01*
G02X287545Y1336564I3503J0D01*
G02X289716Y1335809I-1J-3503D01*
G03X289947Y1335797I124J157D01*
G02X291811Y1336334I1864J-2967D01*
G02X295314Y1332831I0J-3503D01*
G02X295034Y1331459I-3503J0D01*
G03Y1331303I184J-78D01*
G02X295314Y1329931I-3223J-1372D01*
G02X295034Y1328559I-3503J0D01*
G03Y1328403I184J-78D01*
G02X295314Y1327031I-3223J-1372D01*
G02X291811Y1323528I-3503J0D01*
G02X289967Y1324053I1J3503D01*
G01X289921Y1324082D01*
X289815Y1324085D01*
X289415Y1323871D01*
X289358Y1323780D01*
X289357Y1323727D01*
G02X289076Y1322471I-3466J116D01*
G03Y1322313I184J-79D01*
G02X289358Y1320945I-3185J-1370D01*
G01Y1320942D01*
G02X282424I-3467J0D01*
G01Y1320945D01*
G02X282706Y1322313I3467J-2D01*
G03Y1322471I-184J79D01*
G02X282473Y1323261I3186J1369D01*
G02X282352Y1323258I-146J3464D01*
G01X282350D01*
G02X281202Y1323454I1J3468D01*
G03X281070I-66J-189D01*
G02X279921Y1323258I-1149J3272D01*
G02Y1330194I0J3468D01*
G02X281070Y1329998I0J-3468D01*
G03X281202I66J189D01*
G02X282351Y1330194I1149J-3272D01*
G02X283500Y1329998I0J-3468D01*
G03X283632I66J189D01*
G02X284043Y1330114I1146J-3273D01*
G02X284042Y1330159I3501J100D01*
G01Y1330163D01*
G02X284322Y1331533I3503J-2D01*
G03Y1331689I-184J78D01*
G37*
G36*
G01X1361459Y1339463D02*
G03X1361576Y1339543I-47J194D01*
G02X1364440Y1341030I2865J-2016D01*
G02X1367942Y1337527I-1J-3503D01*
G01Y1337525D01*
G02X1367642Y1336108I-3502J1D01*
G03Y1335946I183J-81D01*
G02X1367942Y1334527I-3202J-1418D01*
G02X1367642Y1333108I-3502J-1D01*
G03Y1332946I183J-81D01*
G02X1367942Y1331527I-3202J-1418D01*
G02X1367593Y1330002I-3502J-1D01*
G03X1367587Y1329840I180J-88D01*
G02X1367842Y1328531I-3247J-1312D01*
G01Y1328527D01*
G02X1364563Y1325032I-3502J0D01*
G01X1364561D01*
G03X1364420Y1324959I14J-200D01*
G01X1364208Y1324699D01*
X1364186Y1324618D01*
X1364192Y1324576D01*
G02X1364226Y1324084I-3468J-487D01*
G02X1363946Y1322712I-3502J0D01*
G03Y1322556I184J-78D01*
G02X1364226Y1321185I-3222J-1372D01*
G01Y1321184D01*
G02X1357222I-3502J0D01*
G01Y1321185D01*
G02X1357502Y1322556I3502J-1D01*
G03Y1322712I-184J78D01*
G02X1357334Y1323205I3222J1373D01*
G03X1357137Y1323355I-194J-50D01*
G02X1357080Y1323354I-89J3466D01*
G02X1355931Y1323550I0J3468D01*
G03X1355799I-66J-189D01*
G02X1354650Y1323354I-1149J3272D01*
G02Y1330290I0J3468D01*
G02X1355799Y1330094I0J-3468D01*
G03X1355931I66J189D01*
G02X1357080Y1330290I1149J-3272D01*
G02X1358229Y1330094I0J-3468D01*
G03X1358361I66J189D01*
G02X1358772Y1330210I1146J-3273D01*
G01Y1330257D01*
G02X1359052Y1331629I3502J0D01*
G03Y1331785I-184J78D01*
G02X1358772Y1333157I3222J1372D01*
G02X1359052Y1334529I3502J0D01*
G03Y1334685I-184J78D01*
G02X1358772Y1336056I3222J1372D01*
G01Y1336057D01*
G02X1361459Y1339463I3502J0D01*
G37*
G36*
G01X385890Y1339537D02*
G02X388771Y1341048I2881J-1991D01*
G01X388773D01*
G02X392274Y1337546I-1J-3502D01*
G02X391973Y1336127I-3503J2D01*
G03Y1335965I183J-81D01*
G02X392274Y1334546I-3202J-1421D01*
G02X391711Y1332643I-3503J1D01*
G03X391686Y1332481I168J-109D01*
G02X391814Y1331546I-3375J-938D01*
G02X391464Y1330021I-3503J1D01*
G03X391459Y1329859I180J-87D01*
G02X391714Y1328548I-3248J-1312D01*
G01Y1328546D01*
G02X388300Y1325045I-3502J0D01*
G01X388298D01*
G03X388152Y1324974I7J-200D01*
G01X387930Y1324713D01*
X387907Y1324630D01*
X387913Y1324588D01*
G02X387948Y1324092I-3432J-491D01*
G02X387666Y1322721I-3467J-1D01*
G03Y1322563I184J-79D01*
G02X387948Y1321195I-3185J-1370D01*
G01Y1321192D01*
G02X381014I-3467J0D01*
G01Y1321195D01*
G02X381296Y1322563I3467J-2D01*
G03Y1322721I-184J79D01*
G02X381088Y1323376I3185J1372D01*
G02X380952Y1323374I-119J3465D01*
G01X380950D01*
G02X379802Y1323569I-2J3467D01*
G03X379670I-66J-189D01*
G02X378525Y1323374I-1146J3272D01*
G01X378521D01*
G02Y1330308I0J3467D01*
G01X378525D01*
G02X379670Y1330113I-1J-3467D01*
G03X379802I66J189D01*
G02X380951Y1330308I1146J-3272D01*
G02X382100Y1330113I3J-3467D01*
G03X382232I66J189D01*
G02X382643Y1330229I1146J-3273D01*
G02X382642Y1330274I3501J100D01*
G01Y1330278D01*
G02X382922Y1331648I3503J-2D01*
G03Y1331804I-184J78D01*
G02X382642Y1333176I3223J1372D01*
G02X383188Y1335053I3503J-1D01*
G03X383213Y1335208I-169J107D01*
G02X383108Y1336056I3398J851D01*
G02X385773Y1339457I3503J0D01*
G03X385890Y1339537I-47J194D01*
G37*
G36*
G01X1391354Y1352488D02*
G02X1394856Y1355990I3502J0D01*
G01X1394857D01*
G02X1397027Y1355236I-1J-3502D01*
G03X1397258Y1355224I124J157D01*
G02X1399119Y1355760I1862J-2967D01*
G01X1399122D01*
G02X1402624Y1352258I0J-3502D01*
G01Y1352257D01*
G02X1402344Y1350886I-3502J1D01*
G03Y1350730I184J-78D01*
G02X1402624Y1349358I-3222J-1372D01*
G02X1402344Y1347986I-3502J0D01*
G03Y1347830I184J-78D01*
G02X1402624Y1346459I-3222J-1372D01*
G01Y1346458D01*
G02X1399122Y1342956I-3502J0D01*
G01X1399120D01*
G02X1397123Y1343582I1J3502D01*
G01X1397122D01*
G03X1397009Y1343618I-114J-164D01*
G01X1397008D01*
G03X1396808Y1343418I0J-200D01*
G01Y1343414D01*
G02X1396528Y1342043I-3502J1D01*
G03Y1341887I184J-78D01*
G02X1396808Y1340516I-3222J-1372D01*
G01Y1340515D01*
G02X1389804I-3502J0D01*
G01Y1340516D01*
G02X1390084Y1341887I3502J-1D01*
G03Y1342043I-184J78D01*
G02X1389916Y1342536I3222J1373D01*
G03X1389719Y1342686I-194J-50D01*
G01X1389662D01*
G02X1388513Y1342881I-3J3467D01*
G03X1388381I-66J-189D01*
G02X1387236Y1342686I-1146J3272D01*
G01X1387232D01*
G02Y1349620I0J3467D01*
G01X1387236D01*
G02X1388381Y1349425I-1J-3467D01*
G03X1388513I66J189D01*
G02X1389662Y1349620I1146J-3272D01*
G02X1390811Y1349425I3J-3467D01*
G03X1390943I66J189D01*
G02X1391354Y1349541I1146J-3273D01*
G01Y1349588D01*
G02X1391634Y1350960I3502J0D01*
G03Y1351116I-184J78D01*
G02X1391354Y1352487I3222J1372D01*
G01Y1352488D01*
G37*
G36*
G01X418121Y1355713D02*
G02X421315Y1357778I3194J-1438D01*
G01X421317D01*
G02X424818Y1354276I-1J-3502D01*
G02X424538Y1352904I-3503J0D01*
G03Y1352748I184J-78D01*
G02X424818Y1351376I-3223J-1372D01*
G01Y1351375D01*
G02X424505Y1349928I-3502J0D01*
G03X424499Y1349777I182J-83D01*
G02X424708Y1348586I-3294J-1192D01*
G02X424428Y1347214I-3503J0D01*
G03Y1347058I184J-78D01*
G02X424708Y1345686I-3223J-1372D01*
G02X421205Y1342184I-3503J1D01*
G01X421203D01*
G02X420507Y1342254I1J3502D01*
G03X420282Y1342132I-39J-196D01*
G02X420248Y1342052I-3208J1316D01*
G03Y1341894I184J-79D01*
G02X420530Y1340526I-3185J-1370D01*
G01Y1340523D01*
G02X413596I-3467J0D01*
G01Y1340526D01*
G02X413878Y1341894I3467J-2D01*
G03Y1342052I-184J79D01*
G02X413670Y1342707I3185J1372D01*
G02X413533Y1342704I-144J3465D01*
G02X412384Y1342900I0J3468D01*
G03X412252I-66J-189D01*
G02X411103Y1342704I-1149J3272D01*
G02Y1349640I0J3468D01*
G02X412252Y1349444I0J-3468D01*
G03X412384I66J189D01*
G02X413533Y1349640I1149J-3272D01*
G02X414682Y1349444I0J-3468D01*
G03X414814I66J189D01*
G02X415052Y1349518I1148J-3272D01*
G03X415198Y1349687I-53J193D01*
G02X415452Y1350638I3477J-419D01*
G03Y1350794I-184J78D01*
G02X415172Y1352166I3223J1372D01*
G02X417978Y1355599I3503J0D01*
G03X418121Y1355713I-39J196D01*
G37*
G36*
G01X791071Y1363081D02*
G02X790770Y1364500I3202J1421D01*
G02X797776I3503J0D01*
G02X797475Y1363081I-3503J2D01*
G03Y1362919I183J-81D01*
G02X797776Y1361500I-3202J-1421D01*
G02X797250Y1359655I-3503J1D01*
G03Y1359445I170J-105D01*
G02X797776Y1357600I-2977J-1846D01*
G02X797475Y1356181I-3503J2D01*
G03Y1356019I183J-81D01*
G02X797776Y1354600I-3202J-1421D01*
G02X790770I-3503J0D01*
G02X791071Y1356019I3503J-2D01*
G03Y1356181I-183J81D01*
G02X790770Y1357600I3202J1421D01*
G02X791296Y1359445I3503J-1D01*
G03Y1359655I-170J105D01*
G02X790770Y1361500I2977J1846D01*
G02X791071Y1362919I3503J-2D01*
G03Y1363081I-183J81D01*
G37*
G36*
G01X363406Y1368021D02*
G03X363540I67J188D01*
G02X364723Y1368226I1181J-3297D01*
G02X368226Y1364724I1J-3502D01*
G02X367918Y1363289I-3503J1D01*
G03X367910Y1363146I183J-82D01*
G02X368074Y1362085I-3338J-1059D01*
G02X367898Y1360988I-3502J-1D01*
G03X367909Y1360838I190J-61D01*
G02X368266Y1359298I-3145J-1541D01*
G01Y1359296D01*
G02X364764Y1355794I-3502J0D01*
G01X364761D01*
G02X363581Y1355999I1J3502D01*
G03X363447I-67J-188D01*
G02X362264Y1355794I-1181J3297D01*
G02X361081Y1355999I-2J3502D01*
G03X360947I-67J-188D01*
G02X359764Y1355794I-1181J3297D01*
G02X358345Y1356094I-1J3502D01*
G03X358183I-81J-183D01*
G02X356764Y1355794I-1418J3202D01*
G02X355581Y1355999I-2J3502D01*
G03X355447I-67J-188D01*
G02X354269Y1355794I-1181J3297D01*
G01X354264D01*
G02X353135Y1355981I0J3502D01*
G03X352993Y1355976I-64J-190D01*
G02X351632Y1355700I-1363J3227D01*
G02X348130Y1359203I1J3503D01*
G01Y1359206D01*
G02X348476Y1360723I3502J-1D01*
G03X348484Y1360878I-180J87D01*
G02X348270Y1362085I3288J1205D01*
G02X348577Y1363520I3502J1D01*
G03X348585Y1363663I-183J82D01*
G02X348420Y1364724I3338J1062D01*
G02X351923Y1368226I3503J-1D01*
G01X351926D01*
G02X353106Y1368021I-1J-3502D01*
G03X353240I67J188D01*
G02X354423Y1368226I1181J-3297D01*
G02X355606Y1368021I2J-3502D01*
G03X355740I67J188D01*
G02X356923Y1368226I1181J-3297D01*
G02X358106Y1368021I2J-3502D01*
G03X358240I67J188D01*
G02X359423Y1368226I1181J-3297D01*
G02X360747Y1367967I2J-3502D01*
G03X360899I76J185D01*
G02X362223Y1368226I1322J-3243D01*
G02X363406Y1368021I2J-3502D01*
G37*
G36*
G01X330686Y1378896D02*
Y1378897D01*
G02X337692I3503J0D01*
G01Y1378896D01*
G02X337434Y1377577I-3503J0D01*
G03Y1377427I185J-75D01*
G02X337692Y1376108I-3245J-1319D01*
G02X337384Y1374673I-3503J1D01*
G03X337376Y1374530I183J-82D01*
G02X337540Y1373469I-3338J-1059D01*
G02X337364Y1372372I-3502J-1D01*
G03X337375Y1372222I190J-61D01*
G02X337732Y1370682I-3145J-1541D01*
G01Y1370680D01*
G02X330728I-3502J0D01*
G01Y1370684D01*
G02X330904Y1371777I3502J-3D01*
G03X330893Y1371927I-190J61D01*
G02X330536Y1373469I3145J1541D01*
G02X330843Y1374904I3502J1D01*
G03X330851Y1375047I-183J82D01*
G02X330686Y1376108I3338J1062D01*
G02X330944Y1377427I3503J0D01*
G03Y1377577I-185J75D01*
G02X330686Y1378896I3245J1319D01*
G37*
G36*
G01X1091180Y1379188D02*
G02X1094683Y1382690I3503J-1D01*
G01X1094684D01*
G02X1096854Y1381936I-1J-3502D01*
G03X1097085Y1381924I124J157D01*
G02X1098949Y1382460I1862J-2967D01*
G02X1102452Y1378958I1J-3502D01*
G02X1102172Y1377586I-3503J0D01*
G03Y1377430I184J-78D01*
G02X1102452Y1376058I-3223J-1372D01*
G02X1102172Y1374686I-3503J0D01*
G03Y1374530I184J-78D01*
G02X1102452Y1373158I-3223J-1372D01*
G02X1098949Y1369656I-3503J1D01*
G01X1098947D01*
G02X1097004Y1370245I1J3502D01*
G01X1096960Y1370274D01*
X1096853Y1370282D01*
X1096494Y1370105D01*
G03X1096383Y1369939I89J-179D01*
G02X1096111Y1368806I-3494J240D01*
G03X1096112Y1368650I185J-77D01*
G02X1096392Y1367278I-3223J-1372D01*
G02X1089386I-3503J0D01*
G02X1089666Y1368650I3503J0D01*
G03Y1368806I-184J78D01*
G02X1089513Y1369243I3222J1373D01*
G03X1089330Y1369390I-193J-53D01*
G02X1088340Y1369581I155J3464D01*
G03X1088208I-66J-189D01*
G02X1087063Y1369386I-1146J3272D01*
G01X1087059D01*
G02Y1376320I0J3467D01*
G01X1087063D01*
G02X1088208Y1376125I-1J-3467D01*
G03X1088340I66J189D01*
G02X1089489Y1376320I1146J-3272D01*
G02X1090638Y1376125I3J-3467D01*
G03X1090770I66J189D01*
G02X1091181Y1376241I1146J-3273D01*
G02X1091180Y1376286I3501J100D01*
G01Y1376290D01*
G02X1091460Y1377660I3503J-2D01*
G03Y1377816I-184J78D01*
G02X1091180Y1379188I3223J1372D01*
G37*
G36*
G01X1123780D02*
G02X1127283Y1382690I3503J-1D01*
G01X1127284D01*
G02X1129454Y1381936I-1J-3502D01*
G03X1129685Y1381924I124J157D01*
G02X1131549Y1382460I1862J-2967D01*
G02X1135052Y1378958I1J-3502D01*
G02X1134772Y1377586I-3503J0D01*
G03Y1377430I184J-78D01*
G02X1135052Y1376058I-3223J-1372D01*
G02X1134772Y1374686I-3503J0D01*
G03Y1374530I184J-78D01*
G02X1135052Y1373158I-3223J-1372D01*
G02X1131549Y1369656I-3503J1D01*
G01X1131548D01*
G02X1129594Y1370252I0J3502D01*
G01X1129593Y1370253D01*
G03X1129390Y1370264I-111J-167D01*
G01X1129030Y1370077D01*
X1128972Y1369984D01*
X1128971Y1369929D01*
G02X1128692Y1368636I-3502J79D01*
G03Y1368480I184J-78D01*
G02X1128972Y1367108I-3223J-1372D01*
G02X1121966I-3503J0D01*
G02X1122246Y1368480I3503J0D01*
G03Y1368636I-184J78D01*
G02X1122052Y1369237I3223J1372D01*
G03X1121870Y1369392I-195J-44D01*
G02X1120940Y1369581I219J3461D01*
G03X1120808I-66J-189D01*
G02X1119663Y1369386I-1146J3272D01*
G01X1119659D01*
G02Y1376320I0J3467D01*
G01X1119663D01*
G02X1120808Y1376125I-1J-3467D01*
G03X1120940I66J189D01*
G02X1122089Y1376320I1146J-3272D01*
G02X1123238Y1376125I3J-3467D01*
G03X1123370I66J189D01*
G02X1123781Y1376241I1146J-3273D01*
G02X1123780Y1376286I3501J100D01*
G01Y1376290D01*
G02X1124060Y1377660I3503J-2D01*
G03Y1377816I-184J78D01*
G02X1123780Y1379188I3223J1372D01*
G37*
G36*
G01X1156480D02*
G02X1159983Y1382690I3503J-1D01*
G01X1159984D01*
G02X1162154Y1381936I-1J-3502D01*
G03X1162385Y1381924I124J157D01*
G02X1164249Y1382460I1862J-2967D01*
G02X1167752Y1378958I1J-3502D01*
G02X1167472Y1377586I-3503J0D01*
G03Y1377430I184J-78D01*
G02X1167752Y1376058I-3223J-1372D01*
G02X1167472Y1374686I-3503J0D01*
G03Y1374530I184J-78D01*
G02X1167752Y1373158I-3223J-1372D01*
G02X1164249Y1369656I-3503J1D01*
G01X1164247D01*
G02X1162195Y1370321I1J3502D01*
G01X1162149Y1370354D01*
X1162036Y1370362D01*
X1161617Y1370144D01*
X1161560Y1370046D01*
X1161561Y1369989D01*
G02X1161562Y1369918I-3502J-85D01*
G02X1161282Y1368546I-3503J0D01*
G03Y1368390I184J-78D01*
G02X1161562Y1367018I-3223J-1372D01*
G02X1154556I-3503J0D01*
G02X1154836Y1368390I3503J0D01*
G03Y1368546I-184J78D01*
G02X1154622Y1369242I3223J1372D01*
G03X1154446Y1369403I-196J-38D01*
G02X1153640Y1369581I339J3451D01*
G03X1153508I-66J-189D01*
G02X1152363Y1369386I-1146J3272D01*
G01X1152359D01*
G02Y1376320I0J3467D01*
G01X1152363D01*
G02X1153508Y1376125I-1J-3467D01*
G03X1153640I66J189D01*
G02X1154789Y1376320I1146J-3272D01*
G02X1155938Y1376125I3J-3467D01*
G03X1156070I66J189D01*
G02X1156481Y1376241I1146J-3273D01*
G02X1156480Y1376286I3501J100D01*
G01Y1376290D01*
G02X1156760Y1377660I3503J-2D01*
G03Y1377816I-184J78D01*
G02X1156480Y1379188I3223J1372D01*
G37*
G36*
G01X1189380D02*
G02X1192883Y1382690I3503J-1D01*
G01X1192884D01*
G02X1195054Y1381936I-1J-3502D01*
G03X1195285Y1381924I124J157D01*
G02X1197149Y1382460I1862J-2967D01*
G02X1200652Y1378958I1J-3502D01*
G02X1200372Y1377586I-3503J0D01*
G03Y1377430I184J-78D01*
G02X1200652Y1376058I-3223J-1372D01*
G02X1200372Y1374686I-3503J0D01*
G03Y1374530I184J-78D01*
G02X1200652Y1373158I-3223J-1372D01*
G02X1197149Y1369656I-3503J1D01*
G01X1197146D01*
G02X1195174Y1370265I2J3502D01*
G01X1195129Y1370296D01*
X1195021Y1370304D01*
X1194609Y1370097D01*
X1194551Y1370006D01*
X1194549Y1369951D01*
G02X1194272Y1368716I-3500J136D01*
G03Y1368560I184J-78D01*
G02X1194552Y1367188I-3223J-1372D01*
G02X1187546I-3503J0D01*
G02X1187826Y1368560I3503J0D01*
G03X1187827Y1368716I-184J79D01*
G02X1187651Y1369241I3222J1372D01*
G03X1187469Y1369392I-194J-49D01*
G02X1186540Y1369581I220J3461D01*
G03X1186408I-66J-189D01*
G02X1185263Y1369386I-1146J3272D01*
G01X1185259D01*
G02Y1376320I0J3467D01*
G01X1185263D01*
G02X1186408Y1376125I-1J-3467D01*
G03X1186540I66J189D01*
G02X1187689Y1376320I1146J-3272D01*
G02X1188838Y1376125I3J-3467D01*
G03X1188970I66J189D01*
G02X1189381Y1376241I1146J-3273D01*
G02X1189380Y1376286I3501J100D01*
G01Y1376290D01*
G02X1189660Y1377660I3503J-2D01*
G03Y1377816I-184J78D01*
G02X1189380Y1379188I3223J1372D01*
G37*
G36*
G01X1222180D02*
G02X1225683Y1382690I3503J-1D01*
G01X1225684D01*
G02X1227854Y1381936I-1J-3502D01*
G03X1228085Y1381924I124J157D01*
G02X1229949Y1382460I1862J-2967D01*
G02X1233452Y1378958I1J-3502D01*
G02X1233172Y1377586I-3503J0D01*
G03Y1377430I184J-78D01*
G02X1233452Y1376058I-3223J-1372D01*
G02X1233172Y1374686I-3503J0D01*
G03Y1374530I184J-78D01*
G02X1233452Y1373158I-3223J-1372D01*
G02X1229949Y1369656I-3503J1D01*
G01X1229948D01*
G02X1228009Y1370242I0J3502D01*
G01X1227964Y1370272D01*
X1227857Y1370279D01*
X1227497Y1370097D01*
G03X1227388Y1369927I91J-178D01*
G02X1227112Y1368716I-3499J161D01*
G03Y1368560I184J-78D01*
G02X1227392Y1367188I-3223J-1372D01*
G02X1220386I-3503J0D01*
G02X1220666Y1368560I3503J0D01*
G03X1220667Y1368716I-184J79D01*
G02X1220491Y1369239I3221J1375D01*
G03X1220308Y1369391I-194J-48D01*
G02X1219340Y1369581I177J3463D01*
G03X1219208I-66J-189D01*
G02X1218063Y1369386I-1146J3272D01*
G01X1218059D01*
G02Y1376320I0J3467D01*
G01X1218063D01*
G02X1219208Y1376125I-1J-3467D01*
G03X1219340I66J189D01*
G02X1220489Y1376320I1146J-3272D01*
G02X1221638Y1376125I3J-3467D01*
G03X1221770I66J189D01*
G02X1222181Y1376241I1146J-3273D01*
G02X1222180Y1376286I3501J100D01*
G01Y1376290D01*
G02X1222460Y1377660I3503J-2D01*
G03Y1377816I-184J78D01*
G02X1222180Y1379188I3223J1372D01*
G37*
G36*
G01X119722Y1377835D02*
G02X119442Y1379207I3223J1372D01*
G02X122945Y1382710I3503J0D01*
G02X125116Y1381955I-1J-3503D01*
G03X125347Y1381943I124J157D01*
G02X127211Y1382480I1864J-2967D01*
G02X130714Y1378977I0J-3503D01*
G02X130434Y1377605I-3503J0D01*
G03Y1377449I184J-78D01*
G02X130714Y1376077I-3223J-1372D01*
G02X130434Y1374705I-3503J0D01*
G03Y1374549I184J-78D01*
G02X130714Y1373177I-3223J-1372D01*
G02X127211Y1369674I-3503J0D01*
G02X125355Y1370207I1J3503D01*
G03X125153Y1370213I-106J-169D01*
G01X124800Y1370022D01*
X124744Y1369930D01*
X124743Y1369876D01*
G02X124464Y1368575I-3502J71D01*
G03Y1368419I184J-78D01*
G02X124744Y1367047I-3223J-1372D01*
G02X122784Y1363903I-3502J0D01*
G03X122672Y1363714I88J-180D01*
G02X122674Y1363643I-1465J-77D01*
G02X119740I-1467J0D01*
G02X119743Y1363743I1467J6D01*
G03X119635Y1363934I-199J13D01*
G02X117738Y1367047I1606J3113D01*
G02X118018Y1368419I3503J0D01*
G03X118019Y1368575I-184J79D01*
G02X117781Y1369405I3222J1373D01*
G02X117754Y1369404I-142J3463D01*
G01X117748D01*
G02X116602Y1369600I3J3468D01*
G03X116470I-66J-189D01*
G02X115321Y1369404I-1149J3272D01*
G02Y1376340I0J3468D01*
G02X116470Y1376144I0J-3468D01*
G03X116602I66J189D01*
G02X117751Y1376340I1149J-3272D01*
G02X118900Y1376144I0J-3468D01*
G03X119032I66J189D01*
G02X119443Y1376260I1146J-3273D01*
G02X119442Y1376305I3501J100D01*
G01Y1376309D01*
G02X119722Y1377679I3503J-2D01*
G03Y1377835I-184J78D01*
G37*
G36*
G01X152322D02*
G02X152042Y1379207I3223J1372D01*
G02X155545Y1382710I3503J0D01*
G02X157716Y1381955I-1J-3503D01*
G03X157947Y1381943I124J157D01*
G02X159811Y1382480I1864J-2967D01*
G02X163314Y1378977I0J-3503D01*
G02X163034Y1377605I-3503J0D01*
G03Y1377449I184J-78D01*
G02X163314Y1376077I-3223J-1372D01*
G02X163034Y1374705I-3503J0D01*
G03Y1374549I184J-78D01*
G02X163314Y1373177I-3223J-1372D01*
G02X159811Y1369674I-3503J0D01*
G02X157865Y1370265I1J3503D01*
G01X157819Y1370295D01*
X157709Y1370301D01*
X157350Y1370111D01*
G03X157243Y1369938I93J-177D01*
G01Y1369937D01*
G02X156963Y1368605I-3502J41D01*
G03X156964Y1368449I185J-77D01*
G02X157244Y1367077I-3223J-1372D01*
G02X150238I-3503J0D01*
G02X150518Y1368449I3503J0D01*
G03X150519Y1368605I-184J79D01*
G02X150315Y1369253I3223J1371D01*
G03X150132Y1369411I-196J-42D01*
G02X149202Y1369600I219J3461D01*
G03X149070I-66J-189D01*
G02X147921Y1369404I-1149J3272D01*
G02Y1376340I0J3468D01*
G02X149070Y1376144I0J-3468D01*
G03X149202I66J189D01*
G02X150351Y1376340I1149J-3272D01*
G02X151500Y1376144I0J-3468D01*
G03X151632I66J189D01*
G02X152043Y1376260I1146J-3273D01*
G02X152042Y1376305I3501J100D01*
G01Y1376309D01*
G02X152322Y1377679I3503J-2D01*
G03Y1377835I-184J78D01*
G37*
G36*
G01X185022D02*
G02X184742Y1379207I3223J1372D01*
G02X188245Y1382710I3503J0D01*
G02X190416Y1381955I-1J-3503D01*
G03X190647Y1381943I124J157D01*
G02X192511Y1382480I1864J-2967D01*
G02X196014Y1378977I0J-3503D01*
G02X195734Y1377605I-3503J0D01*
G03Y1377449I184J-78D01*
G02X196014Y1376077I-3223J-1372D01*
G02X195734Y1374705I-3503J0D01*
G03Y1374549I184J-78D01*
G02X196014Y1373177I-3223J-1372D01*
G02X192511Y1369674I-3503J0D01*
G02X190595Y1370245I1J3503D01*
G01X190550Y1370275D01*
X190445Y1370281D01*
X190087Y1370101D01*
G03X189977Y1369934I90J-179D01*
G02X189704Y1368775I-3496J212D01*
G03Y1368619I184J-78D01*
G02X189984Y1367247I-3223J-1372D01*
G02X182978I-3503J0D01*
G02X183258Y1368619I3503J0D01*
G03Y1368775I-184J78D01*
G02X183058Y1369405I3224J1370D01*
G02X183051Y1369404I-489J3398D01*
G02X181902Y1369600I0J3468D01*
G03X181770I-66J-189D01*
G02X180621Y1369404I-1149J3272D01*
G02Y1376340I0J3468D01*
G02X181770Y1376144I0J-3468D01*
G03X181902I66J189D01*
G02X183051Y1376340I1149J-3272D01*
G02X184200Y1376144I0J-3468D01*
G03X184332I66J189D01*
G02X184743Y1376260I1146J-3273D01*
G02X184742Y1376305I3501J100D01*
G01Y1376309D01*
G02X185022Y1377679I3503J-2D01*
G03Y1377835I-184J78D01*
G37*
G36*
G01X217922D02*
G02X217642Y1379207I3223J1372D01*
G02X221145Y1382710I3503J0D01*
G02X223316Y1381955I-1J-3503D01*
G03X223547Y1381943I124J157D01*
G02X225411Y1382480I1864J-2967D01*
G02X228914Y1378977I0J-3503D01*
G02X228634Y1377605I-3503J0D01*
G03Y1377449I184J-78D01*
G02X228914Y1376077I-3223J-1372D01*
G02X228634Y1374705I-3503J0D01*
G03Y1374549I184J-78D01*
G02X228914Y1373177I-3223J-1372D01*
G02X225411Y1369674I-3503J0D01*
G02X223516Y1370231I0J3502D01*
G01X223471Y1370260D01*
X223364Y1370266D01*
X222960Y1370056D01*
X222902Y1369966D01*
X222900Y1369913D01*
G02X222624Y1368695I-3499J153D01*
G03Y1368539I184J-78D01*
G02X222904Y1367167I-3223J-1372D01*
G02X215898I-3503J0D01*
G02X216178Y1368539I3503J0D01*
G03X216179Y1368695I-184J79D01*
G02X215962Y1369405I3222J1373D01*
G01X215960D01*
G02X215942Y1369404I-20J199D01*
G02X214802Y1369600I9J3468D01*
G03X214670I-66J-189D01*
G02X213521Y1369404I-1149J3272D01*
G02Y1376340I0J3468D01*
G02X214670Y1376144I0J-3468D01*
G03X214802I66J189D01*
G02X215951Y1376340I1149J-3272D01*
G02X217100Y1376144I0J-3468D01*
G03X217232I66J189D01*
G02X217643Y1376260I1146J-3273D01*
G02X217642Y1376305I3501J100D01*
G01Y1376309D01*
G02X217922Y1377679I3503J-2D01*
G03Y1377835I-184J78D01*
G37*
G36*
G01X250722D02*
G02X250442Y1379207I3223J1372D01*
G02X253945Y1382710I3503J0D01*
G02X256116Y1381955I-1J-3503D01*
G03X256347Y1381943I124J157D01*
G02X258211Y1382480I1864J-2967D01*
G02X261714Y1378977I0J-3503D01*
G02X261434Y1377605I-3503J0D01*
G03Y1377449I184J-78D01*
G02X261714Y1376077I-3223J-1372D01*
G02X261434Y1374705I-3503J0D01*
G03Y1374549I184J-78D01*
G02X261714Y1373177I-3223J-1372D01*
G02X258211Y1369674I-3503J0D01*
G02X256286Y1370251I1J3503D01*
G01X256285Y1370252D01*
G03X256088Y1370264I-109J-168D01*
G01X255731Y1370090D01*
X255671Y1370002D01*
X255667Y1369950D01*
G02X255396Y1368861I-3456J282D01*
G03Y1368703I184J-79D01*
G02X255678Y1367335I-3185J-1370D01*
G01Y1367332D01*
G02X248744I-3467J0D01*
G01Y1367335D01*
G02X249026Y1368703I3467J-2D01*
G03Y1368861I-184J79D01*
G02X248843Y1369406I3184J1372D01*
G02X248752Y1369404I-122J3465D01*
G01X248750D01*
G02X247602Y1369600I1J3468D01*
G03X247470I-66J-189D01*
G02X246321Y1369404I-1149J3272D01*
G02Y1376340I0J3468D01*
G02X247470Y1376144I0J-3468D01*
G03X247602I66J189D01*
G02X248751Y1376340I1149J-3272D01*
G02X249900Y1376144I0J-3468D01*
G03X250032I66J189D01*
G02X250443Y1376260I1146J-3273D01*
G02X250442Y1376305I3501J100D01*
G01Y1376309D01*
G02X250722Y1377679I3503J-2D01*
G03Y1377835I-184J78D01*
G37*
G36*
G01X320560Y1377966D02*
G02X320206Y1379500I3149J1535D01*
G02X327212I3503J0D01*
G01Y1379499D01*
G02X326859Y1377967I-3504J1D01*
G03Y1377793I180J-87D01*
G02X327212Y1376259I-3149J-1532D01*
G02X326905Y1374824I-3502J-1D01*
G03X326897Y1374681I183J-82D01*
G02X327062Y1373620I-3338J-1062D01*
G02X326886Y1372524I-3503J0D01*
G03X326896Y1372373I190J-63D01*
G02X327254Y1370831I-3145J-1543D01*
G02X320248I-3503J0D01*
G02X320424Y1371927I3503J0D01*
G03X320414Y1372078I-190J63D01*
G02X320056Y1373620I3145J1543D01*
G02X320364Y1375055I3503J-1D01*
G03X320372Y1375198I-183J82D01*
G02X320208Y1376259I3338J1059D01*
G02X320560Y1377791I3502J2D01*
G03Y1377966I-180J88D01*
G37*
G36*
G01X301918Y1388359D02*
G02X301660Y1389678I3245J1319D01*
G02X308666I3503J0D01*
G02X308408Y1388359I-3503J0D01*
G03Y1388209I185J-75D01*
G02X308666Y1386890I-3245J-1319D01*
G01Y1386889D01*
G02X308358Y1385454I-3503J1D01*
G03X308350Y1385311I183J-82D01*
G02X308514Y1384250I-3338J-1059D01*
G02X308338Y1383153I-3502J-1D01*
G03X308349Y1383003I190J-61D01*
G02X308706Y1381463I-3145J-1541D01*
G01Y1381461D01*
G02X301702I-3502J0D01*
G01Y1381465D01*
G02X301878Y1382558I3502J-3D01*
G03X301867Y1382708I-190J61D01*
G02X301510Y1384250I3145J1541D01*
G02X301817Y1385685I3502J1D01*
G03X301825Y1385828I-183J82D01*
G02X301660Y1386889I3338J1062D01*
G01Y1386890D01*
G02X301918Y1388209I3503J0D01*
G03Y1388359I-185J75D01*
G37*
G36*
G01X1345029Y1393101D02*
G02X1346212Y1393306I1181J-3297D01*
G02X1347395Y1393101I2J-3502D01*
G03X1347529I67J188D01*
G02X1348707Y1393306I1181J-3297D01*
G01X1348712D01*
G02X1350387Y1392879I-1J-3502D01*
G03X1350577I95J176D01*
G02X1352225Y1393290I1646J-3091D01*
G02X1355728Y1389788I1J-3502D01*
G02X1355431Y1388378I-3503J2D01*
G03Y1388216I183J-81D01*
G02X1355728Y1386804I-3205J-1411D01*
G02X1355428Y1385385I-3502J-1D01*
G03Y1385223I183J-81D01*
G02X1355728Y1383806I-3202J-1418D01*
G01Y1383804D01*
G02X1352226Y1380302I-3502J0D01*
G01X1352221D01*
G02X1351121Y1380480I2J3502D01*
G03X1350977Y1380473I-63J-190D01*
G02X1349557Y1380172I-1420J3201D01*
G01X1349555D01*
G02X1348137Y1380472I0J3502D01*
G03X1347975I-81J-183D01*
G02X1346557Y1380172I-1418J3202D01*
G01X1346555D01*
G02X1345137Y1380472I0J3502D01*
G03X1344975I-81J-183D01*
G02X1343557Y1380172I-1418J3202D01*
G01X1343555D01*
G02X1342137Y1380472I0J3502D01*
G03X1341975I-81J-183D01*
G02X1340557Y1380172I-1418J3202D01*
G01X1340555D01*
G02X1339137Y1380472I0J3502D01*
G03X1338975I-81J-183D01*
G02X1337558Y1380172I-1418J3202D01*
G01X1337556D01*
G02X1334054Y1383674I0J3502D01*
G01Y1383676D01*
G02X1334354Y1385093I3502J-1D01*
G03Y1385255I-183J81D01*
G02X1334054Y1386674I3202J1418D01*
G02X1334350Y1388084I3502J1D01*
G03Y1388246I-183J81D01*
G02X1334052Y1389658I3205J1414D01*
G02X1337555Y1393160I3503J-1D01*
G01X1337556D01*
G02X1339163Y1392769I-1J-3502D01*
G03X1339360Y1392777I91J178D01*
G02X1341212Y1393306I1851J-2973D01*
G02X1342395Y1393101I2J-3502D01*
G03X1342529I67J188D01*
G02X1343712Y1393306I1181J-3297D01*
G02X1344895Y1393101I2J-3502D01*
G03X1345029I67J188D01*
G37*
G36*
G01X291534Y1388747D02*
G02X291180Y1390281I3149J1535D01*
G02X298186I3503J0D01*
G01Y1390280D01*
G02X297833Y1388748I-3504J1D01*
G03Y1388574I180J-87D01*
G02X298186Y1387040I-3149J-1532D01*
G02X297879Y1385605I-3502J-1D01*
G03X297871Y1385462I183J-82D01*
G02X298036Y1384401I-3338J-1062D01*
G02X297860Y1383305I-3503J0D01*
G03X297870Y1383154I190J-63D01*
G02X298228Y1381612I-3145J-1543D01*
G02X291222I-3503J0D01*
G02X291398Y1382708I3503J0D01*
G03X291388Y1382859I-190J63D01*
G02X291030Y1384401I3145J1543D01*
G02X291338Y1385836I3503J-1D01*
G03X291346Y1385979I-183J82D01*
G02X291182Y1387040I3338J1059D01*
G02X291534Y1388572I3502J2D01*
G03Y1388747I-180J88D01*
G37*
G36*
G01X1674732Y1396505D02*
Y1396507D01*
G02X1678234Y1400008I3502J-1D01*
G02X1680405Y1399253I-1J-3503D01*
G03X1680636Y1399241I124J157D01*
G02X1682500Y1399778I1864J-2967D01*
G02X1686002Y1396275I-1J-3503D01*
G01Y1396274D01*
G02X1685722Y1394903I-3502J1D01*
G03Y1394747I184J-78D01*
G02X1686002Y1393375I-3222J-1372D01*
G02X1685722Y1392003I-3502J0D01*
G03Y1391847I184J-78D01*
G02X1686002Y1390475I-3222J-1372D01*
G01Y1390473D01*
G02X1682500Y1386972I-3502J1D01*
G02X1679699Y1388372I0J3502D01*
G03X1679581Y1388447I-159J-121D01*
G02X1679532Y1388458I743J3423D01*
G01X1679373Y1388289D01*
G03X1679325Y1388102I146J-137D01*
G02X1679434Y1387235I-3394J-867D01*
G02X1679154Y1385863I-3503J0D01*
G03Y1385707I184J-78D01*
G02X1679434Y1384335I-3223J-1372D01*
G02X1672428I-3503J0D01*
G02X1672708Y1385707I3503J0D01*
G03Y1385863I-184J78D01*
G02X1672484Y1386616I3224J1369D01*
G03X1672328Y1386776I-197J-36D01*
G02X1671891Y1386898I712J3394D01*
G03X1671759I-66J-189D01*
G02X1670610Y1386702I-1149J3272D01*
G02Y1393638I0J3468D01*
G02X1671759Y1393442I0J-3468D01*
G03X1671891I66J189D01*
G02X1673040Y1393638I1149J-3272D01*
G02X1674189Y1393442I0J-3468D01*
G03X1674321I66J189D01*
G02X1674732Y1393558I1146J-3273D01*
G01Y1393605D01*
G02X1675012Y1394977I3502J0D01*
G03Y1395133I-184J78D01*
G02X1674732Y1396505I3222J1372D01*
G37*
G36*
G01X1707514Y1396605D02*
Y1396607D01*
G02X1711016Y1400108I3502J-1D01*
G02X1713187Y1399353I-1J-3503D01*
G03X1713418Y1399341I124J157D01*
G02X1715282Y1399878I1864J-2967D01*
G02X1718784Y1396375I-1J-3503D01*
G01Y1396374D01*
G02X1718504Y1395003I-3502J1D01*
G03Y1394847I184J-78D01*
G02X1718784Y1393475I-3222J-1372D01*
G02X1718504Y1392103I-3502J0D01*
G03Y1391947I184J-78D01*
G02X1718784Y1390575I-3222J-1372D01*
G01Y1390573D01*
G02X1715282Y1387072I-3502J1D01*
G02X1712481Y1388472I0J3502D01*
G03X1712363Y1388547I-159J-121D01*
G02X1712314Y1388558I743J3423D01*
G01X1712155Y1388389D01*
G03X1712107Y1388202I146J-137D01*
G02X1712216Y1387335I-3394J-867D01*
G02X1711936Y1385963I-3503J0D01*
G03Y1385807I184J-78D01*
G02X1712216Y1384435I-3223J-1372D01*
G02X1705210I-3503J0D01*
G02X1705490Y1385807I3503J0D01*
G03Y1385963I-184J78D01*
G02X1705266Y1386716I3224J1369D01*
G03X1705110Y1386876I-197J-36D01*
G02X1704673Y1386998I712J3394D01*
G03X1704541I-66J-189D01*
G02X1703392Y1386802I-1149J3272D01*
G02Y1393738I0J3468D01*
G02X1704541Y1393542I0J-3468D01*
G03X1704673I66J189D01*
G02X1705822Y1393738I1149J-3272D01*
G02X1706971Y1393542I0J-3468D01*
G03X1707103I66J189D01*
G02X1707514Y1393658I1146J-3273D01*
G01Y1393705D01*
G02X1707794Y1395077I3502J0D01*
G03Y1395233I-184J78D01*
G02X1707514Y1396605I3222J1372D01*
G37*
G36*
G01X726998Y1397216D02*
G02X730501Y1400718I3503J-1D01*
G01X730502D01*
G02X732672Y1399964I-1J-3502D01*
G03X732903Y1399952I124J157D01*
G02X734767Y1400488I1862J-2967D01*
G02X738270Y1396986I1J-3502D01*
G02X737990Y1395614I-3503J0D01*
G03Y1395458I184J-78D01*
G02X738270Y1394086I-3223J-1372D01*
G02X737990Y1392714I-3503J0D01*
G03Y1392558I184J-78D01*
G02X738270Y1391186I-3223J-1372D01*
G02X734767Y1387684I-3503J1D01*
G02X731966Y1389083I0J3504D01*
G03X731849Y1389158I-160J-120D01*
G02X731821Y1389164I720J3428D01*
G01X731661Y1388997D01*
G03X731611Y1388814I145J-138D01*
G02X731700Y1388026I-3413J-785D01*
G02X731420Y1386654I-3502J0D01*
G03Y1386498I184J-78D01*
G02X731700Y1385127I-3222J-1372D01*
G01Y1385126D01*
G02X724696I-3502J0D01*
G01Y1385127D01*
G02X724976Y1386498I3502J-1D01*
G03Y1386654I-184J78D01*
G02X724766Y1387328I3222J1373D01*
G03X724610Y1387484I-196J-40D01*
G02X724158Y1387609I696J3397D01*
G03X724026I-66J-189D01*
G02X722881Y1387414I-1146J3272D01*
G01X722877D01*
G02Y1394348I0J3467D01*
G01X722881D01*
G02X724026Y1394153I-1J-3467D01*
G03X724158I66J189D01*
G02X725307Y1394348I1146J-3272D01*
G02X726456Y1394153I3J-3467D01*
G03X726588I66J189D01*
G02X726999Y1394269I1146J-3273D01*
G02X726998Y1394314I3501J100D01*
G01Y1394318D01*
G02X727278Y1395688I3503J-2D01*
G03Y1395844I-184J78D01*
G02X726998Y1397216I3223J1372D01*
G37*
G36*
G01X759780Y1397316D02*
G02X763283Y1400818I3503J-1D01*
G01X763284D01*
G02X765454Y1400064I-1J-3502D01*
G03X765685Y1400052I124J157D01*
G02X767549Y1400588I1862J-2967D01*
G02X771052Y1397086I1J-3502D01*
G02X770772Y1395714I-3503J0D01*
G03Y1395558I184J-78D01*
G02X771052Y1394186I-3223J-1372D01*
G02X770772Y1392814I-3503J0D01*
G03Y1392658I184J-78D01*
G02X771052Y1391286I-3223J-1372D01*
G02X767549Y1387784I-3503J1D01*
G02X764748Y1389183I0J3504D01*
G03X764631Y1389258I-160J-120D01*
G02X764581Y1389269I728J3426D01*
G01X764422Y1389099D01*
G03X764373Y1388913I145J-138D01*
G02X764482Y1388046I-3393J-867D01*
G02X764202Y1386674I-3502J0D01*
G03Y1386518I184J-78D01*
G02X764482Y1385147I-3222J-1372D01*
G01Y1385146D01*
G02X757478I-3502J0D01*
G01Y1385147D01*
G02X757758Y1386518I3502J-1D01*
G03X757757Y1386674I-185J77D01*
G02X757533Y1387427I3224J1369D01*
G03X757377Y1387587I-197J-36D01*
G02X756940Y1387709I712J3394D01*
G03X756808I-66J-189D01*
G02X755663Y1387514I-1146J3272D01*
G01X755659D01*
G02Y1394448I0J3467D01*
G01X755663D01*
G02X756808Y1394253I-1J-3467D01*
G03X756940I66J189D01*
G02X758089Y1394448I1146J-3272D01*
G02X759238Y1394253I3J-3467D01*
G03X759370I66J189D01*
G02X759781Y1394369I1146J-3273D01*
G02X759780Y1394414I3501J100D01*
G01Y1394418D01*
G02X760060Y1395788I3503J-2D01*
G03Y1395944I-184J78D01*
G02X759780Y1397316I3223J1372D01*
G37*
G36*
G01X1136147Y1407174D02*
G03X1136283I68J188D01*
G02X1137465Y1407380I1184J-3297D01*
G02X1140968Y1403877I0J-3503D01*
G02X1140762Y1402695I-3503J2D01*
G03Y1402559I188J-68D01*
G02X1140968Y1401377I-3297J-1184D01*
G02X1140718Y1400079I-3503J2D01*
G03X1140716Y1399936I186J-74D01*
G02X1140928Y1398737I-3291J-1200D01*
G02X1137425Y1395234I-3503J0D01*
G02X1136243Y1395440I2J3503D01*
G03X1136107I-68J-188D01*
G02X1134925Y1395234I-1184J3297D01*
G02X1133743Y1395440I2J3503D01*
G03X1133607I-68J-188D01*
G02X1132425Y1395234I-1184J3297D01*
G02X1131243Y1395440I2J3503D01*
G03X1131107I-68J-188D01*
G02X1129925Y1395234I-1184J3297D01*
G02X1128743Y1395440I2J3503D01*
G03X1128607I-68J-188D01*
G02X1127425Y1395234I-1184J3297D01*
G02X1123922Y1398737I0J3503D01*
G02X1124172Y1400035I3503J-2D01*
G03X1124174Y1400178I-186J74D01*
G02X1123962Y1401377I3291J1200D01*
G02X1124168Y1402559I3503J-2D01*
G03Y1402695I-188J68D01*
G02X1123962Y1403877I3297J1184D01*
G02X1127465Y1407380I3503J0D01*
G02X1128647Y1407174I-2J-3503D01*
G03X1128783I68J188D01*
G02X1129965Y1407380I1184J-3297D01*
G02X1131147Y1407174I-2J-3503D01*
G03X1131283I68J188D01*
G02X1132465Y1407380I1184J-3297D01*
G02X1133647Y1407174I-2J-3503D01*
G03X1133783I68J188D01*
G02X1134965Y1407380I1184J-3297D01*
G02X1136147Y1407174I-2J-3503D01*
G37*
G36*
G01X197990Y1413173D02*
G03X198124I67J188D01*
G02X199307Y1413378I1181J-3297D01*
G02X202810Y1409876I1J-3502D01*
G02X202672Y1408904I-3503J2D01*
G03X202683Y1408766I192J-54D01*
G02X202998Y1407315I-3188J-1452D01*
G01Y1407313D01*
G02X202792Y1406131I-3503J2D01*
G03Y1405995I188J-68D01*
G02X202998Y1404813I-3297J-1184D01*
G02X199495Y1401310I-3503J0D01*
G02X198313Y1401516I2J3503D01*
G03X198177I-68J-188D01*
G02X196995Y1401310I-1184J3297D01*
G02X195813Y1401516I2J3503D01*
G03X195677I-68J-188D01*
G02X194495Y1401310I-1184J3297D01*
G02X193313Y1401516I2J3503D01*
G03X193177I-68J-188D01*
G02X191995Y1401310I-1184J3297D01*
G02X190434Y1401678I2J3503D01*
G03X190256I-89J-179D01*
G02X188695Y1401310I-1563J3135D01*
G02X185192Y1404813I0J3503D01*
G02X185398Y1405995I3503J-2D01*
G03Y1406131I-188J68D01*
G02X185192Y1407313I3297J1184D01*
G02X185330Y1408285I3503J-2D01*
G03X185319Y1408423I-192J54D01*
G02X185004Y1409874I3188J1452D01*
G01Y1409876D01*
G02X188507Y1413378I3503J-1D01*
G02X190068Y1413011I0J-3503D01*
G03X190246I89J179D01*
G02X191807Y1413378I1561J-3136D01*
G01X191810D01*
G02X192990Y1413173I-1J-3502D01*
G03X193124I67J188D01*
G02X194307Y1413378I1181J-3297D01*
G02X195490Y1413173I2J-3502D01*
G03X195624I67J188D01*
G02X196807Y1413378I1181J-3297D01*
G02X197990Y1413173I2J-3502D01*
G37*
G36*
G01X169700Y1414247D02*
Y1414249D01*
G02X176704I3502J0D01*
G01Y1414248D01*
G02X176327Y1412668I-3502J1D01*
G03X176315Y1412517I178J-90D01*
G02X176478Y1411460I-3340J-1056D01*
G02X176341Y1410488I-3502J-2D01*
G03X176351Y1410350I192J-55D01*
G02X176666Y1408897I-3187J-1452D01*
G02X176461Y1407714I-3502J-2D01*
G03Y1407580I188J-67D01*
G02X176666Y1406400I-3297J-1181D01*
G01Y1406397D01*
G02X169662I-3502J0D01*
G01Y1406400D01*
G02X169867Y1407580I3502J-1D01*
G03Y1407714I-188J67D01*
G02X169662Y1408897I3297J1181D01*
G02X169799Y1409869I3502J2D01*
G03X169789Y1410007I-192J55D01*
G02X169474Y1411460I3187J1452D01*
G02X169851Y1413041I3502J0D01*
G03X169863Y1413192I-178J90D01*
G02X169700Y1414247I3340J1056D01*
G37*
G36*
G01X159760Y1413343D02*
G02X159596Y1414400I3339J1059D01*
G02X166602I3503J0D01*
G02X166224Y1412819I-3503J2D01*
G03X166212Y1412668I178J-90D01*
G02X166376Y1411611I-3339J-1059D01*
G02X166238Y1410639I-3503J2D01*
G03X166249Y1410501I192J-54D01*
G02X166564Y1409050I-3188J-1452D01*
G01Y1409048D01*
G02X166358Y1407866I-3503J2D01*
G03Y1407730I188J-68D01*
G02X166564Y1406548I-3297J-1184D01*
G02X159558I-3503J0D01*
G02X159764Y1407730I3503J-2D01*
G03Y1407866I-188J68D01*
G02X159558Y1409048I3297J1184D01*
G02X159696Y1410020I3503J-2D01*
G03X159685Y1410158I-192J54D01*
G02X159370Y1411609I3188J1452D01*
G01Y1411611D01*
G02X159748Y1413192I3503J-2D01*
G03X159760Y1413343I-178J90D01*
G37*
G36*
G01X1715866Y1426415D02*
G03X1716028I81J183D01*
G02X1717447Y1426716I1421J-3202D01*
G02X1720950Y1423213I0J-3503D01*
G02X1720649Y1421794I-3503J2D01*
G03Y1421632I183J-81D01*
G02X1720950Y1420213I-3202J-1421D01*
G02X1720649Y1418794I-3503J2D01*
G03Y1418632I183J-81D01*
G02X1720950Y1417213I-3202J-1421D01*
G02X1717447Y1413710I-3503J0D01*
G02X1716028Y1414011I2J3503D01*
G03X1715866I-81J-183D01*
G02X1714447Y1413710I-1421J3202D01*
G02X1710944Y1417213I0J3503D01*
G02X1711245Y1418632I3503J-2D01*
G03Y1418794I-183J81D01*
G02X1710944Y1420213I3202J1421D01*
G02X1711245Y1421632I3503J-2D01*
G03Y1421794I-183J81D01*
G02X1710944Y1423213I3202J1421D01*
G02X1714447Y1426716I3503J0D01*
G02X1715866Y1426415I-2J-3503D01*
G37*
G36*
G01X733999Y1429324D02*
G02X735416Y1429624I1418J-3202D01*
G01X735418D01*
G02X738920Y1426122I0J-3502D01*
G01Y1426120D01*
G02X738620Y1424703I-3502J1D01*
G03Y1424541I183J-81D01*
G02X738920Y1423122I-3202J-1418D01*
G02X738620Y1421703I-3502J-1D01*
G03Y1421541I183J-81D01*
G02X738920Y1420124I-3202J-1418D01*
G01Y1420122D01*
G02X735418Y1416620I-3502J0D01*
G01X735416D01*
G02X733999Y1416920I1J3502D01*
G03X733837I-81J-183D01*
G02X732420Y1416620I-1418J3202D01*
G01X732418D01*
G02X728916Y1420122I0J3502D01*
G01Y1420124D01*
G02X729216Y1421541I3502J-1D01*
G03Y1421703I-183J81D01*
G02X728916Y1423122I3202J1418D01*
G02X729216Y1424541I3502J1D01*
G03Y1424703I-183J81D01*
G02X728916Y1426120I3202J1418D01*
G01Y1426122D01*
G02X732418Y1429624I3502J0D01*
G01X732420D01*
G02X733837Y1429324I-1J-3502D01*
G03X733999I81J183D01*
G37*
G36*
G01X176051Y1451392D02*
G02Y1454398I0J1503D01*
G01X179451D01*
G02Y1451392I0J-1503D01*
G01X176051D01*
G37*
G36*
G01X202851D02*
G02Y1454398I0J1503D01*
G01X206251D01*
G02Y1451392I0J-1503D01*
G01X202851D01*
G37*
G36*
G01X229651D02*
G02Y1454398I0J1503D01*
G01X233051D01*
G02Y1451392I0J-1503D01*
G01X229651D01*
G37*
G36*
G01X256451D02*
G02Y1454398I0J1503D01*
G01X259851D01*
G02Y1451392I0J-1503D01*
G01X256451D01*
G37*
G36*
G01X269851D02*
G02Y1454398I0J1503D01*
G01X273251D01*
G02Y1451392I0J-1503D01*
G01X269851D01*
G37*
G36*
G01X304113D02*
G02Y1454398I0J1503D01*
G01X307513D01*
G02Y1451392I0J-1503D01*
G01X304113D01*
G37*
G36*
G01X330913D02*
G02Y1454398I0J1503D01*
G01X334313D01*
G02Y1451392I0J-1503D01*
G01X330913D01*
G37*
G36*
G01X357713D02*
G02Y1454398I0J1503D01*
G01X361113D01*
G02Y1451392I0J-1503D01*
G01X357713D01*
G37*
G36*
G01X384513D02*
G02Y1454398I0J1503D01*
G01X387913D01*
G02Y1451392I0J-1503D01*
G01X384513D01*
G37*
G36*
G01X397913D02*
G02Y1454398I0J1503D01*
G01X401313D01*
G02Y1451392I0J-1503D01*
G01X397913D01*
G37*
G36*
G01X440224D02*
G02Y1454398I0J1503D01*
G01X443624D01*
G02Y1451392I0J-1503D01*
G01X440224D01*
G37*
G36*
G01X467024D02*
G02Y1454398I0J1503D01*
G01X470424D01*
G02Y1451392I0J-1503D01*
G01X467024D01*
G37*
G36*
G01X493824D02*
G02Y1454398I0J1503D01*
G01X497224D01*
G02Y1451392I0J-1503D01*
G01X493824D01*
G37*
G36*
G01X520624D02*
G02Y1454398I0J1503D01*
G01X524024D01*
G02Y1451392I0J-1503D01*
G01X520624D01*
G37*
G36*
G01X534024D02*
G02Y1454398I0J1503D01*
G01X537424D01*
G02Y1451392I0J-1503D01*
G01X534024D01*
G37*
G36*
G01X568286D02*
G02Y1454398I0J1503D01*
G01X571686D01*
G02Y1451392I0J-1503D01*
G01X568286D01*
G37*
G36*
G01X595086D02*
G02Y1454398I0J1503D01*
G01X598486D01*
G02Y1451392I0J-1503D01*
G01X595086D01*
G37*
G36*
G01X621886D02*
G02Y1454398I0J1503D01*
G01X625286D01*
G02Y1451392I0J-1503D01*
G01X621886D01*
G37*
G36*
G01X648686D02*
G02Y1454398I0J1503D01*
G01X652086D01*
G02Y1451392I0J-1503D01*
G01X648686D01*
G37*
G36*
G01X662086D02*
G02Y1454398I0J1503D01*
G01X665486D01*
G02Y1451392I0J-1503D01*
G01X662086D01*
G37*
G36*
G01X691276Y1453610D02*
G02Y1456614I0J1502D01*
G01X694676D01*
G02Y1453610I0J-1502D01*
G01X691276D01*
G37*
G36*
G01X169351Y1461092D02*
G02Y1464098I0J1503D01*
G01X172751D01*
G02Y1461092I0J-1503D01*
G01X169351D01*
G37*
G36*
G01X196151D02*
G02Y1464098I0J1503D01*
G01X199551D01*
G02Y1461092I0J-1503D01*
G01X196151D01*
G37*
G36*
G01X222951D02*
G02Y1464098I0J1503D01*
G01X226351D01*
G02Y1461092I0J-1503D01*
G01X222951D01*
G37*
G36*
G01X249751D02*
G02Y1464098I0J1503D01*
G01X253151D01*
G02Y1461092I0J-1503D01*
G01X249751D01*
G37*
G36*
G01X297413D02*
G02Y1464098I0J1503D01*
G01X300813D01*
G02Y1461092I0J-1503D01*
G01X297413D01*
G37*
G36*
G01X324213D02*
G02Y1464098I0J1503D01*
G01X327613D01*
G02Y1461092I0J-1503D01*
G01X324213D01*
G37*
G36*
G01X351013D02*
G02Y1464098I0J1503D01*
G01X354413D01*
G02Y1461092I0J-1503D01*
G01X351013D01*
G37*
G36*
G01X377813D02*
G02Y1464098I0J1503D01*
G01X381213D01*
G02Y1461092I0J-1503D01*
G01X377813D01*
G37*
G36*
G01X433524D02*
G02Y1464098I0J1503D01*
G01X436924D01*
G02Y1461092I0J-1503D01*
G01X433524D01*
G37*
G36*
G01X460324D02*
G02Y1464098I0J1503D01*
G01X463724D01*
G02Y1461092I0J-1503D01*
G01X460324D01*
G37*
G36*
G01X487124D02*
G02Y1464098I0J1503D01*
G01X490524D01*
G02Y1461092I0J-1503D01*
G01X487124D01*
G37*
G36*
G01X513924D02*
G02Y1464098I0J1503D01*
G01X517324D01*
G02Y1461092I0J-1503D01*
G01X513924D01*
G37*
G36*
G01X561586D02*
G02Y1464098I0J1503D01*
G01X564986D01*
G02Y1461092I0J-1503D01*
G01X561586D01*
G37*
G36*
G01X588386D02*
G02Y1464098I0J1503D01*
G01X591786D01*
G02Y1461092I0J-1503D01*
G01X588386D01*
G37*
G36*
G01X615186D02*
G02Y1464098I0J1503D01*
G01X618586D01*
G02Y1461092I0J-1503D01*
G01X615186D01*
G37*
G36*
G01X641986D02*
G02Y1464098I0J1503D01*
G01X645386D01*
G02Y1461092I0J-1503D01*
G01X641986D01*
G37*
G36*
G01X189451Y1470792D02*
G02Y1473798I0J1503D01*
G01X192851D01*
G02Y1470792I0J-1503D01*
G01X189451D01*
G37*
G36*
G01X216251D02*
G02Y1473798I0J1503D01*
G01X219651D01*
G02Y1470792I0J-1503D01*
G01X216251D01*
G37*
G36*
G01X243051D02*
G02Y1473798I0J1503D01*
G01X246451D01*
G02Y1470792I0J-1503D01*
G01X243051D01*
G37*
G36*
G01X317513D02*
G02Y1473798I0J1503D01*
G01X320913D01*
G02Y1470792I0J-1503D01*
G01X317513D01*
G37*
G36*
G01X344313D02*
G02Y1473798I0J1503D01*
G01X347713D01*
G02Y1470792I0J-1503D01*
G01X344313D01*
G37*
G36*
G01X371113D02*
G02Y1473798I0J1503D01*
G01X374513D01*
G02Y1470792I0J-1503D01*
G01X371113D01*
G37*
G36*
G01X453624D02*
G02Y1473798I0J1503D01*
G01X457024D01*
G02Y1470792I0J-1503D01*
G01X453624D01*
G37*
G36*
G01X480424D02*
G02Y1473798I0J1503D01*
G01X483824D01*
G02Y1470792I0J-1503D01*
G01X480424D01*
G37*
G36*
G01X507224D02*
G02Y1473798I0J1503D01*
G01X510624D01*
G02Y1470792I0J-1503D01*
G01X507224D01*
G37*
G36*
G01X581686D02*
G02Y1473798I0J1503D01*
G01X585086D01*
G02Y1470792I0J-1503D01*
G01X581686D01*
G37*
G36*
G01X608486D02*
G02Y1473798I0J1503D01*
G01X611886D01*
G02Y1470792I0J-1503D01*
G01X608486D01*
G37*
G36*
G01X635286D02*
G02Y1473798I0J1503D01*
G01X638686D01*
G02Y1470792I0J-1503D01*
G01X635286D01*
G37*
G36*
G01X1183924Y1484392D02*
G02Y1487398I0J1503D01*
G01X1187324D01*
G02Y1484392I0J-1503D01*
G01X1183924D01*
G37*
G36*
G01X1210724D02*
G02Y1487398I0J1503D01*
G01X1214124D01*
G02Y1484392I0J-1503D01*
G01X1210724D01*
G37*
G36*
G01X1237524D02*
G02Y1487398I0J1503D01*
G01X1240924D01*
G02Y1484392I0J-1503D01*
G01X1237524D01*
G37*
G36*
G01X1264324D02*
G02Y1487398I0J1503D01*
G01X1267724D01*
G02Y1484392I0J-1503D01*
G01X1264324D01*
G37*
G36*
G01X1277724D02*
G02Y1487398I0J1503D01*
G01X1281124D01*
G02Y1484392I0J-1503D01*
G01X1277724D01*
G37*
G36*
G01X1311986D02*
G02Y1487398I0J1503D01*
G01X1315386D01*
G02Y1484392I0J-1503D01*
G01X1311986D01*
G37*
G36*
G01X1338786D02*
G02Y1487398I0J1503D01*
G01X1342186D01*
G02Y1484392I0J-1503D01*
G01X1338786D01*
G37*
G36*
G01X1365586D02*
G02Y1487398I0J1503D01*
G01X1368986D01*
G02Y1484392I0J-1503D01*
G01X1365586D01*
G37*
G36*
G01X1392386D02*
G02Y1487398I0J1503D01*
G01X1395786D01*
G02Y1484392I0J-1503D01*
G01X1392386D01*
G37*
G36*
G01X1405786D02*
G02Y1487398I0J1503D01*
G01X1409186D01*
G02Y1484392I0J-1503D01*
G01X1405786D01*
G37*
G36*
G01X1448098D02*
G02Y1487398I0J1503D01*
G01X1451498D01*
G02Y1484392I0J-1503D01*
G01X1448098D01*
G37*
G36*
G01X1474898D02*
G02Y1487398I0J1503D01*
G01X1478298D01*
G02Y1484392I0J-1503D01*
G01X1474898D01*
G37*
G36*
G01X1501698D02*
G02Y1487398I0J1503D01*
G01X1505098D01*
G02Y1484392I0J-1503D01*
G01X1501698D01*
G37*
G36*
G01X1528498D02*
G02Y1487398I0J1503D01*
G01X1531898D01*
G02Y1484392I0J-1503D01*
G01X1528498D01*
G37*
G36*
G01X1541898D02*
G02Y1487398I0J1503D01*
G01X1545298D01*
G02Y1484392I0J-1503D01*
G01X1541898D01*
G37*
G36*
G01X1576160D02*
G02Y1487398I0J1503D01*
G01X1579560D01*
G02Y1484392I0J-1503D01*
G01X1576160D01*
G37*
G36*
G01X1602960D02*
G02Y1487398I0J1503D01*
G01X1606360D01*
G02Y1484392I0J-1503D01*
G01X1602960D01*
G37*
G36*
G01X1629760D02*
G02Y1487398I0J1503D01*
G01X1633160D01*
G02Y1484392I0J-1503D01*
G01X1629760D01*
G37*
G36*
G01X1656560D02*
G02Y1487398I0J1503D01*
G01X1659960D01*
G02Y1484392I0J-1503D01*
G01X1656560D01*
G37*
G36*
G01X1669960D02*
G02Y1487398I0J1503D01*
G01X1673360D01*
G02Y1484392I0J-1503D01*
G01X1669960D01*
G37*
G36*
G01X1177224Y1494092D02*
G02Y1497098I0J1503D01*
G01X1180624D01*
G02Y1494092I0J-1503D01*
G01X1177224D01*
G37*
G36*
G01X1204024D02*
G02Y1497098I0J1503D01*
G01X1207424D01*
G02Y1494092I0J-1503D01*
G01X1204024D01*
G37*
G36*
G01X1230824D02*
G02Y1497098I0J1503D01*
G01X1234224D01*
G02Y1494092I0J-1503D01*
G01X1230824D01*
G37*
G36*
G01X1257624D02*
G02Y1497098I0J1503D01*
G01X1261024D01*
G02Y1494092I0J-1503D01*
G01X1257624D01*
G37*
G36*
G01X1305286D02*
G02Y1497098I0J1503D01*
G01X1308686D01*
G02Y1494092I0J-1503D01*
G01X1305286D01*
G37*
G36*
G01X1332086D02*
G02Y1497098I0J1503D01*
G01X1335486D01*
G02Y1494092I0J-1503D01*
G01X1332086D01*
G37*
G36*
G01X1358886D02*
G02Y1497098I0J1503D01*
G01X1362286D01*
G02Y1494092I0J-1503D01*
G01X1358886D01*
G37*
G36*
G01X1385686D02*
G02Y1497098I0J1503D01*
G01X1389086D01*
G02Y1494092I0J-1503D01*
G01X1385686D01*
G37*
G36*
G01X1441398D02*
G02Y1497098I0J1503D01*
G01X1444798D01*
G02Y1494092I0J-1503D01*
G01X1441398D01*
G37*
G36*
G01X1468198D02*
G02Y1497098I0J1503D01*
G01X1471598D01*
G02Y1494092I0J-1503D01*
G01X1468198D01*
G37*
G36*
G01X1494998D02*
G02Y1497098I0J1503D01*
G01X1498398D01*
G02Y1494092I0J-1503D01*
G01X1494998D01*
G37*
G36*
G01X1521798D02*
G02Y1497098I0J1503D01*
G01X1525198D01*
G02Y1494092I0J-1503D01*
G01X1521798D01*
G37*
G36*
G01X1569460D02*
G02Y1497098I0J1503D01*
G01X1572860D01*
G02Y1494092I0J-1503D01*
G01X1569460D01*
G37*
G36*
G01X1596260D02*
G02Y1497098I0J1503D01*
G01X1599660D01*
G02Y1494092I0J-1503D01*
G01X1596260D01*
G37*
G36*
G01X1623060D02*
G02Y1497098I0J1503D01*
G01X1626460D01*
G02Y1494092I0J-1503D01*
G01X1623060D01*
G37*
G36*
G01X1649860D02*
G02Y1497098I0J1503D01*
G01X1653260D01*
G02Y1494092I0J-1503D01*
G01X1649860D01*
G37*
G36*
G01X1197324Y1503792D02*
G02Y1506798I0J1503D01*
G01X1200724D01*
G02Y1503792I0J-1503D01*
G01X1197324D01*
G37*
G36*
G01X1224124D02*
G02Y1506798I0J1503D01*
G01X1227524D01*
G02Y1503792I0J-1503D01*
G01X1224124D01*
G37*
G36*
G01X1250924D02*
G02Y1506798I0J1503D01*
G01X1254324D01*
G02Y1503792I0J-1503D01*
G01X1250924D01*
G37*
G36*
G01X1325386D02*
G02Y1506798I0J1503D01*
G01X1328786D01*
G02Y1503792I0J-1503D01*
G01X1325386D01*
G37*
G36*
G01X1352186D02*
G02Y1506798I0J1503D01*
G01X1355586D01*
G02Y1503792I0J-1503D01*
G01X1352186D01*
G37*
G36*
G01X1378986D02*
G02Y1506798I0J1503D01*
G01X1382386D01*
G02Y1503792I0J-1503D01*
G01X1378986D01*
G37*
G36*
G01X1461498D02*
G02Y1506798I0J1503D01*
G01X1464898D01*
G02Y1503792I0J-1503D01*
G01X1461498D01*
G37*
G36*
G01X1488298D02*
G02Y1506798I0J1503D01*
G01X1491698D01*
G02Y1503792I0J-1503D01*
G01X1488298D01*
G37*
G36*
G01X1515098D02*
G02Y1506798I0J1503D01*
G01X1518498D01*
G02Y1503792I0J-1503D01*
G01X1515098D01*
G37*
G36*
G01X1589560D02*
G02Y1506798I0J1503D01*
G01X1592960D01*
G02Y1503792I0J-1503D01*
G01X1589560D01*
G37*
G36*
G01X1616360D02*
G02Y1506798I0J1503D01*
G01X1619760D01*
G02Y1503792I0J-1503D01*
G01X1616360D01*
G37*
G36*
G01X1643160D02*
G02Y1506798I0J1503D01*
G01X1646560D01*
G02Y1503792I0J-1503D01*
G01X1643160D01*
G37*
G36*
G01X188668Y1520261D02*
X188670Y1520264D01*
G02X189730Y1520900I1060J-565D01*
G02X190932Y1519698I0J-1202D01*
G01Y1519697D01*
G02X190772Y1519098I-1203J1D01*
G01X189227Y1516425D01*
X189225Y1516421D01*
G02X188155Y1515768I-1070J550D01*
G01X188153D01*
G02X186952Y1516970I1J1202D01*
G01Y1516972D01*
G02X187102Y1517551I1203J-3D01*
G01X188668Y1520261D01*
G37*
G36*
G01X193392D02*
X193394Y1520264D01*
G02X194454Y1520900I1060J-565D01*
G02X195656Y1519698I0J-1202D01*
G01Y1519697D01*
G02X195496Y1519098I-1203J1D01*
G01X193951Y1516425D01*
X193949Y1516421D01*
G02X192879Y1515768I-1070J550D01*
G01X192877D01*
G02X191676Y1516970I1J1202D01*
G01Y1516972D01*
G02X191826Y1517551I1203J-3D01*
G01X193392Y1520261D01*
G37*
G36*
G01X198116D02*
X198118Y1520264D01*
G02X199178Y1520900I1060J-565D01*
G02X200380Y1519698I0J-1202D01*
G01Y1519697D01*
G02X200220Y1519098I-1203J1D01*
G01X198675Y1516425D01*
X198673Y1516421D01*
G02X197603Y1515768I-1070J550D01*
G01X197601D01*
G02X196400Y1516970I1J1202D01*
G01Y1516972D01*
G02X196550Y1517551I1203J-3D01*
G01X198116Y1520261D01*
G37*
G36*
G01X202843Y1520264D02*
G02X203903Y1520900I1060J-565D01*
G01X203905D01*
G02X205106Y1519698I-1J-1202D01*
G02X204945Y1519098I-1204J1D01*
G01X203400Y1516425D01*
X203398Y1516421D01*
G02X202328Y1515768I-1070J550D01*
G02X201126Y1516970I0J1202D01*
G01Y1516972D01*
G02X201275Y1517551I1202J-1D01*
G01X202841Y1520261D01*
X202843Y1520264D01*
G37*
G36*
G01X207567D02*
G02X208627Y1520900I1060J-565D01*
G01X208629D01*
G02X209830Y1519698I-1J-1202D01*
G02X209669Y1519098I-1204J1D01*
G01X208124Y1516425D01*
X208122Y1516421D01*
G02X207052Y1515768I-1070J550D01*
G02X205850Y1516970I0J1202D01*
G01Y1516972D01*
G02X205999Y1517551I1202J-1D01*
G01X207565Y1520261D01*
X207567Y1520264D01*
G37*
G36*
G01X212290Y1520261D02*
X212292Y1520264D01*
G02X213352Y1520900I1060J-565D01*
G02X214554Y1519698I0J-1202D01*
G01Y1519697D01*
G02X214394Y1519098I-1203J1D01*
G01X212849Y1516425D01*
X212847Y1516421D01*
G02X211777Y1515768I-1070J550D01*
G01X211775D01*
G02X210574Y1516970I1J1202D01*
G01Y1516972D01*
G02X210724Y1517551I1203J-3D01*
G01X212290Y1520261D01*
G37*
G36*
G01X217014D02*
X217016Y1520264D01*
G02X218076Y1520900I1060J-565D01*
G02X219278Y1519698I0J-1202D01*
G01Y1519697D01*
G02X219118Y1519098I-1203J1D01*
G01X217573Y1516425D01*
X217571Y1516421D01*
G02X216501Y1515768I-1070J550D01*
G01X216499D01*
G02X215298Y1516970I1J1202D01*
G01Y1516972D01*
G02X215448Y1517551I1203J-3D01*
G01X217014Y1520261D01*
G37*
G36*
G01X221738D02*
X221740Y1520264D01*
G02X222800Y1520900I1060J-565D01*
G02X224002Y1519698I0J-1202D01*
G01Y1519697D01*
G02X223842Y1519098I-1203J1D01*
G01X222297Y1516425D01*
X222295Y1516421D01*
G02X221225Y1515768I-1070J550D01*
G01X221223D01*
G02X220022Y1516970I1J1202D01*
G01Y1516972D01*
G02X220172Y1517551I1203J-3D01*
G01X221738Y1520261D01*
G37*
G36*
G01X226465Y1520264D02*
G02X227525Y1520900I1060J-565D01*
G01X227526D01*
G02X228728Y1519698I0J-1202D01*
G01Y1519697D01*
G02X228568Y1519098I-1203J1D01*
G01X227023Y1516425D01*
X227021Y1516421D01*
G02X225951Y1515768I-1070J550D01*
G01X225950D01*
G02X224748Y1516970I0J1202D01*
G01Y1516972D01*
G02X224897Y1517551I1202J-1D01*
G01X226463Y1520261D01*
X226465Y1520264D01*
G37*
G36*
G01X231189D02*
G02X232249Y1520900I1060J-565D01*
G01X232250D01*
G02X233452Y1519698I0J-1202D01*
G01Y1519697D01*
G02X233292Y1519098I-1203J1D01*
G01X231747Y1516425D01*
X231745Y1516421D01*
G02X230675Y1515768I-1070J550D01*
G01X230674D01*
G02X229472Y1516970I0J1202D01*
G01Y1516972D01*
G02X229621Y1517551I1202J-1D01*
G01X231187Y1520261D01*
X231189Y1520264D01*
G37*
G36*
G01X250087D02*
G02X251147Y1520900I1060J-565D01*
G01X251148D01*
G02X252350Y1519698I0J-1202D01*
G01Y1519697D01*
G02X252190Y1519098I-1203J1D01*
G01X250645Y1516425D01*
X250643Y1516421D01*
G02X249573Y1515768I-1070J550D01*
G01X249572D01*
G02X248370Y1516970I0J1202D01*
G01Y1516972D01*
G02X248519Y1517551I1202J-1D01*
G01X250085Y1520261D01*
X250087Y1520264D01*
G37*
G36*
G01X254811D02*
G02X255871Y1520900I1060J-565D01*
G01X255872D01*
G02X257074Y1519698I0J-1202D01*
G01Y1519697D01*
G02X256914Y1519098I-1203J1D01*
G01X255369Y1516425D01*
X255367Y1516421D01*
G02X254297Y1515768I-1070J550D01*
G01X254296D01*
G02X253094Y1516970I0J1202D01*
G01Y1516972D01*
G02X253243Y1517551I1202J-1D01*
G01X254809Y1520261D01*
X254811Y1520264D01*
G37*
G36*
G01X316730Y1520261D02*
X316732Y1520264D01*
G02X317792Y1520900I1060J-565D01*
G02X318994Y1519698I0J-1202D01*
G01Y1519697D01*
G02X318834Y1519098I-1203J1D01*
G01X317289Y1516425D01*
X317287Y1516421D01*
G02X316217Y1515768I-1070J550D01*
G01X316215D01*
G02X315014Y1516970I1J1202D01*
G01Y1516972D01*
G02X315164Y1517551I1203J-3D01*
G01X316730Y1520261D01*
G37*
G36*
G01X321454D02*
X321456Y1520264D01*
G02X322516Y1520900I1060J-565D01*
G02X323718Y1519698I0J-1202D01*
G01Y1519697D01*
G02X323558Y1519098I-1203J1D01*
G01X322013Y1516425D01*
X322011Y1516421D01*
G02X320941Y1515768I-1070J550D01*
G01X320939D01*
G02X319738Y1516970I1J1202D01*
G01Y1516972D01*
G02X319888Y1517551I1203J-3D01*
G01X321454Y1520261D01*
G37*
G36*
G01X326178D02*
X326180Y1520264D01*
G02X327240Y1520900I1060J-565D01*
G02X328442Y1519698I0J-1202D01*
G01Y1519697D01*
G02X328282Y1519098I-1203J1D01*
G01X326737Y1516425D01*
X326735Y1516421D01*
G02X325665Y1515768I-1070J550D01*
G01X325663D01*
G02X324462Y1516970I1J1202D01*
G01Y1516972D01*
G02X324612Y1517551I1203J-3D01*
G01X326178Y1520261D01*
G37*
G36*
G01X330905Y1520264D02*
G02X331965Y1520900I1060J-565D01*
G01X331967D01*
G02X333168Y1519698I-1J-1202D01*
G02X333007Y1519098I-1204J1D01*
G01X331462Y1516425D01*
X331460Y1516421D01*
G02X330390Y1515768I-1070J550D01*
G02X329188Y1516970I0J1202D01*
G01Y1516972D01*
G02X329337Y1517551I1202J-1D01*
G01X330903Y1520261D01*
X330905Y1520264D01*
G37*
G36*
G01X335629D02*
G02X336689Y1520900I1060J-565D01*
G01X336691D01*
G02X337892Y1519698I-1J-1202D01*
G02X337731Y1519098I-1204J1D01*
G01X336186Y1516425D01*
X336184Y1516421D01*
G02X335114Y1515768I-1070J550D01*
G02X333912Y1516970I0J1202D01*
G01Y1516972D01*
G02X334061Y1517551I1202J-1D01*
G01X335627Y1520261D01*
X335629Y1520264D01*
G37*
G36*
G01X340352Y1520261D02*
X340354Y1520264D01*
G02X341414Y1520900I1060J-565D01*
G02X342616Y1519698I0J-1202D01*
G01Y1519697D01*
G02X342456Y1519098I-1203J1D01*
G01X340911Y1516425D01*
X340909Y1516421D01*
G02X339839Y1515768I-1070J550D01*
G01X339837D01*
G02X338636Y1516970I1J1202D01*
G01Y1516972D01*
G02X338786Y1517551I1203J-3D01*
G01X340352Y1520261D01*
G37*
G36*
G01X345076D02*
X345078Y1520264D01*
G02X346138Y1520900I1060J-565D01*
G02X347340Y1519698I0J-1202D01*
G01Y1519697D01*
G02X347180Y1519098I-1203J1D01*
G01X345635Y1516425D01*
X345633Y1516421D01*
G02X344563Y1515768I-1070J550D01*
G01X344561D01*
G02X343360Y1516970I1J1202D01*
G01Y1516972D01*
G02X343510Y1517551I1203J-3D01*
G01X345076Y1520261D01*
G37*
G36*
G01X349800D02*
X349802Y1520264D01*
G02X350862Y1520900I1060J-565D01*
G02X352064Y1519698I0J-1202D01*
G01Y1519697D01*
G02X351904Y1519098I-1203J1D01*
G01X350359Y1516425D01*
X350357Y1516421D01*
G02X349287Y1515768I-1070J550D01*
G01X349285D01*
G02X348084Y1516970I1J1202D01*
G01Y1516972D01*
G02X348234Y1517551I1203J-3D01*
G01X349800Y1520261D01*
G37*
G36*
G01X354527Y1520264D02*
G02X355587Y1520900I1060J-565D01*
G01X355589D01*
G02X356790Y1519698I-1J-1202D01*
G02X356629Y1519098I-1204J1D01*
G01X355084Y1516425D01*
X355082Y1516421D01*
G02X354012Y1515768I-1070J550D01*
G02X352810Y1516970I0J1202D01*
G01Y1516972D01*
G02X352959Y1517551I1202J-1D01*
G01X354525Y1520261D01*
X354527Y1520264D01*
G37*
G36*
G01X359251D02*
G02X360311Y1520900I1060J-565D01*
G01X360313D01*
G02X361514Y1519698I-1J-1202D01*
G02X361353Y1519098I-1204J1D01*
G01X359808Y1516425D01*
X359806Y1516421D01*
G02X358736Y1515768I-1070J550D01*
G02X357534Y1516970I0J1202D01*
G01Y1516972D01*
G02X357683Y1517551I1202J-1D01*
G01X359249Y1520261D01*
X359251Y1520264D01*
G37*
G36*
G01X363974Y1520261D02*
X363976Y1520264D01*
G02X365036Y1520900I1060J-565D01*
G02X366238Y1519698I0J-1202D01*
G01Y1519697D01*
G02X366078Y1519098I-1203J1D01*
G01X364533Y1516425D01*
X364531Y1516421D01*
G02X363461Y1515768I-1070J550D01*
G01X363459D01*
G02X362258Y1516970I1J1202D01*
G01Y1516972D01*
G02X362408Y1517551I1203J-3D01*
G01X363974Y1520261D01*
G37*
G36*
G01X368698D02*
X368700Y1520264D01*
G02X369760Y1520900I1060J-565D01*
G02X370962Y1519698I0J-1202D01*
G01Y1519697D01*
G02X370802Y1519098I-1203J1D01*
G01X369257Y1516425D01*
X369255Y1516421D01*
G02X368185Y1515768I-1070J550D01*
G01X368183D01*
G02X366982Y1516970I1J1202D01*
G01Y1516972D01*
G02X367132Y1517551I1203J-3D01*
G01X368698Y1520261D01*
G37*
G36*
G01X373422D02*
X373424Y1520264D01*
G02X374484Y1520900I1060J-565D01*
G02X375686Y1519698I0J-1202D01*
G01Y1519697D01*
G02X375526Y1519098I-1203J1D01*
G01X373981Y1516425D01*
X373979Y1516421D01*
G02X372909Y1515768I-1070J550D01*
G01X372907D01*
G02X371706Y1516970I1J1202D01*
G01Y1516972D01*
G02X371856Y1517551I1203J-3D01*
G01X373422Y1520261D01*
G37*
G36*
G01X378149Y1520264D02*
G02X379209Y1520900I1060J-565D01*
G01X379211D01*
G02X380412Y1519698I-1J-1202D01*
G02X380251Y1519098I-1204J1D01*
G01X378706Y1516425D01*
X378704Y1516421D01*
G02X377634Y1515768I-1070J550D01*
G02X376432Y1516970I0J1202D01*
G01Y1516972D01*
G02X376581Y1517551I1202J-1D01*
G01X378147Y1520261D01*
X378149Y1520264D01*
G37*
G36*
G01X382873D02*
G02X383933Y1520900I1060J-565D01*
G01X383935D01*
G02X385136Y1519698I-1J-1202D01*
G02X384975Y1519098I-1204J1D01*
G01X383430Y1516425D01*
X383428Y1516421D01*
G02X382358Y1515768I-1070J550D01*
G02X381156Y1516970I0J1202D01*
G01Y1516972D01*
G02X381305Y1517551I1202J-1D01*
G01X382871Y1520261D01*
X382873Y1520264D01*
G37*
G36*
G01X387596Y1520261D02*
X387598Y1520264D01*
G02X388658Y1520900I1060J-565D01*
G02X389860Y1519698I0J-1202D01*
G01Y1519697D01*
G02X389700Y1519098I-1203J1D01*
G01X388155Y1516425D01*
X388153Y1516421D01*
G02X387083Y1515768I-1070J550D01*
G01X387081D01*
G02X385880Y1516970I1J1202D01*
G01Y1516972D01*
G02X386030Y1517551I1203J-3D01*
G01X387596Y1520261D01*
G37*
G36*
G01X452843Y1520264D02*
G02X453903Y1520900I1060J-565D01*
G01X453905D01*
G02X455106Y1519698I-1J-1202D01*
G02X454945Y1519098I-1204J1D01*
G01X453400Y1516425D01*
X453398Y1516421D01*
G02X452328Y1515768I-1070J550D01*
G02X451126Y1516970I0J1202D01*
G01Y1516972D01*
G02X451275Y1517551I1202J-1D01*
G01X452841Y1520261D01*
X452843Y1520264D01*
G37*
G36*
G01X457567D02*
G02X458627Y1520900I1060J-565D01*
G01X458629D01*
G02X459830Y1519698I-1J-1202D01*
G02X459669Y1519098I-1204J1D01*
G01X458124Y1516425D01*
X458122Y1516421D01*
G02X457052Y1515768I-1070J550D01*
G02X455850Y1516970I0J1202D01*
G01Y1516972D01*
G02X455999Y1517551I1202J-1D01*
G01X457565Y1520261D01*
X457567Y1520264D01*
G37*
G36*
G01X462291D02*
G02X463351Y1520900I1060J-565D01*
G01X463353D01*
G02X464554Y1519698I-1J-1202D01*
G02X464393Y1519098I-1204J1D01*
G01X462848Y1516425D01*
X462846Y1516421D01*
G02X461776Y1515768I-1070J550D01*
G02X460574Y1516970I0J1202D01*
G01Y1516972D01*
G02X460723Y1517551I1202J-1D01*
G01X462289Y1520261D01*
X462291Y1520264D01*
G37*
G36*
G01X467014Y1520261D02*
X467016Y1520264D01*
G02X468076Y1520900I1060J-565D01*
G02X469278Y1519698I0J-1202D01*
G01Y1519697D01*
G02X469118Y1519098I-1203J1D01*
G01X467573Y1516425D01*
X467571Y1516421D01*
G02X466501Y1515768I-1070J550D01*
G01X466499D01*
G02X465298Y1516970I1J1202D01*
G01Y1516972D01*
G02X465448Y1517551I1203J-3D01*
G01X467014Y1520261D01*
G37*
G36*
G01X471738D02*
X471740Y1520264D01*
G02X472800Y1520900I1060J-565D01*
G02X474002Y1519698I0J-1202D01*
G01Y1519697D01*
G02X473842Y1519098I-1203J1D01*
G01X472297Y1516425D01*
X472295Y1516421D01*
G02X471225Y1515768I-1070J550D01*
G01X471223D01*
G02X470022Y1516970I1J1202D01*
G01Y1516972D01*
G02X470172Y1517551I1203J-3D01*
G01X471738Y1520261D01*
G37*
G36*
G01X476465Y1520264D02*
G02X477525Y1520900I1060J-565D01*
G01X477527D01*
G02X478728Y1519698I-1J-1202D01*
G02X478567Y1519098I-1204J1D01*
G01X477022Y1516425D01*
X477020Y1516421D01*
G02X475950Y1515768I-1070J550D01*
G02X474748Y1516970I0J1202D01*
G01Y1516972D01*
G02X474897Y1517551I1202J-1D01*
G01X476463Y1520261D01*
X476465Y1520264D01*
G37*
G36*
G01X481189D02*
G02X482249Y1520900I1060J-565D01*
G01X482251D01*
G02X483452Y1519698I-1J-1202D01*
G02X483291Y1519098I-1204J1D01*
G01X481746Y1516425D01*
X481744Y1516421D01*
G02X480674Y1515768I-1070J550D01*
G02X479472Y1516970I0J1202D01*
G01Y1516972D01*
G02X479621Y1517551I1202J-1D01*
G01X481187Y1520261D01*
X481189Y1520264D01*
G37*
G36*
G01X485913D02*
G02X486973Y1520900I1060J-565D01*
G01X486975D01*
G02X488176Y1519698I-1J-1202D01*
G02X488015Y1519098I-1204J1D01*
G01X486470Y1516425D01*
X486468Y1516421D01*
G02X485398Y1515768I-1070J550D01*
G02X484196Y1516970I0J1202D01*
G01Y1516972D01*
G02X484345Y1517551I1202J-1D01*
G01X485911Y1520261D01*
X485913Y1520264D01*
G37*
G36*
G01X490636Y1520261D02*
X490638Y1520264D01*
G02X491698Y1520900I1060J-565D01*
G02X492900Y1519698I0J-1202D01*
G01Y1519697D01*
G02X492740Y1519098I-1203J1D01*
G01X491195Y1516425D01*
X491193Y1516421D01*
G02X490123Y1515768I-1070J550D01*
G01X490121D01*
G02X488920Y1516970I1J1202D01*
G01Y1516972D01*
G02X489070Y1517551I1203J-3D01*
G01X490636Y1520261D01*
G37*
G36*
G01X495360D02*
X495362Y1520264D01*
G02X496422Y1520900I1060J-565D01*
G02X497624Y1519698I0J-1202D01*
G01Y1519697D01*
G02X497464Y1519098I-1203J1D01*
G01X495919Y1516425D01*
X495917Y1516421D01*
G02X494847Y1515768I-1070J550D01*
G01X494845D01*
G02X493644Y1516970I1J1202D01*
G01Y1516972D01*
G02X493794Y1517551I1203J-3D01*
G01X495360Y1520261D01*
G37*
G36*
G01X500087Y1520264D02*
G02X501147Y1520900I1060J-565D01*
G01X501149D01*
G02X502350Y1519698I-1J-1202D01*
G02X502189Y1519098I-1204J1D01*
G01X500644Y1516425D01*
X500642Y1516421D01*
G02X499572Y1515768I-1070J550D01*
G02X498370Y1516970I0J1202D01*
G01Y1516972D01*
G02X498519Y1517551I1202J-1D01*
G01X500085Y1520261D01*
X500087Y1520264D01*
G37*
G36*
G01X504811D02*
G02X505871Y1520900I1060J-565D01*
G01X505873D01*
G02X507074Y1519698I-1J-1202D01*
G02X506913Y1519098I-1204J1D01*
G01X505368Y1516425D01*
X505366Y1516421D01*
G02X504296Y1515768I-1070J550D01*
G02X503094Y1516970I0J1202D01*
G01Y1516972D01*
G02X503243Y1517551I1202J-1D01*
G01X504809Y1520261D01*
X504811Y1520264D01*
G37*
G36*
G01X509535D02*
G02X510595Y1520900I1060J-565D01*
G01X510597D01*
G02X511798Y1519698I-1J-1202D01*
G02X511637Y1519098I-1204J1D01*
G01X510092Y1516425D01*
X510090Y1516421D01*
G02X509020Y1515768I-1070J550D01*
G02X507818Y1516970I0J1202D01*
G01Y1516972D01*
G02X507967Y1517551I1202J-1D01*
G01X509533Y1520261D01*
X509535Y1520264D01*
G37*
G36*
G01X514258Y1520261D02*
X514260Y1520264D01*
G02X515320Y1520900I1060J-565D01*
G02X516522Y1519698I0J-1202D01*
G01Y1519697D01*
G02X516362Y1519098I-1203J1D01*
G01X514817Y1516425D01*
X514815Y1516421D01*
G02X513745Y1515768I-1070J550D01*
G01X513743D01*
G02X512542Y1516970I1J1202D01*
G01Y1516972D01*
G02X512692Y1517551I1203J-3D01*
G01X514258Y1520261D01*
G37*
G36*
G01X518982D02*
X518984Y1520264D01*
G02X520044Y1520900I1060J-565D01*
G02X521246Y1519698I0J-1202D01*
G01Y1519697D01*
G02X521086Y1519098I-1203J1D01*
G01X519541Y1516425D01*
X519539Y1516421D01*
G02X518469Y1515768I-1070J550D01*
G01X518467D01*
G02X517266Y1516970I1J1202D01*
G01Y1516972D01*
G02X517416Y1517551I1203J-3D01*
G01X518982Y1520261D01*
G37*
G36*
G01X523709Y1520264D02*
G02X524769Y1520900I1060J-565D01*
G01X524771D01*
G02X525972Y1519698I-1J-1202D01*
G02X525811Y1519098I-1204J1D01*
G01X524266Y1516425D01*
X524264Y1516421D01*
G02X523194Y1515768I-1070J550D01*
G02X521992Y1516970I0J1202D01*
G01Y1516972D01*
G02X522141Y1517551I1202J-1D01*
G01X523707Y1520261D01*
X523709Y1520264D01*
G37*
G36*
G01X580905D02*
G02X581965Y1520900I1060J-565D01*
G01X581967D01*
G02X583168Y1519698I-1J-1202D01*
G02X583007Y1519098I-1204J1D01*
G01X581462Y1516425D01*
X581460Y1516421D01*
G02X580390Y1515768I-1070J550D01*
G02X579188Y1516970I0J1202D01*
G01Y1516972D01*
G02X579337Y1517551I1202J-1D01*
G01X580903Y1520261D01*
X580905Y1520264D01*
G37*
G36*
G01X585629D02*
G02X586689Y1520900I1060J-565D01*
G01X586691D01*
G02X587892Y1519698I-1J-1202D01*
G02X587731Y1519098I-1204J1D01*
G01X586186Y1516425D01*
X586184Y1516421D01*
G02X585114Y1515768I-1070J550D01*
G02X583912Y1516970I0J1202D01*
G01Y1516972D01*
G02X584061Y1517551I1202J-1D01*
G01X585627Y1520261D01*
X585629Y1520264D01*
G37*
G36*
G01X590353D02*
G02X591413Y1520900I1060J-565D01*
G01X591415D01*
G02X592616Y1519698I-1J-1202D01*
G02X592455Y1519098I-1204J1D01*
G01X590910Y1516425D01*
X590908Y1516421D01*
G02X589838Y1515768I-1070J550D01*
G02X588636Y1516970I0J1202D01*
G01Y1516972D01*
G02X588785Y1517551I1202J-1D01*
G01X590351Y1520261D01*
X590353Y1520264D01*
G37*
G36*
G01X595076Y1520261D02*
X595078Y1520264D01*
G02X596138Y1520900I1060J-565D01*
G02X597340Y1519698I0J-1202D01*
G01Y1519697D01*
G02X597180Y1519098I-1203J1D01*
G01X595635Y1516425D01*
X595633Y1516421D01*
G02X594563Y1515768I-1070J550D01*
G01X594561D01*
G02X593360Y1516970I1J1202D01*
G01Y1516972D01*
G02X593510Y1517551I1203J-3D01*
G01X595076Y1520261D01*
G37*
G36*
G01X599800D02*
X599802Y1520264D01*
G02X600862Y1520900I1060J-565D01*
G02X602064Y1519698I0J-1202D01*
G01Y1519697D01*
G02X601904Y1519098I-1203J1D01*
G01X600359Y1516425D01*
X600357Y1516421D01*
G02X599287Y1515768I-1070J550D01*
G01X599285D01*
G02X598084Y1516970I1J1202D01*
G01Y1516972D01*
G02X598234Y1517551I1203J-3D01*
G01X599800Y1520261D01*
G37*
G36*
G01X604527Y1520264D02*
G02X605587Y1520900I1060J-565D01*
G01X605589D01*
G02X606790Y1519698I-1J-1202D01*
G02X606629Y1519098I-1204J1D01*
G01X605084Y1516425D01*
X605082Y1516421D01*
G02X604012Y1515768I-1070J550D01*
G02X602810Y1516970I0J1202D01*
G01Y1516972D01*
G02X602959Y1517551I1202J-1D01*
G01X604525Y1520261D01*
X604527Y1520264D01*
G37*
G36*
G01X609251D02*
G02X610311Y1520900I1060J-565D01*
G01X610313D01*
G02X611514Y1519698I-1J-1202D01*
G02X611353Y1519098I-1204J1D01*
G01X609808Y1516425D01*
X609806Y1516421D01*
G02X608736Y1515768I-1070J550D01*
G02X607534Y1516970I0J1202D01*
G01Y1516972D01*
G02X607683Y1517551I1202J-1D01*
G01X609249Y1520261D01*
X609251Y1520264D01*
G37*
G36*
G01X613975D02*
G02X615035Y1520900I1060J-565D01*
G01X615037D01*
G02X616238Y1519698I-1J-1202D01*
G02X616077Y1519098I-1204J1D01*
G01X614532Y1516425D01*
X614530Y1516421D01*
G02X613460Y1515768I-1070J550D01*
G02X612258Y1516970I0J1202D01*
G01Y1516972D01*
G02X612407Y1517551I1202J-1D01*
G01X613973Y1520261D01*
X613975Y1520264D01*
G37*
G36*
G01X618698Y1520261D02*
X618700Y1520264D01*
G02X619760Y1520900I1060J-565D01*
G02X620962Y1519698I0J-1202D01*
G01Y1519697D01*
G02X620802Y1519098I-1203J1D01*
G01X619257Y1516425D01*
X619255Y1516421D01*
G02X618185Y1515768I-1070J550D01*
G01X618183D01*
G02X616982Y1516970I1J1202D01*
G01Y1516972D01*
G02X617132Y1517551I1203J-3D01*
G01X618698Y1520261D01*
G37*
G36*
G01X623422D02*
X623424Y1520264D01*
G02X624484Y1520900I1060J-565D01*
G02X625686Y1519698I0J-1202D01*
G01Y1519697D01*
G02X625526Y1519098I-1203J1D01*
G01X623981Y1516425D01*
X623979Y1516421D01*
G02X622909Y1515768I-1070J550D01*
G01X622907D01*
G02X621706Y1516970I1J1202D01*
G01Y1516972D01*
G02X621856Y1517551I1203J-3D01*
G01X623422Y1520261D01*
G37*
G36*
G01X628149Y1520264D02*
G02X629209Y1520900I1060J-565D01*
G01X629211D01*
G02X630412Y1519698I-1J-1202D01*
G02X630251Y1519098I-1204J1D01*
G01X628706Y1516425D01*
X628704Y1516421D01*
G02X627634Y1515768I-1070J550D01*
G02X626432Y1516970I0J1202D01*
G01Y1516972D01*
G02X626581Y1517551I1202J-1D01*
G01X628147Y1520261D01*
X628149Y1520264D01*
G37*
G36*
G01X632873D02*
G02X633933Y1520900I1060J-565D01*
G01X633935D01*
G02X635136Y1519698I-1J-1202D01*
G02X634975Y1519098I-1204J1D01*
G01X633430Y1516425D01*
X633428Y1516421D01*
G02X632358Y1515768I-1070J550D01*
G02X631156Y1516970I0J1202D01*
G01Y1516972D01*
G02X631305Y1517551I1202J-1D01*
G01X632871Y1520261D01*
X632873Y1520264D01*
G37*
G36*
G01X637597D02*
G02X638657Y1520900I1060J-565D01*
G01X638659D01*
G02X639860Y1519698I-1J-1202D01*
G02X639699Y1519098I-1204J1D01*
G01X638154Y1516425D01*
X638152Y1516421D01*
G02X637082Y1515768I-1070J550D01*
G02X635880Y1516970I0J1202D01*
G01Y1516972D01*
G02X636029Y1517551I1202J-1D01*
G01X637595Y1520261D01*
X637597Y1520264D01*
G37*
G36*
G01X642320Y1520261D02*
X642322Y1520264D01*
G02X643382Y1520900I1060J-565D01*
G02X644584Y1519698I0J-1202D01*
G01Y1519697D01*
G02X644424Y1519098I-1203J1D01*
G01X642879Y1516425D01*
X642877Y1516421D01*
G02X641807Y1515768I-1070J550D01*
G01X641805D01*
G02X640604Y1516970I1J1202D01*
G01Y1516972D01*
G02X640754Y1517551I1203J-3D01*
G01X642320Y1520261D01*
G37*
G36*
G01X647044D02*
X647046Y1520264D01*
G02X648106Y1520900I1060J-565D01*
G02X649308Y1519698I0J-1202D01*
G01Y1519697D01*
G02X649148Y1519098I-1203J1D01*
G01X647603Y1516425D01*
X647601Y1516421D01*
G02X646531Y1515768I-1070J550D01*
G01X646529D01*
G02X645328Y1516970I1J1202D01*
G01Y1516972D01*
G02X645478Y1517551I1203J-3D01*
G01X647044Y1520261D01*
G37*
G36*
G01X651771Y1520264D02*
G02X652831Y1520900I1060J-565D01*
G01X652833D01*
G02X654034Y1519698I-1J-1202D01*
G02X653873Y1519098I-1204J1D01*
G01X652328Y1516425D01*
X652326Y1516421D01*
G02X651256Y1515768I-1070J550D01*
G02X650054Y1516970I0J1202D01*
G01Y1516972D01*
G02X650203Y1517551I1202J-1D01*
G01X651769Y1520261D01*
X651771Y1520264D01*
G37*
G36*
G01X236974Y1520900D02*
X236975D01*
G02X238178Y1519698I1J-1202D01*
G02X238017Y1519098I-1204J1D01*
G01X236472Y1516425D01*
X236470Y1516421D01*
G02X235400Y1515768I-1070J550D01*
G01X235399D01*
G02X234196Y1516970I-1J1202D01*
G01Y1516972D01*
G02X234346Y1517551I1203J-3D01*
G01X235912Y1520261D01*
X235914Y1520264D01*
G02X236974Y1520900I1060J-565D01*
G37*
G36*
G01X241698D02*
X241699D01*
G02X242902Y1519698I1J-1202D01*
G02X242741Y1519098I-1204J1D01*
G01X241196Y1516425D01*
X241194Y1516421D01*
G02X240124Y1515768I-1070J550D01*
G01X240123D01*
G02X238920Y1516970I-1J1202D01*
G01Y1516972D01*
G02X239070Y1517551I1203J-3D01*
G01X240636Y1520261D01*
X240638Y1520264D01*
G02X241698Y1520900I1060J-565D01*
G37*
G36*
G01X246422D02*
X246423D01*
G02X247626Y1519698I1J-1202D01*
G02X247465Y1519098I-1204J1D01*
G01X245920Y1516425D01*
X245918Y1516421D01*
G02X244848Y1515768I-1070J550D01*
G01X244847D01*
G02X243644Y1516970I-1J1202D01*
G01Y1516972D01*
G02X243794Y1517551I1203J-3D01*
G01X245360Y1520261D01*
X245362Y1520264D01*
G02X246422Y1520900I1060J-565D01*
G37*
G36*
G01X260596D02*
X260597D01*
G02X261800Y1519698I1J-1202D01*
G02X261639Y1519098I-1204J1D01*
G01X260094Y1516425D01*
X260092Y1516421D01*
G02X259022Y1515768I-1070J550D01*
G01X259021D01*
G02X257818Y1516970I-1J1202D01*
G01Y1516972D01*
G02X257968Y1517551I1203J-3D01*
G01X259534Y1520261D01*
X259536Y1520264D01*
G02X260596Y1520900I1060J-565D01*
G37*
G36*
G01X188666Y1533895D02*
X188667Y1533898D01*
G02X189730Y1534538I1063J-563D01*
G02X190932Y1533336I0J-1202D01*
G01Y1533335D01*
G02X190779Y1532748I-1202J0D01*
G01X190774Y1532738D01*
X190773D01*
X190772Y1532736D01*
X189229Y1530066D01*
X189227Y1530061D01*
G02X186968Y1530800I-1072J545D01*
G01Y1530801D01*
G02X187102Y1531189I1187J-193D01*
G01X188666Y1533895D01*
G37*
G36*
G01X193390D02*
X193391Y1533898D01*
G02X194454Y1534538I1063J-563D01*
G02X195656Y1533336I0J-1202D01*
G01Y1533335D01*
G02X195503Y1532748I-1202J0D01*
G01X195498Y1532738D01*
X195497D01*
X195496Y1532736D01*
X193953Y1530066D01*
X193951Y1530061D01*
G02X191692Y1530800I-1072J545D01*
G01Y1530801D01*
G02X191826Y1531189I1187J-193D01*
G01X193390Y1533895D01*
G37*
G36*
G01X198114D02*
X198115Y1533898D01*
G02X199178Y1534538I1063J-563D01*
G02X200380Y1533336I0J-1202D01*
G01Y1533335D01*
G02X200227Y1532748I-1202J0D01*
G01X200222Y1532738D01*
X200221D01*
X200220Y1532736D01*
X198677Y1530066D01*
X198675Y1530061D01*
G02X196416Y1530800I-1072J545D01*
G01Y1530801D01*
G02X196550Y1531189I1187J-193D01*
G01X198114Y1533895D01*
G37*
G36*
G01X202840Y1533898D02*
G02X203903Y1534538I1063J-563D01*
G01X203905D01*
G02X205106Y1533336I-1J-1202D01*
G01Y1533335D01*
G02X204952Y1532748I-1203J2D01*
G01X204947Y1532738D01*
X204946D01*
X204945Y1532736D01*
X203402Y1530066D01*
X203400Y1530061D01*
G02X201141Y1530800I-1072J545D01*
G01Y1530801D01*
G02X201275Y1531189I1187J-193D01*
G01X202839Y1533895D01*
X202840Y1533898D01*
G37*
G36*
G01X207564D02*
G02X208627Y1534538I1063J-563D01*
G01X208629D01*
G02X209830Y1533336I-1J-1202D01*
G01Y1533335D01*
G02X209676Y1532748I-1203J2D01*
G01X209671Y1532738D01*
X209670D01*
X209669Y1532736D01*
X208126Y1530066D01*
X208124Y1530061D01*
G02X205865Y1530800I-1072J545D01*
G01Y1530801D01*
G02X205999Y1531189I1187J-193D01*
G01X207563Y1533895D01*
X207564Y1533898D01*
G37*
G36*
G01X212288Y1533895D02*
X212289Y1533898D01*
G02X213352Y1534538I1063J-563D01*
G02X214554Y1533336I0J-1202D01*
G01Y1533335D01*
G02X214401Y1532748I-1202J0D01*
G01X214396Y1532738D01*
X214395D01*
X214394Y1532736D01*
X212851Y1530066D01*
X212849Y1530061D01*
G02X210590Y1530800I-1072J545D01*
G01Y1530801D01*
G02X210724Y1531189I1187J-193D01*
G01X212288Y1533895D01*
G37*
G36*
G01X217012D02*
X217013Y1533898D01*
G02X218076Y1534538I1063J-563D01*
G02X219278Y1533336I0J-1202D01*
G01Y1533335D01*
G02X219125Y1532748I-1202J0D01*
G01X219120Y1532738D01*
X219119D01*
X219118Y1532736D01*
X217575Y1530066D01*
X217573Y1530061D01*
G02X215314Y1530800I-1072J545D01*
G01Y1530801D01*
G02X215448Y1531189I1187J-193D01*
G01X217012Y1533895D01*
G37*
G36*
G01X221736D02*
X221737Y1533898D01*
G02X222800Y1534538I1063J-563D01*
G02X224002Y1533336I0J-1202D01*
G01Y1533335D01*
G02X223849Y1532748I-1202J0D01*
G01X223844Y1532738D01*
X223843D01*
X223842Y1532736D01*
X222299Y1530066D01*
X222297Y1530061D01*
G02X220038Y1530800I-1072J545D01*
G01Y1530801D01*
G02X220172Y1531189I1187J-193D01*
G01X221736Y1533895D01*
G37*
G36*
G01X226462Y1533898D02*
G02X227525Y1534538I1063J-563D01*
G01X227527D01*
G02X228728Y1533336I-1J-1202D01*
G01Y1533335D01*
G02X228574Y1532748I-1203J2D01*
G01X228569Y1532738D01*
X228568D01*
X228567Y1532736D01*
X227024Y1530066D01*
X227022Y1530061D01*
G02X224763Y1530800I-1072J545D01*
G01Y1530801D01*
G02X224897Y1531189I1187J-193D01*
G01X226461Y1533895D01*
X226462Y1533898D01*
G37*
G36*
G01X231186D02*
G02X232249Y1534538I1063J-563D01*
G01X232251D01*
G02X233452Y1533336I-1J-1202D01*
G01Y1533335D01*
G02X233298Y1532748I-1203J2D01*
G01X233293Y1532738D01*
X233292D01*
X233291Y1532736D01*
X231748Y1530066D01*
X231746Y1530061D01*
G02X229487Y1530800I-1072J545D01*
G01Y1530801D01*
G02X229621Y1531189I1187J-193D01*
G01X231185Y1533895D01*
X231186Y1533898D01*
G37*
G36*
G01X235910Y1533895D02*
X235911Y1533898D01*
G02X236974Y1534538I1063J-563D01*
G02X238176Y1533336I0J-1202D01*
G01Y1533335D01*
G02X238023Y1532748I-1202J0D01*
G01X238018Y1532738D01*
X238017D01*
X238016Y1532736D01*
X236473Y1530066D01*
X236471Y1530061D01*
G02X234212Y1530800I-1072J545D01*
G01Y1530801D01*
G02X234346Y1531189I1187J-193D01*
G01X235910Y1533895D01*
G37*
G36*
G01X240634D02*
X240635Y1533898D01*
G02X241698Y1534538I1063J-563D01*
G02X242900Y1533336I0J-1202D01*
G01Y1533335D01*
G02X242747Y1532748I-1202J0D01*
G01X242742Y1532738D01*
X242741D01*
X242740Y1532736D01*
X241197Y1530066D01*
X241195Y1530061D01*
G02X238936Y1530800I-1072J545D01*
G01Y1530801D01*
G02X239070Y1531189I1187J-193D01*
G01X240634Y1533895D01*
G37*
G36*
G01X245358D02*
X245359Y1533898D01*
G02X246422Y1534538I1063J-563D01*
G02X247624Y1533336I0J-1202D01*
G01Y1533335D01*
G02X247471Y1532748I-1202J0D01*
G01X247466Y1532738D01*
X247465D01*
X247464Y1532736D01*
X245921Y1530066D01*
X245919Y1530061D01*
G02X243660Y1530800I-1072J545D01*
G01Y1530801D01*
G02X243794Y1531189I1187J-193D01*
G01X245358Y1533895D01*
G37*
G36*
G01X250084Y1533898D02*
G02X251147Y1534538I1063J-563D01*
G01X251149D01*
G02X252350Y1533336I-1J-1202D01*
G01Y1533335D01*
G02X252196Y1532748I-1203J2D01*
G01X252191Y1532738D01*
X252190D01*
X252189Y1532736D01*
X250646Y1530066D01*
X250644Y1530061D01*
G02X248385Y1530800I-1072J545D01*
G01Y1530801D01*
G02X248519Y1531189I1187J-193D01*
G01X250083Y1533895D01*
X250084Y1533898D01*
G37*
G36*
G01X254808D02*
G02X255871Y1534538I1063J-563D01*
G01X255873D01*
G02X257074Y1533336I-1J-1202D01*
G01Y1533335D01*
G02X256920Y1532748I-1203J2D01*
G01X256915Y1532738D01*
X256914D01*
X256913Y1532736D01*
X255370Y1530066D01*
X255368Y1530061D01*
G02X253109Y1530800I-1072J545D01*
G01Y1530801D01*
G02X253243Y1531189I1187J-193D01*
G01X254807Y1533895D01*
X254808Y1533898D01*
G37*
G36*
G01X259532Y1533895D02*
X259533Y1533898D01*
G02X260596Y1534538I1063J-563D01*
G02X261798Y1533336I0J-1202D01*
G01Y1533335D01*
G02X261645Y1532748I-1202J0D01*
G01X261640Y1532738D01*
X261639D01*
X261638Y1532736D01*
X260095Y1530066D01*
X260093Y1530061D01*
G02X257834Y1530800I-1072J545D01*
G01Y1530801D01*
G02X257968Y1531189I1187J-193D01*
G01X259532Y1533895D01*
G37*
G36*
G01X316728D02*
X316729Y1533898D01*
G02X317792Y1534538I1063J-563D01*
G02X318994Y1533336I0J-1202D01*
G01Y1533335D01*
G02X318841Y1532748I-1202J0D01*
G01X318836Y1532738D01*
X318835D01*
X318834Y1532736D01*
X317291Y1530066D01*
X317289Y1530061D01*
G02X315030Y1530800I-1072J545D01*
G01Y1530801D01*
G02X315164Y1531189I1187J-193D01*
G01X316728Y1533895D01*
G37*
G36*
G01X321452D02*
X321453Y1533898D01*
G02X322516Y1534538I1063J-563D01*
G02X323718Y1533336I0J-1202D01*
G01Y1533335D01*
G02X323565Y1532748I-1202J0D01*
G01X323560Y1532738D01*
X323559D01*
X323558Y1532736D01*
X322015Y1530066D01*
X322013Y1530061D01*
G02X319754Y1530800I-1072J545D01*
G01Y1530801D01*
G02X319888Y1531189I1187J-193D01*
G01X321452Y1533895D01*
G37*
G36*
G01X326176D02*
X326177Y1533898D01*
G02X327240Y1534538I1063J-563D01*
G02X328442Y1533336I0J-1202D01*
G01Y1533335D01*
G02X328289Y1532748I-1202J0D01*
G01X328284Y1532738D01*
X328283D01*
X328282Y1532736D01*
X326739Y1530066D01*
X326737Y1530061D01*
G02X324478Y1530800I-1072J545D01*
G01Y1530801D01*
G02X324612Y1531189I1187J-193D01*
G01X326176Y1533895D01*
G37*
G36*
G01X330902Y1533898D02*
G02X331965Y1534538I1063J-563D01*
G01X331967D01*
G02X333168Y1533336I-1J-1202D01*
G01Y1533335D01*
G02X333014Y1532748I-1203J2D01*
G01X333009Y1532738D01*
X333008D01*
X333007Y1532736D01*
X331464Y1530066D01*
X331462Y1530061D01*
G02X329203Y1530800I-1072J545D01*
G01Y1530801D01*
G02X329337Y1531189I1187J-193D01*
G01X330901Y1533895D01*
X330902Y1533898D01*
G37*
G36*
G01X335626D02*
G02X336689Y1534538I1063J-563D01*
G01X336691D01*
G02X337892Y1533336I-1J-1202D01*
G01Y1533335D01*
G02X337738Y1532748I-1203J2D01*
G01X337733Y1532738D01*
X337732D01*
X337731Y1532736D01*
X336188Y1530066D01*
X336186Y1530061D01*
G02X333927Y1530800I-1072J545D01*
G01Y1530801D01*
G02X334061Y1531189I1187J-193D01*
G01X335625Y1533895D01*
X335626Y1533898D01*
G37*
G36*
G01X340350Y1533895D02*
X340351Y1533898D01*
G02X341414Y1534538I1063J-563D01*
G02X342616Y1533336I0J-1202D01*
G01Y1533335D01*
G02X342463Y1532748I-1202J0D01*
G01X342458Y1532738D01*
X342457D01*
X342456Y1532736D01*
X340913Y1530066D01*
X340911Y1530061D01*
G02X338652Y1530800I-1072J545D01*
G01Y1530801D01*
G02X338786Y1531189I1187J-193D01*
G01X340350Y1533895D01*
G37*
G36*
G01X345074D02*
X345075Y1533898D01*
G02X346138Y1534538I1063J-563D01*
G02X347340Y1533336I0J-1202D01*
G01Y1533335D01*
G02X347187Y1532748I-1202J0D01*
G01X347182Y1532738D01*
X347181D01*
X347180Y1532736D01*
X345637Y1530066D01*
X345635Y1530061D01*
G02X343376Y1530800I-1072J545D01*
G01Y1530801D01*
G02X343510Y1531189I1187J-193D01*
G01X345074Y1533895D01*
G37*
G36*
G01X349798D02*
X349799Y1533898D01*
G02X350862Y1534538I1063J-563D01*
G02X352064Y1533336I0J-1202D01*
G01Y1533335D01*
G02X351911Y1532748I-1202J0D01*
G01X351906Y1532738D01*
X351905D01*
X351904Y1532736D01*
X350361Y1530066D01*
X350359Y1530061D01*
G02X348100Y1530800I-1072J545D01*
G01Y1530801D01*
G02X348234Y1531189I1187J-193D01*
G01X349798Y1533895D01*
G37*
G36*
G01X354524Y1533898D02*
G02X355587Y1534538I1063J-563D01*
G01X355589D01*
G02X356790Y1533336I-1J-1202D01*
G01Y1533335D01*
G02X356636Y1532748I-1203J2D01*
G01X356631Y1532738D01*
X356630D01*
X356629Y1532736D01*
X355086Y1530066D01*
X355084Y1530061D01*
G02X352825Y1530800I-1072J545D01*
G01Y1530801D01*
G02X352959Y1531189I1187J-193D01*
G01X354523Y1533895D01*
X354524Y1533898D01*
G37*
G36*
G01X359248D02*
G02X360311Y1534538I1063J-563D01*
G01X360313D01*
G02X361514Y1533336I-1J-1202D01*
G01Y1533335D01*
G02X361360Y1532748I-1203J2D01*
G01X361355Y1532738D01*
X361354D01*
X361353Y1532736D01*
X359810Y1530066D01*
X359808Y1530061D01*
G02X357549Y1530800I-1072J545D01*
G01Y1530801D01*
G02X357683Y1531189I1187J-193D01*
G01X359247Y1533895D01*
X359248Y1533898D01*
G37*
G36*
G01X363972Y1533895D02*
X363973Y1533898D01*
G02X365036Y1534538I1063J-563D01*
G02X366238Y1533336I0J-1202D01*
G01Y1533335D01*
G02X366085Y1532748I-1202J0D01*
G01X366080Y1532738D01*
X366079D01*
X366078Y1532736D01*
X364535Y1530066D01*
X364533Y1530061D01*
G02X362274Y1530800I-1072J545D01*
G01Y1530801D01*
G02X362408Y1531189I1187J-193D01*
G01X363972Y1533895D01*
G37*
G36*
G01X368696D02*
X368697Y1533898D01*
G02X369760Y1534538I1063J-563D01*
G02X370962Y1533336I0J-1202D01*
G01Y1533335D01*
G02X370809Y1532748I-1202J0D01*
G01X370804Y1532738D01*
X370803D01*
X370802Y1532736D01*
X369259Y1530066D01*
X369257Y1530061D01*
G02X366998Y1530800I-1072J545D01*
G01Y1530801D01*
G02X367132Y1531189I1187J-193D01*
G01X368696Y1533895D01*
G37*
G36*
G01X373420D02*
X373421Y1533898D01*
G02X374484Y1534538I1063J-563D01*
G02X375686Y1533336I0J-1202D01*
G01Y1533335D01*
G02X375533Y1532748I-1202J0D01*
G01X375528Y1532738D01*
X375527D01*
X375526Y1532736D01*
X373983Y1530066D01*
X373981Y1530061D01*
G02X371722Y1530800I-1072J545D01*
G01Y1530801D01*
G02X371856Y1531189I1187J-193D01*
G01X373420Y1533895D01*
G37*
G36*
G01X378146Y1533898D02*
G02X379209Y1534538I1063J-563D01*
G01X379211D01*
G02X380412Y1533336I-1J-1202D01*
G01Y1533335D01*
G02X380258Y1532748I-1203J2D01*
G01X380253Y1532738D01*
X380252D01*
X380251Y1532736D01*
X378708Y1530066D01*
X378706Y1530061D01*
G02X376447Y1530800I-1072J545D01*
G01Y1530801D01*
G02X376581Y1531189I1187J-193D01*
G01X378145Y1533895D01*
X378146Y1533898D01*
G37*
G36*
G01X382870D02*
G02X383933Y1534538I1063J-563D01*
G01X383935D01*
G02X385136Y1533336I-1J-1202D01*
G01Y1533335D01*
G02X384982Y1532748I-1203J2D01*
G01X384977Y1532738D01*
X384976D01*
X384975Y1532736D01*
X383432Y1530066D01*
X383430Y1530061D01*
G02X381171Y1530800I-1072J545D01*
G01Y1530801D01*
G02X381305Y1531189I1187J-193D01*
G01X382869Y1533895D01*
X382870Y1533898D01*
G37*
G36*
G01X387594Y1533895D02*
X387595Y1533898D01*
G02X388658Y1534538I1063J-563D01*
G02X389860Y1533336I0J-1202D01*
G01Y1533335D01*
G02X389707Y1532748I-1202J0D01*
G01X389702Y1532738D01*
X389701D01*
X389700Y1532736D01*
X388157Y1530066D01*
X388155Y1530061D01*
G02X385896Y1530800I-1072J545D01*
G01Y1530801D01*
G02X386030Y1531189I1187J-193D01*
G01X387594Y1533895D01*
G37*
G36*
G01X452840Y1533898D02*
G02X453903Y1534538I1063J-563D01*
G01X453905D01*
G02X455106Y1533336I-1J-1202D01*
G01Y1533335D01*
G02X454952Y1532748I-1203J2D01*
G01X454947Y1532738D01*
X454946D01*
X454945Y1532736D01*
X453402Y1530066D01*
X453400Y1530061D01*
G02X451141Y1530800I-1072J545D01*
G01Y1530801D01*
G02X451275Y1531189I1187J-193D01*
G01X452839Y1533895D01*
X452840Y1533898D01*
G37*
G36*
G01X457564D02*
G02X458627Y1534538I1063J-563D01*
G01X458629D01*
G02X459830Y1533336I-1J-1202D01*
G01Y1533335D01*
G02X459676Y1532748I-1203J2D01*
G01X459671Y1532738D01*
X459670D01*
X459669Y1532736D01*
X458126Y1530066D01*
X458124Y1530061D01*
G02X455865Y1530800I-1072J545D01*
G01Y1530801D01*
G02X455999Y1531189I1187J-193D01*
G01X457563Y1533895D01*
X457564Y1533898D01*
G37*
G36*
G01X462288D02*
G02X463351Y1534538I1063J-563D01*
G01X463353D01*
G02X464554Y1533336I-1J-1202D01*
G01Y1533335D01*
G02X464400Y1532748I-1203J2D01*
G01X464395Y1532738D01*
X464394D01*
X464393Y1532736D01*
X462850Y1530066D01*
X462848Y1530061D01*
G02X460589Y1530800I-1072J545D01*
G01Y1530801D01*
G02X460723Y1531189I1187J-193D01*
G01X462287Y1533895D01*
X462288Y1533898D01*
G37*
G36*
G01X467012Y1533895D02*
X467013Y1533898D01*
G02X468076Y1534538I1063J-563D01*
G02X469278Y1533336I0J-1202D01*
G01Y1533335D01*
G02X469125Y1532748I-1202J0D01*
G01X469120Y1532738D01*
X469119D01*
X469118Y1532736D01*
X467575Y1530066D01*
X467573Y1530061D01*
G02X465314Y1530800I-1072J545D01*
G01Y1530801D01*
G02X465448Y1531189I1187J-193D01*
G01X467012Y1533895D01*
G37*
G36*
G01X471736D02*
X471737Y1533898D01*
G02X472800Y1534538I1063J-563D01*
G02X474002Y1533336I0J-1202D01*
G01Y1533335D01*
G02X473849Y1532748I-1202J0D01*
G01X473844Y1532738D01*
X473843D01*
X473842Y1532736D01*
X472299Y1530066D01*
X472297Y1530061D01*
G02X470038Y1530800I-1072J545D01*
G01Y1530801D01*
G02X470172Y1531189I1187J-193D01*
G01X471736Y1533895D01*
G37*
G36*
G01X476462Y1533898D02*
G02X477525Y1534538I1063J-563D01*
G01X477527D01*
G02X478728Y1533336I-1J-1202D01*
G01Y1533335D01*
G02X478574Y1532748I-1203J2D01*
G01X478569Y1532738D01*
X478568D01*
X478567Y1532736D01*
X477024Y1530066D01*
X477022Y1530061D01*
G02X474763Y1530800I-1072J545D01*
G01Y1530801D01*
G02X474897Y1531189I1187J-193D01*
G01X476461Y1533895D01*
X476462Y1533898D01*
G37*
G36*
G01X481186D02*
G02X482249Y1534538I1063J-563D01*
G01X482251D01*
G02X483452Y1533336I-1J-1202D01*
G01Y1533335D01*
G02X483298Y1532748I-1203J2D01*
G01X483293Y1532738D01*
X483292D01*
X483291Y1532736D01*
X481748Y1530066D01*
X481746Y1530061D01*
G02X479487Y1530800I-1072J545D01*
G01Y1530801D01*
G02X479621Y1531189I1187J-193D01*
G01X481185Y1533895D01*
X481186Y1533898D01*
G37*
G36*
G01X485910D02*
G02X486973Y1534538I1063J-563D01*
G01X486975D01*
G02X488176Y1533336I-1J-1202D01*
G01Y1533335D01*
G02X488022Y1532748I-1203J2D01*
G01X488017Y1532738D01*
X488016D01*
X488015Y1532736D01*
X486472Y1530066D01*
X486470Y1530061D01*
G02X484211Y1530800I-1072J545D01*
G01Y1530801D01*
G02X484345Y1531189I1187J-193D01*
G01X485909Y1533895D01*
X485910Y1533898D01*
G37*
G36*
G01X490634Y1533895D02*
X490635Y1533898D01*
G02X491698Y1534538I1063J-563D01*
G02X492900Y1533336I0J-1202D01*
G01Y1533335D01*
G02X492747Y1532748I-1202J0D01*
G01X492742Y1532738D01*
X492741D01*
X492740Y1532736D01*
X491197Y1530066D01*
X491195Y1530061D01*
G02X488936Y1530800I-1072J545D01*
G01Y1530801D01*
G02X489070Y1531189I1187J-193D01*
G01X490634Y1533895D01*
G37*
G36*
G01X495358D02*
X495359Y1533898D01*
G02X496422Y1534538I1063J-563D01*
G02X497624Y1533336I0J-1202D01*
G01Y1533335D01*
G02X497471Y1532748I-1202J0D01*
G01X497466Y1532738D01*
X497465D01*
X497464Y1532736D01*
X495921Y1530066D01*
X495919Y1530061D01*
G02X493660Y1530800I-1072J545D01*
G01Y1530801D01*
G02X493794Y1531189I1187J-193D01*
G01X495358Y1533895D01*
G37*
G36*
G01X500084Y1533898D02*
G02X501147Y1534538I1063J-563D01*
G01X501149D01*
G02X502350Y1533336I-1J-1202D01*
G01Y1533335D01*
G02X502196Y1532748I-1203J2D01*
G01X502191Y1532738D01*
X502190D01*
X502189Y1532736D01*
X500646Y1530066D01*
X500644Y1530061D01*
G02X498385Y1530800I-1072J545D01*
G01Y1530801D01*
G02X498519Y1531189I1187J-193D01*
G01X500083Y1533895D01*
X500084Y1533898D01*
G37*
G36*
G01X504808D02*
G02X505871Y1534538I1063J-563D01*
G01X505873D01*
G02X507074Y1533336I-1J-1202D01*
G01Y1533335D01*
G02X506920Y1532748I-1203J2D01*
G01X506915Y1532738D01*
X506914D01*
X506913Y1532736D01*
X505370Y1530066D01*
X505368Y1530061D01*
G02X503109Y1530800I-1072J545D01*
G01Y1530801D01*
G02X503243Y1531189I1187J-193D01*
G01X504807Y1533895D01*
X504808Y1533898D01*
G37*
G36*
G01X509532D02*
G02X510595Y1534538I1063J-563D01*
G01X510597D01*
G02X511798Y1533336I-1J-1202D01*
G01Y1533335D01*
G02X511644Y1532748I-1203J2D01*
G01X511639Y1532738D01*
X511638D01*
X511637Y1532736D01*
X510094Y1530066D01*
X510092Y1530061D01*
G02X507833Y1530800I-1072J545D01*
G01Y1530801D01*
G02X507967Y1531189I1187J-193D01*
G01X509531Y1533895D01*
X509532Y1533898D01*
G37*
G36*
G01X514256Y1533895D02*
X514257Y1533898D01*
G02X515320Y1534538I1063J-563D01*
G02X516522Y1533336I0J-1202D01*
G01Y1533335D01*
G02X516369Y1532748I-1202J0D01*
G01X516364Y1532738D01*
X516363D01*
X516362Y1532736D01*
X514819Y1530066D01*
X514817Y1530061D01*
G02X512558Y1530800I-1072J545D01*
G01Y1530801D01*
G02X512692Y1531189I1187J-193D01*
G01X514256Y1533895D01*
G37*
G36*
G01X518980D02*
X518981Y1533898D01*
G02X520044Y1534538I1063J-563D01*
G02X521246Y1533336I0J-1202D01*
G01Y1533335D01*
G02X521093Y1532748I-1202J0D01*
G01X521088Y1532738D01*
X521087D01*
X521086Y1532736D01*
X519543Y1530066D01*
X519541Y1530061D01*
G02X517282Y1530800I-1072J545D01*
G01Y1530801D01*
G02X517416Y1531189I1187J-193D01*
G01X518980Y1533895D01*
G37*
G36*
G01X523706Y1533898D02*
G02X524769Y1534538I1063J-563D01*
G01X524771D01*
G02X525972Y1533336I-1J-1202D01*
G01Y1533335D01*
G02X525818Y1532748I-1203J2D01*
G01X525813Y1532738D01*
X525812D01*
X525811Y1532736D01*
X524268Y1530066D01*
X524266Y1530061D01*
G02X522007Y1530800I-1072J545D01*
G01Y1530801D01*
G02X522141Y1531189I1187J-193D01*
G01X523705Y1533895D01*
X523706Y1533898D01*
G37*
G36*
G01X580905Y1533902D02*
G02X581965Y1534538I1060J-565D01*
G01X581967D01*
G02X583168Y1533336I-1J-1202D01*
G02X583007Y1532736I-1204J1D01*
G01X581462Y1530063D01*
X581460Y1530059D01*
G02X580390Y1529406I-1070J550D01*
G02X579188Y1530608I0J1202D01*
G01Y1530610D01*
G02X579337Y1531189I1202J-1D01*
G01X580903Y1533899D01*
X580905Y1533902D01*
G37*
G36*
G01X585629D02*
G02X586689Y1534538I1060J-565D01*
G01X586691D01*
G02X587892Y1533336I-1J-1202D01*
G02X587731Y1532736I-1204J1D01*
G01X586186Y1530063D01*
X586184Y1530059D01*
G02X585114Y1529406I-1070J550D01*
G02X583912Y1530608I0J1202D01*
G01Y1530610D01*
G02X584061Y1531189I1202J-1D01*
G01X585627Y1533899D01*
X585629Y1533902D01*
G37*
G36*
G01X590353D02*
G02X591413Y1534538I1060J-565D01*
G01X591415D01*
G02X592616Y1533336I-1J-1202D01*
G02X592455Y1532736I-1204J1D01*
G01X590910Y1530063D01*
X590908Y1530059D01*
G02X589838Y1529406I-1070J550D01*
G02X588636Y1530608I0J1202D01*
G01Y1530610D01*
G02X588785Y1531189I1202J-1D01*
G01X590351Y1533899D01*
X590353Y1533902D01*
G37*
G36*
G01X595076Y1533899D02*
X595078Y1533902D01*
G02X596138Y1534538I1060J-565D01*
G02X597340Y1533336I0J-1202D01*
G01Y1533335D01*
G02X597180Y1532736I-1203J1D01*
G01X595635Y1530063D01*
X595633Y1530059D01*
G02X594563Y1529406I-1070J550D01*
G01X594561D01*
G02X593360Y1530608I1J1202D01*
G01Y1530610D01*
G02X593510Y1531189I1203J-3D01*
G01X595076Y1533899D01*
G37*
G36*
G01X599800D02*
X599802Y1533902D01*
G02X600862Y1534538I1060J-565D01*
G02X602064Y1533336I0J-1202D01*
G01Y1533335D01*
G02X601904Y1532736I-1203J1D01*
G01X600359Y1530063D01*
X600357Y1530059D01*
G02X599287Y1529406I-1070J550D01*
G01X599285D01*
G02X598084Y1530608I1J1202D01*
G01Y1530610D01*
G02X598234Y1531189I1203J-3D01*
G01X599800Y1533899D01*
G37*
G36*
G01X604527Y1533902D02*
G02X605587Y1534538I1060J-565D01*
G01X605589D01*
G02X606790Y1533336I-1J-1202D01*
G02X606629Y1532736I-1204J1D01*
G01X605084Y1530063D01*
X605082Y1530059D01*
G02X604012Y1529406I-1070J550D01*
G02X602810Y1530608I0J1202D01*
G01Y1530610D01*
G02X602959Y1531189I1202J-1D01*
G01X604525Y1533899D01*
X604527Y1533902D01*
G37*
G36*
G01X609251D02*
G02X610311Y1534538I1060J-565D01*
G01X610313D01*
G02X611514Y1533336I-1J-1202D01*
G02X611353Y1532736I-1204J1D01*
G01X609808Y1530063D01*
X609806Y1530059D01*
G02X608736Y1529406I-1070J550D01*
G02X607534Y1530608I0J1202D01*
G01Y1530610D01*
G02X607683Y1531189I1202J-1D01*
G01X609249Y1533899D01*
X609251Y1533902D01*
G37*
G36*
G01X613975D02*
G02X615035Y1534538I1060J-565D01*
G01X615037D01*
G02X616238Y1533336I-1J-1202D01*
G02X616077Y1532736I-1204J1D01*
G01X614532Y1530063D01*
X614530Y1530059D01*
G02X613460Y1529406I-1070J550D01*
G02X612258Y1530608I0J1202D01*
G01Y1530610D01*
G02X612407Y1531189I1202J-1D01*
G01X613973Y1533899D01*
X613975Y1533902D01*
G37*
G36*
G01X618698Y1533899D02*
X618700Y1533902D01*
G02X619760Y1534538I1060J-565D01*
G02X620962Y1533336I0J-1202D01*
G01Y1533335D01*
G02X620802Y1532736I-1203J1D01*
G01X619257Y1530063D01*
X619255Y1530059D01*
G02X618185Y1529406I-1070J550D01*
G01X618183D01*
G02X616982Y1530608I1J1202D01*
G01Y1530610D01*
G02X617132Y1531189I1203J-3D01*
G01X618698Y1533899D01*
G37*
G36*
G01X623422D02*
X623424Y1533902D01*
G02X624484Y1534538I1060J-565D01*
G02X625686Y1533336I0J-1202D01*
G01Y1533335D01*
G02X625526Y1532736I-1203J1D01*
G01X623981Y1530063D01*
X623979Y1530059D01*
G02X622909Y1529406I-1070J550D01*
G01X622907D01*
G02X621706Y1530608I1J1202D01*
G01Y1530610D01*
G02X621856Y1531189I1203J-3D01*
G01X623422Y1533899D01*
G37*
G36*
G01X628149Y1533902D02*
G02X629209Y1534538I1060J-565D01*
G01X629211D01*
G02X630412Y1533336I-1J-1202D01*
G02X630251Y1532736I-1204J1D01*
G01X628706Y1530063D01*
X628704Y1530059D01*
G02X627634Y1529406I-1070J550D01*
G02X626432Y1530608I0J1202D01*
G01Y1530610D01*
G02X626581Y1531189I1202J-1D01*
G01X628147Y1533899D01*
X628149Y1533902D01*
G37*
G36*
G01X632873D02*
G02X633933Y1534538I1060J-565D01*
G01X633935D01*
G02X635136Y1533336I-1J-1202D01*
G02X634975Y1532736I-1204J1D01*
G01X633430Y1530063D01*
X633428Y1530059D01*
G02X632358Y1529406I-1070J550D01*
G02X631156Y1530608I0J1202D01*
G01Y1530610D01*
G02X631305Y1531189I1202J-1D01*
G01X632871Y1533899D01*
X632873Y1533902D01*
G37*
G36*
G01X637597D02*
G02X638657Y1534538I1060J-565D01*
G01X638659D01*
G02X639860Y1533336I-1J-1202D01*
G02X639699Y1532736I-1204J1D01*
G01X638154Y1530063D01*
X638152Y1530059D01*
G02X637082Y1529406I-1070J550D01*
G02X635880Y1530608I0J1202D01*
G01Y1530610D01*
G02X636029Y1531189I1202J-1D01*
G01X637595Y1533899D01*
X637597Y1533902D01*
G37*
G36*
G01X642320Y1533899D02*
X642322Y1533902D01*
G02X643382Y1534538I1060J-565D01*
G02X644584Y1533336I0J-1202D01*
G01Y1533335D01*
G02X644424Y1532736I-1203J1D01*
G01X642879Y1530063D01*
X642877Y1530059D01*
G02X641807Y1529406I-1070J550D01*
G01X641805D01*
G02X640604Y1530608I1J1202D01*
G01Y1530610D01*
G02X640754Y1531189I1203J-3D01*
G01X642320Y1533899D01*
G37*
G36*
G01X647044D02*
X647046Y1533902D01*
G02X648106Y1534538I1060J-565D01*
G02X649308Y1533336I0J-1202D01*
G01Y1533335D01*
G02X649148Y1532736I-1203J1D01*
G01X647603Y1530063D01*
X647601Y1530059D01*
G02X646531Y1529406I-1070J550D01*
G01X646529D01*
G02X645328Y1530608I1J1202D01*
G01Y1530610D01*
G02X645478Y1531189I1203J-3D01*
G01X647044Y1533899D01*
G37*
G36*
G01X651771Y1533902D02*
G02X652831Y1534538I1060J-565D01*
G01X652833D01*
G02X654034Y1533336I-1J-1202D01*
G02X653873Y1532736I-1204J1D01*
G01X652328Y1530063D01*
X652326Y1530059D01*
G02X651256Y1529406I-1070J550D01*
G02X650054Y1530608I0J1202D01*
G01Y1530610D01*
G02X650203Y1531189I1202J-1D01*
G01X651769Y1533899D01*
X651771Y1533902D01*
G37*
G36*
G01X1196543Y1553264D02*
G02X1197603Y1553900I1060J-565D01*
G01X1197605D01*
G02X1198806Y1552698I-1J-1202D01*
G02X1198645Y1552098I-1204J1D01*
G01X1197100Y1549425D01*
X1197098Y1549421D01*
G02X1196028Y1548768I-1070J550D01*
G02X1194826Y1549970I0J1202D01*
G01Y1549972D01*
G02X1194975Y1550551I1202J-1D01*
G01X1196541Y1553261D01*
X1196543Y1553264D01*
G37*
G36*
G01X1201267D02*
G02X1202327Y1553900I1060J-565D01*
G01X1202329D01*
G02X1203530Y1552698I-1J-1202D01*
G02X1203369Y1552098I-1204J1D01*
G01X1201824Y1549425D01*
X1201822Y1549421D01*
G02X1200752Y1548768I-1070J550D01*
G02X1199550Y1549970I0J1202D01*
G01Y1549972D01*
G02X1199699Y1550551I1202J-1D01*
G01X1201265Y1553261D01*
X1201267Y1553264D01*
G37*
G36*
G01X1205991D02*
G02X1207051Y1553900I1060J-565D01*
G01X1207052D01*
G02X1208254Y1552698I0J-1202D01*
G01Y1552697D01*
G02X1208094Y1552098I-1203J1D01*
G01X1206549Y1549425D01*
X1206547Y1549421D01*
G02X1205477Y1548768I-1070J550D01*
G01X1205476D01*
G02X1204274Y1549970I0J1202D01*
G01Y1549972D01*
G02X1204423Y1550551I1202J-1D01*
G01X1205989Y1553261D01*
X1205991Y1553264D01*
G37*
G36*
G01X1210714Y1553261D02*
X1210716Y1553264D01*
G02X1211776Y1553900I1060J-565D01*
G02X1212978Y1552698I0J-1202D01*
G01Y1552697D01*
G02X1212818Y1552098I-1203J1D01*
G01X1211273Y1549425D01*
X1211271Y1549421D01*
G02X1210201Y1548768I-1070J550D01*
G01X1210199D01*
G02X1208998Y1549970I1J1202D01*
G01Y1549972D01*
G02X1209148Y1550551I1203J-3D01*
G01X1210714Y1553261D01*
G37*
G36*
G01X1215438D02*
X1215440Y1553264D01*
G02X1216500Y1553900I1060J-565D01*
G02X1217702Y1552698I0J-1202D01*
G01Y1552697D01*
G02X1217542Y1552098I-1203J1D01*
G01X1215997Y1549425D01*
X1215995Y1549421D01*
G02X1214925Y1548768I-1070J550D01*
G01X1214923D01*
G02X1213722Y1549970I1J1202D01*
G01Y1549972D01*
G02X1213872Y1550551I1203J-3D01*
G01X1215438Y1553261D01*
G37*
G36*
G01X1220165Y1553264D02*
G02X1221225Y1553900I1060J-565D01*
G01X1221227D01*
G02X1222428Y1552698I-1J-1202D01*
G02X1222267Y1552098I-1204J1D01*
G01X1220722Y1549425D01*
X1220720Y1549421D01*
G02X1219650Y1548768I-1070J550D01*
G02X1218448Y1549970I0J1202D01*
G01Y1549972D01*
G02X1218597Y1550551I1202J-1D01*
G01X1220163Y1553261D01*
X1220165Y1553264D01*
G37*
G36*
G01X1224889D02*
G02X1225949Y1553900I1060J-565D01*
G01X1225951D01*
G02X1227152Y1552698I-1J-1202D01*
G02X1226991Y1552098I-1204J1D01*
G01X1225446Y1549425D01*
X1225444Y1549421D01*
G02X1224374Y1548768I-1070J550D01*
G02X1223172Y1549970I0J1202D01*
G01Y1549972D01*
G02X1223321Y1550551I1202J-1D01*
G01X1224887Y1553261D01*
X1224889Y1553264D01*
G37*
G36*
G01X1229613D02*
G02X1230673Y1553900I1060J-565D01*
G01X1230674D01*
G02X1231876Y1552698I0J-1202D01*
G01Y1552697D01*
G02X1231716Y1552098I-1203J1D01*
G01X1230171Y1549425D01*
X1230169Y1549421D01*
G02X1229099Y1548768I-1070J550D01*
G01X1229098D01*
G02X1227896Y1549970I0J1202D01*
G01Y1549972D01*
G02X1228045Y1550551I1202J-1D01*
G01X1229611Y1553261D01*
X1229613Y1553264D01*
G37*
G36*
G01X1243787D02*
G02X1244847Y1553900I1060J-565D01*
G01X1244849D01*
G02X1246050Y1552698I-1J-1202D01*
G02X1245889Y1552098I-1204J1D01*
G01X1244344Y1549425D01*
X1244342Y1549421D01*
G02X1243272Y1548768I-1070J550D01*
G02X1242070Y1549970I0J1202D01*
G01Y1549972D01*
G02X1242219Y1550551I1202J-1D01*
G01X1243785Y1553261D01*
X1243787Y1553264D01*
G37*
G36*
G01X1248511D02*
G02X1249571Y1553900I1060J-565D01*
G01X1249572D01*
G02X1250774Y1552698I0J-1202D01*
G01Y1552697D01*
G02X1250614Y1552098I-1203J1D01*
G01X1249069Y1549425D01*
X1249067Y1549421D01*
G02X1247997Y1548768I-1070J550D01*
G01X1247996D01*
G02X1246794Y1549970I0J1202D01*
G01Y1549972D01*
G02X1246943Y1550551I1202J-1D01*
G01X1248509Y1553261D01*
X1248511Y1553264D01*
G37*
G36*
G01X1253234Y1553261D02*
X1253236Y1553264D01*
G02X1254296Y1553900I1060J-565D01*
G02X1255498Y1552698I0J-1202D01*
G01Y1552697D01*
G02X1255338Y1552098I-1203J1D01*
G01X1253793Y1549425D01*
X1253791Y1549421D01*
G02X1252721Y1548768I-1070J550D01*
G01X1252719D01*
G02X1251518Y1549970I1J1202D01*
G01Y1549972D01*
G02X1251668Y1550551I1203J-3D01*
G01X1253234Y1553261D01*
G37*
G36*
G01X1262685Y1553264D02*
G02X1263745Y1553900I1060J-565D01*
G01X1263747D01*
G02X1264948Y1552698I-1J-1202D01*
G02X1264787Y1552098I-1204J1D01*
G01X1263242Y1549425D01*
X1263240Y1549421D01*
G02X1262170Y1548768I-1070J550D01*
G02X1260968Y1549970I0J1202D01*
G01Y1549972D01*
G02X1261117Y1550551I1202J-1D01*
G01X1262683Y1553261D01*
X1262685Y1553264D01*
G37*
G36*
G01X1267409D02*
G02X1268469Y1553900I1060J-565D01*
G01X1268471D01*
G02X1269672Y1552698I-1J-1202D01*
G02X1269511Y1552098I-1204J1D01*
G01X1267966Y1549425D01*
X1267964Y1549421D01*
G02X1266894Y1548768I-1070J550D01*
G02X1265692Y1549970I0J1202D01*
G01Y1549972D01*
G02X1265841Y1550551I1202J-1D01*
G01X1267407Y1553261D01*
X1267409Y1553264D01*
G37*
G36*
G01X1324605D02*
G02X1325665Y1553900I1060J-565D01*
G01X1325667D01*
G02X1326868Y1552698I-1J-1202D01*
G02X1326707Y1552098I-1204J1D01*
G01X1325162Y1549425D01*
X1325160Y1549421D01*
G02X1324090Y1548768I-1070J550D01*
G02X1322888Y1549970I0J1202D01*
G01Y1549972D01*
G02X1323037Y1550551I1202J-1D01*
G01X1324603Y1553261D01*
X1324605Y1553264D01*
G37*
G36*
G01X1329329D02*
G02X1330389Y1553900I1060J-565D01*
G01X1330391D01*
G02X1331592Y1552698I-1J-1202D01*
G02X1331431Y1552098I-1204J1D01*
G01X1329886Y1549425D01*
X1329884Y1549421D01*
G02X1328814Y1548768I-1070J550D01*
G02X1327612Y1549970I0J1202D01*
G01Y1549972D01*
G02X1327761Y1550551I1202J-1D01*
G01X1329327Y1553261D01*
X1329329Y1553264D01*
G37*
G36*
G01X1334053D02*
G02X1335113Y1553900I1060J-565D01*
G01X1335114D01*
G02X1336316Y1552698I0J-1202D01*
G01Y1552697D01*
G02X1336156Y1552098I-1203J1D01*
G01X1334611Y1549425D01*
X1334609Y1549421D01*
G02X1333539Y1548768I-1070J550D01*
G01X1333538D01*
G02X1332336Y1549970I0J1202D01*
G01Y1549972D01*
G02X1332485Y1550551I1202J-1D01*
G01X1334051Y1553261D01*
X1334053Y1553264D01*
G37*
G36*
G01X1338776Y1553261D02*
X1338778Y1553264D01*
G02X1339838Y1553900I1060J-565D01*
G02X1341040Y1552698I0J-1202D01*
G01Y1552697D01*
G02X1340880Y1552098I-1203J1D01*
G01X1339335Y1549425D01*
X1339333Y1549421D01*
G02X1338263Y1548768I-1070J550D01*
G01X1338261D01*
G02X1337060Y1549970I1J1202D01*
G01Y1549972D01*
G02X1337210Y1550551I1203J-3D01*
G01X1338776Y1553261D01*
G37*
G36*
G01X1343500D02*
X1343502Y1553264D01*
G02X1344562Y1553900I1060J-565D01*
G02X1345764Y1552698I0J-1202D01*
G01Y1552697D01*
G02X1345604Y1552098I-1203J1D01*
G01X1344059Y1549425D01*
X1344057Y1549421D01*
G02X1342987Y1548768I-1070J550D01*
G01X1342985D01*
G02X1341784Y1549970I1J1202D01*
G01Y1549972D01*
G02X1341934Y1550551I1203J-3D01*
G01X1343500Y1553261D01*
G37*
G36*
G01X1348227Y1553264D02*
G02X1349287Y1553900I1060J-565D01*
G01X1349289D01*
G02X1350490Y1552698I-1J-1202D01*
G02X1350329Y1552098I-1204J1D01*
G01X1348784Y1549425D01*
X1348782Y1549421D01*
G02X1347712Y1548768I-1070J550D01*
G02X1346510Y1549970I0J1202D01*
G01Y1549972D01*
G02X1346659Y1550551I1202J-1D01*
G01X1348225Y1553261D01*
X1348227Y1553264D01*
G37*
G36*
G01X1352951D02*
G02X1354011Y1553900I1060J-565D01*
G01X1354013D01*
G02X1355214Y1552698I-1J-1202D01*
G02X1355053Y1552098I-1204J1D01*
G01X1353508Y1549425D01*
X1353506Y1549421D01*
G02X1352436Y1548768I-1070J550D01*
G02X1351234Y1549970I0J1202D01*
G01Y1549972D01*
G02X1351383Y1550551I1202J-1D01*
G01X1352949Y1553261D01*
X1352951Y1553264D01*
G37*
G36*
G01X1357675D02*
G02X1358735Y1553900I1060J-565D01*
G01X1358736D01*
G02X1359938Y1552698I0J-1202D01*
G01Y1552697D01*
G02X1359778Y1552098I-1203J1D01*
G01X1358233Y1549425D01*
X1358231Y1549421D01*
G02X1357161Y1548768I-1070J550D01*
G01X1357160D01*
G02X1355958Y1549970I0J1202D01*
G01Y1549972D01*
G02X1356107Y1550551I1202J-1D01*
G01X1357673Y1553261D01*
X1357675Y1553264D01*
G37*
G36*
G01X1362398Y1553261D02*
X1362400Y1553264D01*
G02X1363460Y1553900I1060J-565D01*
G02X1364662Y1552698I0J-1202D01*
G01Y1552697D01*
G02X1364502Y1552098I-1203J1D01*
G01X1362957Y1549425D01*
X1362955Y1549421D01*
G02X1361885Y1548768I-1070J550D01*
G01X1361883D01*
G02X1360682Y1549970I1J1202D01*
G01Y1549972D01*
G02X1360832Y1550551I1203J-3D01*
G01X1362398Y1553261D01*
G37*
G36*
G01X1367122D02*
X1367124Y1553264D01*
G02X1368184Y1553900I1060J-565D01*
G02X1369386Y1552698I0J-1202D01*
G01Y1552697D01*
G02X1369226Y1552098I-1203J1D01*
G01X1367681Y1549425D01*
X1367679Y1549421D01*
G02X1366609Y1548768I-1070J550D01*
G01X1366607D01*
G02X1365406Y1549970I1J1202D01*
G01Y1549972D01*
G02X1365556Y1550551I1203J-3D01*
G01X1367122Y1553261D01*
G37*
G36*
G01X1371849Y1553264D02*
G02X1372909Y1553900I1060J-565D01*
G01X1372911D01*
G02X1374112Y1552698I-1J-1202D01*
G02X1373951Y1552098I-1204J1D01*
G01X1372406Y1549425D01*
X1372404Y1549421D01*
G02X1371334Y1548768I-1070J550D01*
G02X1370132Y1549970I0J1202D01*
G01Y1549972D01*
G02X1370281Y1550551I1202J-1D01*
G01X1371847Y1553261D01*
X1371849Y1553264D01*
G37*
G36*
G01X1376573D02*
G02X1377633Y1553900I1060J-565D01*
G01X1377635D01*
G02X1378836Y1552698I-1J-1202D01*
G02X1378675Y1552098I-1204J1D01*
G01X1377130Y1549425D01*
X1377128Y1549421D01*
G02X1376058Y1548768I-1070J550D01*
G02X1374856Y1549970I0J1202D01*
G01Y1549972D01*
G02X1375005Y1550551I1202J-1D01*
G01X1376571Y1553261D01*
X1376573Y1553264D01*
G37*
G36*
G01X1381297D02*
G02X1382357Y1553900I1060J-565D01*
G01X1382358D01*
G02X1383560Y1552698I0J-1202D01*
G01Y1552697D01*
G02X1383400Y1552098I-1203J1D01*
G01X1381855Y1549425D01*
X1381853Y1549421D01*
G02X1380783Y1548768I-1070J550D01*
G01X1380782D01*
G02X1379580Y1549970I0J1202D01*
G01Y1549972D01*
G02X1379729Y1550551I1202J-1D01*
G01X1381295Y1553261D01*
X1381297Y1553264D01*
G37*
G36*
G01X1386020Y1553261D02*
X1386022Y1553264D01*
G02X1387082Y1553900I1060J-565D01*
G02X1388284Y1552698I0J-1202D01*
G01Y1552697D01*
G02X1388124Y1552098I-1203J1D01*
G01X1386579Y1549425D01*
X1386577Y1549421D01*
G02X1385507Y1548768I-1070J550D01*
G01X1385505D01*
G02X1384304Y1549970I1J1202D01*
G01Y1549972D01*
G02X1384454Y1550551I1203J-3D01*
G01X1386020Y1553261D01*
G37*
G36*
G01X1395471Y1553264D02*
G02X1396531Y1553900I1060J-565D01*
G01X1396533D01*
G02X1397734Y1552698I-1J-1202D01*
G02X1397573Y1552098I-1204J1D01*
G01X1396028Y1549425D01*
X1396026Y1549421D01*
G02X1394956Y1548768I-1070J550D01*
G02X1393754Y1549970I0J1202D01*
G01Y1549972D01*
G02X1393903Y1550551I1202J-1D01*
G01X1395469Y1553261D01*
X1395471Y1553264D01*
G37*
G36*
G01X1460717D02*
G02X1461777Y1553900I1060J-565D01*
G01X1461779D01*
G02X1462980Y1552698I-1J-1202D01*
G02X1462819Y1552098I-1204J1D01*
G01X1461274Y1549425D01*
X1461272Y1549421D01*
G02X1460202Y1548768I-1070J550D01*
G02X1459000Y1549970I0J1202D01*
G01Y1549972D01*
G02X1459149Y1550551I1202J-1D01*
G01X1460715Y1553261D01*
X1460717Y1553264D01*
G37*
G36*
G01X1465441D02*
G02X1466501Y1553900I1060J-565D01*
G01X1466503D01*
G02X1467704Y1552698I-1J-1202D01*
G02X1467543Y1552098I-1204J1D01*
G01X1465998Y1549425D01*
X1465996Y1549421D01*
G02X1464926Y1548768I-1070J550D01*
G02X1463724Y1549970I0J1202D01*
G01Y1549972D01*
G02X1463873Y1550551I1202J-1D01*
G01X1465439Y1553261D01*
X1465441Y1553264D01*
G37*
G36*
G01X1470165D02*
G02X1471225Y1553900I1060J-565D01*
G01X1471227D01*
G02X1472428Y1552698I-1J-1202D01*
G02X1472267Y1552098I-1204J1D01*
G01X1470722Y1549425D01*
X1470720Y1549421D01*
G02X1469650Y1548768I-1070J550D01*
G02X1468448Y1549970I0J1202D01*
G01Y1549972D01*
G02X1468597Y1550551I1202J-1D01*
G01X1470163Y1553261D01*
X1470165Y1553264D01*
G37*
G36*
G01X1474888Y1553261D02*
X1474890Y1553264D01*
G02X1475950Y1553900I1060J-565D01*
G02X1477152Y1552698I0J-1202D01*
G01Y1552697D01*
G02X1476992Y1552098I-1203J1D01*
G01X1475447Y1549425D01*
X1475445Y1549421D01*
G02X1474375Y1548768I-1070J550D01*
G01X1474373D01*
G02X1473172Y1549970I1J1202D01*
G01Y1549972D01*
G02X1473322Y1550551I1203J-3D01*
G01X1474888Y1553261D01*
G37*
G36*
G01X1479612D02*
X1479614Y1553264D01*
G02X1480674Y1553900I1060J-565D01*
G02X1481876Y1552698I0J-1202D01*
G01Y1552697D01*
G02X1481716Y1552098I-1203J1D01*
G01X1480171Y1549425D01*
X1480169Y1549421D01*
G02X1479099Y1548768I-1070J550D01*
G01X1479097D01*
G02X1477896Y1549970I1J1202D01*
G01Y1549972D01*
G02X1478046Y1550551I1203J-3D01*
G01X1479612Y1553261D01*
G37*
G36*
G01X1484339Y1553264D02*
G02X1485399Y1553900I1060J-565D01*
G01X1485401D01*
G02X1486602Y1552698I-1J-1202D01*
G02X1486441Y1552098I-1204J1D01*
G01X1484896Y1549425D01*
X1484894Y1549421D01*
G02X1483824Y1548768I-1070J550D01*
G02X1482622Y1549970I0J1202D01*
G01Y1549972D01*
G02X1482771Y1550551I1202J-1D01*
G01X1484337Y1553261D01*
X1484339Y1553264D01*
G37*
G36*
G01X1489063D02*
G02X1490123Y1553900I1060J-565D01*
G01X1490125D01*
G02X1491326Y1552698I-1J-1202D01*
G02X1491165Y1552098I-1204J1D01*
G01X1489620Y1549425D01*
X1489618Y1549421D01*
G02X1488548Y1548768I-1070J550D01*
G02X1487346Y1549970I0J1202D01*
G01Y1549972D01*
G02X1487495Y1550551I1202J-1D01*
G01X1489061Y1553261D01*
X1489063Y1553264D01*
G37*
G36*
G01X1493787D02*
G02X1494847Y1553900I1060J-565D01*
G01X1494849D01*
G02X1496050Y1552698I-1J-1202D01*
G02X1495889Y1552098I-1204J1D01*
G01X1494344Y1549425D01*
X1494342Y1549421D01*
G02X1493272Y1548768I-1070J550D01*
G02X1492070Y1549970I0J1202D01*
G01Y1549972D01*
G02X1492219Y1550551I1202J-1D01*
G01X1493785Y1553261D01*
X1493787Y1553264D01*
G37*
G36*
G01X1498510Y1553261D02*
X1498512Y1553264D01*
G02X1499572Y1553900I1060J-565D01*
G02X1500774Y1552698I0J-1202D01*
G01Y1552697D01*
G02X1500614Y1552098I-1203J1D01*
G01X1499069Y1549425D01*
X1499067Y1549421D01*
G02X1497997Y1548768I-1070J550D01*
G01X1497995D01*
G02X1496794Y1549970I1J1202D01*
G01Y1549972D01*
G02X1496944Y1550551I1203J-3D01*
G01X1498510Y1553261D01*
G37*
G36*
G01X1503234D02*
X1503236Y1553264D01*
G02X1504296Y1553900I1060J-565D01*
G02X1505498Y1552698I0J-1202D01*
G01Y1552697D01*
G02X1505338Y1552098I-1203J1D01*
G01X1503793Y1549425D01*
X1503791Y1549421D01*
G02X1502721Y1548768I-1070J550D01*
G01X1502719D01*
G02X1501518Y1549970I1J1202D01*
G01Y1549972D01*
G02X1501668Y1550551I1203J-3D01*
G01X1503234Y1553261D01*
G37*
G36*
G01X1507961Y1553264D02*
G02X1509021Y1553900I1060J-565D01*
G01X1509023D01*
G02X1510224Y1552698I-1J-1202D01*
G02X1510063Y1552098I-1204J1D01*
G01X1508518Y1549425D01*
X1508516Y1549421D01*
G02X1507446Y1548768I-1070J550D01*
G02X1506244Y1549970I0J1202D01*
G01Y1549972D01*
G02X1506393Y1550551I1202J-1D01*
G01X1507959Y1553261D01*
X1507961Y1553264D01*
G37*
G36*
G01X1512685D02*
G02X1513745Y1553900I1060J-565D01*
G01X1513747D01*
G02X1514948Y1552698I-1J-1202D01*
G02X1514787Y1552098I-1204J1D01*
G01X1513242Y1549425D01*
X1513240Y1549421D01*
G02X1512170Y1548768I-1070J550D01*
G02X1510968Y1549970I0J1202D01*
G01Y1549972D01*
G02X1511117Y1550551I1202J-1D01*
G01X1512683Y1553261D01*
X1512685Y1553264D01*
G37*
G36*
G01X1517409D02*
G02X1518469Y1553900I1060J-565D01*
G01X1518471D01*
G02X1519672Y1552698I-1J-1202D01*
G02X1519511Y1552098I-1204J1D01*
G01X1517966Y1549425D01*
X1517964Y1549421D01*
G02X1516894Y1548768I-1070J550D01*
G02X1515692Y1549970I0J1202D01*
G01Y1549972D01*
G02X1515841Y1550551I1202J-1D01*
G01X1517407Y1553261D01*
X1517409Y1553264D01*
G37*
G36*
G01X1522132Y1553261D02*
X1522134Y1553264D01*
G02X1523194Y1553900I1060J-565D01*
G02X1524396Y1552698I0J-1202D01*
G01Y1552697D01*
G02X1524236Y1552098I-1203J1D01*
G01X1522691Y1549425D01*
X1522689Y1549421D01*
G02X1521619Y1548768I-1070J550D01*
G01X1521617D01*
G02X1520416Y1549970I1J1202D01*
G01Y1549972D01*
G02X1520566Y1550551I1203J-3D01*
G01X1522132Y1553261D01*
G37*
G36*
G01X1526856D02*
X1526858Y1553264D01*
G02X1527918Y1553900I1060J-565D01*
G02X1529120Y1552698I0J-1202D01*
G01Y1552697D01*
G02X1528960Y1552098I-1203J1D01*
G01X1527415Y1549425D01*
X1527413Y1549421D01*
G02X1526343Y1548768I-1070J550D01*
G01X1526341D01*
G02X1525140Y1549970I1J1202D01*
G01Y1549972D01*
G02X1525290Y1550551I1203J-3D01*
G01X1526856Y1553261D01*
G37*
G36*
G01X1531583Y1553264D02*
G02X1532643Y1553900I1060J-565D01*
G01X1532645D01*
G02X1533846Y1552698I-1J-1202D01*
G02X1533685Y1552098I-1204J1D01*
G01X1532140Y1549425D01*
X1532138Y1549421D01*
G02X1531068Y1548768I-1070J550D01*
G02X1529866Y1549970I0J1202D01*
G01Y1549972D01*
G02X1530015Y1550551I1202J-1D01*
G01X1531581Y1553261D01*
X1531583Y1553264D01*
G37*
G36*
G01X1588779D02*
G02X1589839Y1553900I1060J-565D01*
G01X1589841D01*
G02X1591042Y1552698I-1J-1202D01*
G02X1590881Y1552098I-1204J1D01*
G01X1589336Y1549425D01*
X1589334Y1549421D01*
G02X1588264Y1548768I-1070J550D01*
G02X1587062Y1549970I0J1202D01*
G01Y1549972D01*
G02X1587211Y1550551I1202J-1D01*
G01X1588777Y1553261D01*
X1588779Y1553264D01*
G37*
G36*
G01X1593503D02*
G02X1594563Y1553900I1060J-565D01*
G01X1594565D01*
G02X1595766Y1552698I-1J-1202D01*
G02X1595605Y1552098I-1204J1D01*
G01X1594060Y1549425D01*
X1594058Y1549421D01*
G02X1592988Y1548768I-1070J550D01*
G02X1591786Y1549970I0J1202D01*
G01Y1549972D01*
G02X1591935Y1550551I1202J-1D01*
G01X1593501Y1553261D01*
X1593503Y1553264D01*
G37*
G36*
G01X1598227D02*
G02X1599287Y1553900I1060J-565D01*
G01X1599289D01*
G02X1600490Y1552698I-1J-1202D01*
G02X1600329Y1552098I-1204J1D01*
G01X1598784Y1549425D01*
X1598782Y1549421D01*
G02X1597712Y1548768I-1070J550D01*
G02X1596510Y1549970I0J1202D01*
G01Y1549972D01*
G02X1596659Y1550551I1202J-1D01*
G01X1598225Y1553261D01*
X1598227Y1553264D01*
G37*
G36*
G01X1602950Y1553261D02*
X1602952Y1553264D01*
G02X1604012Y1553900I1060J-565D01*
G02X1605214Y1552698I0J-1202D01*
G01Y1552697D01*
G02X1605054Y1552098I-1203J1D01*
G01X1603509Y1549425D01*
X1603507Y1549421D01*
G02X1602437Y1548768I-1070J550D01*
G01X1602435D01*
G02X1601234Y1549970I1J1202D01*
G01Y1549972D01*
G02X1601384Y1550551I1203J-3D01*
G01X1602950Y1553261D01*
G37*
G36*
G01X1607674D02*
X1607676Y1553264D01*
G02X1608736Y1553900I1060J-565D01*
G02X1609938Y1552698I0J-1202D01*
G01Y1552697D01*
G02X1609778Y1552098I-1203J1D01*
G01X1608233Y1549425D01*
X1608231Y1549421D01*
G02X1607161Y1548768I-1070J550D01*
G01X1607159D01*
G02X1605958Y1549970I1J1202D01*
G01Y1549972D01*
G02X1606108Y1550551I1203J-3D01*
G01X1607674Y1553261D01*
G37*
G36*
G01X1612401Y1553264D02*
G02X1613461Y1553900I1060J-565D01*
G01X1613463D01*
G02X1614664Y1552698I-1J-1202D01*
G02X1614503Y1552098I-1204J1D01*
G01X1612958Y1549425D01*
X1612956Y1549421D01*
G02X1611886Y1548768I-1070J550D01*
G02X1610684Y1549970I0J1202D01*
G01Y1549972D01*
G02X1610833Y1550551I1202J-1D01*
G01X1612399Y1553261D01*
X1612401Y1553264D01*
G37*
G36*
G01X1617125D02*
G02X1618185Y1553900I1060J-565D01*
G01X1618187D01*
G02X1619388Y1552698I-1J-1202D01*
G02X1619227Y1552098I-1204J1D01*
G01X1617682Y1549425D01*
X1617680Y1549421D01*
G02X1616610Y1548768I-1070J550D01*
G02X1615408Y1549970I0J1202D01*
G01Y1549972D01*
G02X1615557Y1550551I1202J-1D01*
G01X1617123Y1553261D01*
X1617125Y1553264D01*
G37*
G36*
G01X1621849D02*
G02X1622909Y1553900I1060J-565D01*
G01X1622911D01*
G02X1624112Y1552698I-1J-1202D01*
G02X1623951Y1552098I-1204J1D01*
G01X1622406Y1549425D01*
X1622404Y1549421D01*
G02X1621334Y1548768I-1070J550D01*
G02X1620132Y1549970I0J1202D01*
G01Y1549972D01*
G02X1620281Y1550551I1202J-1D01*
G01X1621847Y1553261D01*
X1621849Y1553264D01*
G37*
G36*
G01X1626572Y1553261D02*
X1626574Y1553264D01*
G02X1627634Y1553900I1060J-565D01*
G02X1628836Y1552698I0J-1202D01*
G01Y1552697D01*
G02X1628676Y1552098I-1203J1D01*
G01X1627131Y1549425D01*
X1627129Y1549421D01*
G02X1626059Y1548768I-1070J550D01*
G01X1626057D01*
G02X1624856Y1549970I1J1202D01*
G01Y1549972D01*
G02X1625006Y1550551I1203J-3D01*
G01X1626572Y1553261D01*
G37*
G36*
G01X1631296D02*
X1631298Y1553264D01*
G02X1632358Y1553900I1060J-565D01*
G02X1633560Y1552698I0J-1202D01*
G01Y1552697D01*
G02X1633400Y1552098I-1203J1D01*
G01X1631855Y1549425D01*
X1631853Y1549421D01*
G02X1630783Y1548768I-1070J550D01*
G01X1630781D01*
G02X1629580Y1549970I1J1202D01*
G01Y1549972D01*
G02X1629730Y1550551I1203J-3D01*
G01X1631296Y1553261D01*
G37*
G36*
G01X1636023Y1553264D02*
G02X1637083Y1553900I1060J-565D01*
G01X1637085D01*
G02X1638286Y1552698I-1J-1202D01*
G02X1638125Y1552098I-1204J1D01*
G01X1636580Y1549425D01*
X1636578Y1549421D01*
G02X1635508Y1548768I-1070J550D01*
G02X1634306Y1549970I0J1202D01*
G01Y1549972D01*
G02X1634455Y1550551I1202J-1D01*
G01X1636021Y1553261D01*
X1636023Y1553264D01*
G37*
G36*
G01X1640747D02*
G02X1641807Y1553900I1060J-565D01*
G01X1641809D01*
G02X1643010Y1552698I-1J-1202D01*
G02X1642849Y1552098I-1204J1D01*
G01X1641304Y1549425D01*
X1641302Y1549421D01*
G02X1640232Y1548768I-1070J550D01*
G02X1639030Y1549970I0J1202D01*
G01Y1549972D01*
G02X1639179Y1550551I1202J-1D01*
G01X1640745Y1553261D01*
X1640747Y1553264D01*
G37*
G36*
G01X1645471D02*
G02X1646531Y1553900I1060J-565D01*
G01X1646533D01*
G02X1647734Y1552698I-1J-1202D01*
G02X1647573Y1552098I-1204J1D01*
G01X1646028Y1549425D01*
X1646026Y1549421D01*
G02X1644956Y1548768I-1070J550D01*
G02X1643754Y1549970I0J1202D01*
G01Y1549972D01*
G02X1643903Y1550551I1202J-1D01*
G01X1645469Y1553261D01*
X1645471Y1553264D01*
G37*
G36*
G01X1650194Y1553261D02*
X1650196Y1553264D01*
G02X1651256Y1553900I1060J-565D01*
G02X1652458Y1552698I0J-1202D01*
G01Y1552697D01*
G02X1652298Y1552098I-1203J1D01*
G01X1650753Y1549425D01*
X1650751Y1549421D01*
G02X1649681Y1548768I-1070J550D01*
G01X1649679D01*
G02X1648478Y1549970I1J1202D01*
G01Y1549972D01*
G02X1648628Y1550551I1203J-3D01*
G01X1650194Y1553261D01*
G37*
G36*
G01X1654918D02*
X1654920Y1553264D01*
G02X1655980Y1553900I1060J-565D01*
G02X1657182Y1552698I0J-1202D01*
G01Y1552697D01*
G02X1657022Y1552098I-1203J1D01*
G01X1655477Y1549425D01*
X1655475Y1549421D01*
G02X1654405Y1548768I-1070J550D01*
G01X1654403D01*
G02X1653202Y1549970I1J1202D01*
G01Y1549972D01*
G02X1653352Y1550551I1203J-3D01*
G01X1654918Y1553261D01*
G37*
G36*
G01X1659645Y1553264D02*
G02X1660705Y1553900I1060J-565D01*
G01X1660707D01*
G02X1661908Y1552698I-1J-1202D01*
G02X1661747Y1552098I-1204J1D01*
G01X1660202Y1549425D01*
X1660200Y1549421D01*
G02X1659130Y1548768I-1070J550D01*
G02X1657928Y1549970I0J1202D01*
G01Y1549972D01*
G02X1658077Y1550551I1202J-1D01*
G01X1659643Y1553261D01*
X1659645Y1553264D01*
G37*
G36*
G01X1235398Y1553900D02*
X1235399D01*
G02X1236602Y1552698I1J-1202D01*
G02X1236441Y1552098I-1204J1D01*
G01X1234896Y1549425D01*
X1234894Y1549421D01*
G02X1233824Y1548768I-1070J550D01*
G01X1233823D01*
G02X1232620Y1549970I-1J1202D01*
G01Y1549972D01*
G02X1232770Y1550551I1203J-3D01*
G01X1234336Y1553261D01*
X1234338Y1553264D01*
G02X1235398Y1553900I1060J-565D01*
G37*
G36*
G01X1240122D02*
X1240123D01*
G02X1241326Y1552698I1J-1202D01*
G02X1241165Y1552098I-1204J1D01*
G01X1239620Y1549425D01*
X1239618Y1549421D01*
G02X1238548Y1548768I-1070J550D01*
G01X1238547D01*
G02X1237344Y1549970I-1J1202D01*
G01Y1549972D01*
G02X1237494Y1550551I1203J-3D01*
G01X1239060Y1553261D01*
X1239062Y1553264D01*
G02X1240122Y1553900I1060J-565D01*
G37*
G36*
G01X1259020D02*
X1259021D01*
G02X1260224Y1552698I1J-1202D01*
G02X1260063Y1552098I-1204J1D01*
G01X1258518Y1549425D01*
X1258516Y1549421D01*
G02X1257446Y1548768I-1070J550D01*
G01X1257445D01*
G02X1256242Y1549970I-1J1202D01*
G01Y1549972D01*
G02X1256392Y1550551I1203J-3D01*
G01X1257958Y1553261D01*
X1257960Y1553264D01*
G02X1259020Y1553900I1060J-565D01*
G37*
G36*
G01X1391806D02*
X1391807D01*
G02X1393010Y1552698I1J-1202D01*
G02X1392849Y1552098I-1204J1D01*
G01X1391304Y1549425D01*
X1391302Y1549421D01*
G02X1390232Y1548768I-1070J550D01*
G01X1390231D01*
G02X1389028Y1549970I-1J1202D01*
G01Y1549972D01*
G02X1389178Y1550551I1203J-3D01*
G01X1390744Y1553261D01*
X1390746Y1553264D01*
G02X1391806Y1553900I1060J-565D01*
G37*
G36*
G01X1196543Y1566902D02*
G02X1197603Y1567538I1060J-565D01*
G01X1197605D01*
G02X1198806Y1566336I-1J-1202D01*
G02X1198645Y1565736I-1204J1D01*
G01X1197100Y1563063D01*
X1197098Y1563059D01*
G02X1196028Y1562406I-1070J550D01*
G02X1194826Y1563608I0J1202D01*
G01Y1563610D01*
G02X1194975Y1564189I1202J-1D01*
G01X1196541Y1566899D01*
X1196543Y1566902D01*
G37*
G36*
G01X1201267D02*
G02X1202327Y1567538I1060J-565D01*
G01X1202329D01*
G02X1203530Y1566336I-1J-1202D01*
G02X1203369Y1565736I-1204J1D01*
G01X1201824Y1563063D01*
X1201822Y1563059D01*
G02X1200752Y1562406I-1070J550D01*
G02X1199550Y1563608I0J1202D01*
G01Y1563610D01*
G02X1199699Y1564189I1202J-1D01*
G01X1201265Y1566899D01*
X1201267Y1566902D01*
G37*
G36*
G01X1205991D02*
G02X1207051Y1567538I1060J-565D01*
G01X1207053D01*
G02X1208254Y1566336I-1J-1202D01*
G02X1208093Y1565736I-1204J1D01*
G01X1206548Y1563063D01*
X1206546Y1563059D01*
G02X1205476Y1562406I-1070J550D01*
G02X1204274Y1563608I0J1202D01*
G01Y1563610D01*
G02X1204423Y1564189I1202J-1D01*
G01X1205989Y1566899D01*
X1205991Y1566902D01*
G37*
G36*
G01X1210714Y1566899D02*
X1210716Y1566902D01*
G02X1211776Y1567538I1060J-565D01*
G02X1212978Y1566336I0J-1202D01*
G01Y1566335D01*
G02X1212818Y1565736I-1203J1D01*
G01X1211273Y1563063D01*
X1211271Y1563059D01*
G02X1210201Y1562406I-1070J550D01*
G01X1210199D01*
G02X1208998Y1563608I1J1202D01*
G01Y1563610D01*
G02X1209148Y1564189I1203J-3D01*
G01X1210714Y1566899D01*
G37*
G36*
G01X1215438D02*
X1215440Y1566902D01*
G02X1216500Y1567538I1060J-565D01*
G02X1217702Y1566336I0J-1202D01*
G01Y1566335D01*
G02X1217542Y1565736I-1203J1D01*
G01X1215997Y1563063D01*
X1215995Y1563059D01*
G02X1214925Y1562406I-1070J550D01*
G01X1214923D01*
G02X1213722Y1563608I1J1202D01*
G01Y1563610D01*
G02X1213872Y1564189I1203J-3D01*
G01X1215438Y1566899D01*
G37*
G36*
G01X1220165Y1566902D02*
G02X1221225Y1567538I1060J-565D01*
G01X1221227D01*
G02X1222428Y1566336I-1J-1202D01*
G02X1222267Y1565736I-1204J1D01*
G01X1220722Y1563063D01*
X1220720Y1563059D01*
G02X1219650Y1562406I-1070J550D01*
G02X1218448Y1563608I0J1202D01*
G01Y1563610D01*
G02X1218597Y1564189I1202J-1D01*
G01X1220163Y1566899D01*
X1220165Y1566902D01*
G37*
G36*
G01X1224889D02*
G02X1225949Y1567538I1060J-565D01*
G01X1225951D01*
G02X1227152Y1566336I-1J-1202D01*
G02X1226991Y1565736I-1204J1D01*
G01X1225446Y1563063D01*
X1225444Y1563059D01*
G02X1224374Y1562406I-1070J550D01*
G02X1223172Y1563608I0J1202D01*
G01Y1563610D01*
G02X1223321Y1564189I1202J-1D01*
G01X1224887Y1566899D01*
X1224889Y1566902D01*
G37*
G36*
G01X1229613D02*
G02X1230673Y1567538I1060J-565D01*
G01X1230675D01*
G02X1231876Y1566336I-1J-1202D01*
G02X1231715Y1565736I-1204J1D01*
G01X1230170Y1563063D01*
X1230168Y1563059D01*
G02X1229098Y1562406I-1070J550D01*
G02X1227896Y1563608I0J1202D01*
G01Y1563610D01*
G02X1228045Y1564189I1202J-1D01*
G01X1229611Y1566899D01*
X1229613Y1566902D01*
G37*
G36*
G01X1234336Y1566899D02*
X1234338Y1566902D01*
G02X1235398Y1567538I1060J-565D01*
G02X1236600Y1566336I0J-1202D01*
G01Y1566335D01*
G02X1236440Y1565736I-1203J1D01*
G01X1234895Y1563063D01*
X1234893Y1563059D01*
G02X1233823Y1562406I-1070J550D01*
G01X1233821D01*
G02X1232620Y1563608I1J1202D01*
G01Y1563610D01*
G02X1232770Y1564189I1203J-3D01*
G01X1234336Y1566899D01*
G37*
G36*
G01X1239060D02*
X1239062Y1566902D01*
G02X1240122Y1567538I1060J-565D01*
G02X1241324Y1566336I0J-1202D01*
G01Y1566335D01*
G02X1241164Y1565736I-1203J1D01*
G01X1239619Y1563063D01*
X1239617Y1563059D01*
G02X1238547Y1562406I-1070J550D01*
G01X1238545D01*
G02X1237344Y1563608I1J1202D01*
G01Y1563610D01*
G02X1237494Y1564189I1203J-3D01*
G01X1239060Y1566899D01*
G37*
G36*
G01X1243787Y1566902D02*
G02X1244847Y1567538I1060J-565D01*
G01X1244849D01*
G02X1246050Y1566336I-1J-1202D01*
G02X1245889Y1565736I-1204J1D01*
G01X1244344Y1563063D01*
X1244342Y1563059D01*
G02X1243272Y1562406I-1070J550D01*
G02X1242070Y1563608I0J1202D01*
G01Y1563610D01*
G02X1242219Y1564189I1202J-1D01*
G01X1243785Y1566899D01*
X1243787Y1566902D01*
G37*
G36*
G01X1248511D02*
G02X1249571Y1567538I1060J-565D01*
G01X1249573D01*
G02X1250774Y1566336I-1J-1202D01*
G02X1250613Y1565736I-1204J1D01*
G01X1249068Y1563063D01*
X1249066Y1563059D01*
G02X1247996Y1562406I-1070J550D01*
G02X1246794Y1563608I0J1202D01*
G01Y1563610D01*
G02X1246943Y1564189I1202J-1D01*
G01X1248509Y1566899D01*
X1248511Y1566902D01*
G37*
G36*
G01X1253235D02*
G02X1254295Y1567538I1060J-565D01*
G01X1254297D01*
G02X1255498Y1566336I-1J-1202D01*
G02X1255337Y1565736I-1204J1D01*
G01X1253792Y1563063D01*
X1253790Y1563059D01*
G02X1252720Y1562406I-1070J550D01*
G02X1251518Y1563608I0J1202D01*
G01Y1563610D01*
G02X1251667Y1564189I1202J-1D01*
G01X1253233Y1566899D01*
X1253235Y1566902D01*
G37*
G36*
G01X1257958Y1566899D02*
X1257960Y1566902D01*
G02X1259020Y1567538I1060J-565D01*
G02X1260222Y1566336I0J-1202D01*
G01Y1566335D01*
G02X1260062Y1565736I-1203J1D01*
G01X1258517Y1563063D01*
X1258515Y1563059D01*
G02X1257445Y1562406I-1070J550D01*
G01X1257443D01*
G02X1256242Y1563608I1J1202D01*
G01Y1563610D01*
G02X1256392Y1564189I1203J-3D01*
G01X1257958Y1566899D01*
G37*
G36*
G01X1262682D02*
X1262684Y1566902D01*
G02X1263744Y1567538I1060J-565D01*
G02X1264946Y1566336I0J-1202D01*
G01Y1566335D01*
G02X1264786Y1565736I-1203J1D01*
G01X1263241Y1563063D01*
X1263239Y1563059D01*
G02X1262169Y1562406I-1070J550D01*
G01X1262167D01*
G02X1260966Y1563608I1J1202D01*
G01Y1563610D01*
G02X1261116Y1564189I1203J-3D01*
G01X1262682Y1566899D01*
G37*
G36*
G01X1267409Y1566902D02*
G02X1268469Y1567538I1060J-565D01*
G01X1268471D01*
G02X1269672Y1566336I-1J-1202D01*
G02X1269511Y1565736I-1204J1D01*
G01X1267966Y1563063D01*
X1267964Y1563059D01*
G02X1266894Y1562406I-1070J550D01*
G02X1265692Y1563608I0J1202D01*
G01Y1563610D01*
G02X1265841Y1564189I1202J-1D01*
G01X1267407Y1566899D01*
X1267409Y1566902D01*
G37*
G36*
G01X1324602Y1566898D02*
G02X1325665Y1567538I1063J-563D01*
G01X1325667D01*
G02X1326868Y1566336I-1J-1202D01*
G01Y1566335D01*
G02X1326714Y1565748I-1203J2D01*
G01X1326709Y1565738D01*
X1326708D01*
X1326707Y1565736D01*
X1325164Y1563066D01*
X1325162Y1563061D01*
G02X1322903Y1563800I-1072J545D01*
G01Y1563801D01*
G02X1323037Y1564189I1187J-193D01*
G01X1324601Y1566895D01*
X1324602Y1566898D01*
G37*
G36*
G01X1329326D02*
G02X1330389Y1567538I1063J-563D01*
G01X1330391D01*
G02X1331592Y1566336I-1J-1202D01*
G01Y1566335D01*
G02X1331438Y1565748I-1203J2D01*
G01X1331433Y1565738D01*
X1331432D01*
X1331431Y1565736D01*
X1329888Y1563066D01*
X1329886Y1563061D01*
G02X1327627Y1563800I-1072J545D01*
G01Y1563801D01*
G02X1327761Y1564189I1187J-193D01*
G01X1329325Y1566895D01*
X1329326Y1566898D01*
G37*
G36*
G01X1334050D02*
G02X1335113Y1567538I1063J-563D01*
G01X1335115D01*
G02X1336316Y1566336I-1J-1202D01*
G01Y1566335D01*
G02X1336162Y1565748I-1203J2D01*
G01X1336157Y1565738D01*
X1336156D01*
X1336155Y1565736D01*
X1334612Y1563066D01*
X1334610Y1563061D01*
G02X1332351Y1563800I-1072J545D01*
G01Y1563801D01*
G02X1332485Y1564189I1187J-193D01*
G01X1334049Y1566895D01*
X1334050Y1566898D01*
G37*
G36*
G01X1338774Y1566895D02*
X1338775Y1566898D01*
G02X1339838Y1567538I1063J-563D01*
G02X1341040Y1566336I0J-1202D01*
G01Y1566335D01*
G02X1340887Y1565748I-1202J0D01*
G01X1340882Y1565738D01*
X1340881D01*
X1340880Y1565736D01*
X1339337Y1563066D01*
X1339335Y1563061D01*
G02X1337076Y1563800I-1072J545D01*
G01Y1563801D01*
G02X1337210Y1564189I1187J-193D01*
G01X1338774Y1566895D01*
G37*
G36*
G01X1343498D02*
X1343499Y1566898D01*
G02X1344562Y1567538I1063J-563D01*
G02X1345764Y1566336I0J-1202D01*
G01Y1566335D01*
G02X1345611Y1565748I-1202J0D01*
G01X1345606Y1565738D01*
X1345605D01*
X1345604Y1565736D01*
X1344061Y1563066D01*
X1344059Y1563061D01*
G02X1341800Y1563800I-1072J545D01*
G01Y1563801D01*
G02X1341934Y1564189I1187J-193D01*
G01X1343498Y1566895D01*
G37*
G36*
G01X1348224Y1566898D02*
G02X1349287Y1567538I1063J-563D01*
G01X1349289D01*
G02X1350490Y1566336I-1J-1202D01*
G01Y1566335D01*
G02X1350336Y1565748I-1203J2D01*
G01X1350331Y1565738D01*
X1350330D01*
X1350329Y1565736D01*
X1348786Y1563066D01*
X1348784Y1563061D01*
G02X1346525Y1563800I-1072J545D01*
G01Y1563801D01*
G02X1346659Y1564189I1187J-193D01*
G01X1348223Y1566895D01*
X1348224Y1566898D01*
G37*
G36*
G01X1352948D02*
G02X1354011Y1567538I1063J-563D01*
G01X1354013D01*
G02X1355214Y1566336I-1J-1202D01*
G01Y1566335D01*
G02X1355060Y1565748I-1203J2D01*
G01X1355055Y1565738D01*
X1355054D01*
X1355053Y1565736D01*
X1353510Y1563066D01*
X1353508Y1563061D01*
G02X1351249Y1563800I-1072J545D01*
G01Y1563801D01*
G02X1351383Y1564189I1187J-193D01*
G01X1352947Y1566895D01*
X1352948Y1566898D01*
G37*
G36*
G01X1357672D02*
G02X1358735Y1567538I1063J-563D01*
G01X1358737D01*
G02X1359938Y1566336I-1J-1202D01*
G01Y1566335D01*
G02X1359784Y1565748I-1203J2D01*
G01X1359779Y1565738D01*
X1359778D01*
X1359777Y1565736D01*
X1358234Y1563066D01*
X1358232Y1563061D01*
G02X1355973Y1563800I-1072J545D01*
G01Y1563801D01*
G02X1356107Y1564189I1187J-193D01*
G01X1357671Y1566895D01*
X1357672Y1566898D01*
G37*
G36*
G01X1362396Y1566895D02*
X1362397Y1566898D01*
G02X1363460Y1567538I1063J-563D01*
G02X1364662Y1566336I0J-1202D01*
G01Y1566335D01*
G02X1364509Y1565748I-1202J0D01*
G01X1364504Y1565738D01*
X1364503D01*
X1364502Y1565736D01*
X1362959Y1563066D01*
X1362957Y1563061D01*
G02X1360698Y1563800I-1072J545D01*
G01Y1563801D01*
G02X1360832Y1564189I1187J-193D01*
G01X1362396Y1566895D01*
G37*
G36*
G01X1367120D02*
X1367121Y1566898D01*
G02X1368184Y1567538I1063J-563D01*
G02X1369386Y1566336I0J-1202D01*
G01Y1566335D01*
G02X1369233Y1565748I-1202J0D01*
G01X1369228Y1565738D01*
X1369227D01*
X1369226Y1565736D01*
X1367683Y1563066D01*
X1367681Y1563061D01*
G02X1365422Y1563800I-1072J545D01*
G01Y1563801D01*
G02X1365556Y1564189I1187J-193D01*
G01X1367120Y1566895D01*
G37*
G36*
G01X1371846Y1566898D02*
G02X1372909Y1567538I1063J-563D01*
G01X1372911D01*
G02X1374112Y1566336I-1J-1202D01*
G01Y1566335D01*
G02X1373958Y1565748I-1203J2D01*
G01X1373953Y1565738D01*
X1373952D01*
X1373951Y1565736D01*
X1372408Y1563066D01*
X1372406Y1563061D01*
G02X1370147Y1563800I-1072J545D01*
G01Y1563801D01*
G02X1370281Y1564189I1187J-193D01*
G01X1371845Y1566895D01*
X1371846Y1566898D01*
G37*
G36*
G01X1376570D02*
G02X1377633Y1567538I1063J-563D01*
G01X1377635D01*
G02X1378836Y1566336I-1J-1202D01*
G01Y1566335D01*
G02X1378682Y1565748I-1203J2D01*
G01X1378677Y1565738D01*
X1378676D01*
X1378675Y1565736D01*
X1377132Y1563066D01*
X1377130Y1563061D01*
G02X1374871Y1563800I-1072J545D01*
G01Y1563801D01*
G02X1375005Y1564189I1187J-193D01*
G01X1376569Y1566895D01*
X1376570Y1566898D01*
G37*
G36*
G01X1381294D02*
G02X1382357Y1567538I1063J-563D01*
G01X1382359D01*
G02X1383560Y1566336I-1J-1202D01*
G01Y1566335D01*
G02X1383406Y1565748I-1203J2D01*
G01X1383401Y1565738D01*
X1383400D01*
X1383399Y1565736D01*
X1381856Y1563066D01*
X1381854Y1563061D01*
G02X1379595Y1563800I-1072J545D01*
G01Y1563801D01*
G02X1379729Y1564189I1187J-193D01*
G01X1381293Y1566895D01*
X1381294Y1566898D01*
G37*
G36*
G01X1386018Y1566895D02*
X1386019Y1566898D01*
G02X1387082Y1567538I1063J-563D01*
G02X1388284Y1566336I0J-1202D01*
G01Y1566335D01*
G02X1388131Y1565748I-1202J0D01*
G01X1388126Y1565738D01*
X1388125D01*
X1388124Y1565736D01*
X1386581Y1563066D01*
X1386579Y1563061D01*
G02X1384320Y1563800I-1072J545D01*
G01Y1563801D01*
G02X1384454Y1564189I1187J-193D01*
G01X1386018Y1566895D01*
G37*
G36*
G01X1390742D02*
X1390743Y1566898D01*
G02X1391806Y1567538I1063J-563D01*
G02X1393008Y1566336I0J-1202D01*
G01Y1566335D01*
G02X1392855Y1565748I-1202J0D01*
G01X1392850Y1565738D01*
X1392849D01*
X1392848Y1565736D01*
X1391305Y1563066D01*
X1391303Y1563061D01*
G02X1389044Y1563800I-1072J545D01*
G01Y1563801D01*
G02X1389178Y1564189I1187J-193D01*
G01X1390742Y1566895D01*
G37*
G36*
G01X1395468Y1566898D02*
G02X1396531Y1567538I1063J-563D01*
G01X1396533D01*
G02X1397734Y1566336I-1J-1202D01*
G01Y1566335D01*
G02X1397580Y1565748I-1203J2D01*
G01X1397575Y1565738D01*
X1397574D01*
X1397573Y1565736D01*
X1396030Y1563066D01*
X1396028Y1563061D01*
G02X1393769Y1563800I-1072J545D01*
G01Y1563801D01*
G02X1393903Y1564189I1187J-193D01*
G01X1395467Y1566895D01*
X1395468Y1566898D01*
G37*
G36*
G01X1460714D02*
G02X1461777Y1567538I1063J-563D01*
G01X1461779D01*
G02X1462980Y1566336I-1J-1202D01*
G01Y1566335D01*
G02X1462826Y1565748I-1203J2D01*
G01X1462821Y1565738D01*
X1462820D01*
X1462819Y1565736D01*
X1461276Y1563066D01*
X1461274Y1563061D01*
G02X1459015Y1563800I-1072J545D01*
G01Y1563801D01*
G02X1459149Y1564189I1187J-193D01*
G01X1460713Y1566895D01*
X1460714Y1566898D01*
G37*
G36*
G01X1465438D02*
G02X1466501Y1567538I1063J-563D01*
G01X1466503D01*
G02X1467704Y1566336I-1J-1202D01*
G01Y1566335D01*
G02X1467550Y1565748I-1203J2D01*
G01X1467545Y1565738D01*
X1467544D01*
X1467543Y1565736D01*
X1466000Y1563066D01*
X1465998Y1563061D01*
G02X1463739Y1563800I-1072J545D01*
G01Y1563801D01*
G02X1463873Y1564189I1187J-193D01*
G01X1465437Y1566895D01*
X1465438Y1566898D01*
G37*
G36*
G01X1470162D02*
G02X1471225Y1567538I1063J-563D01*
G01X1471227D01*
G02X1472428Y1566336I-1J-1202D01*
G01Y1566335D01*
G02X1472274Y1565748I-1203J2D01*
G01X1472269Y1565738D01*
X1472268D01*
X1472267Y1565736D01*
X1470724Y1563066D01*
X1470722Y1563061D01*
G02X1468463Y1563800I-1072J545D01*
G01Y1563801D01*
G02X1468597Y1564189I1187J-193D01*
G01X1470161Y1566895D01*
X1470162Y1566898D01*
G37*
G36*
G01X1474886Y1566895D02*
X1474887Y1566898D01*
G02X1475950Y1567538I1063J-563D01*
G02X1477152Y1566336I0J-1202D01*
G01Y1566335D01*
G02X1476999Y1565748I-1202J0D01*
G01X1476994Y1565738D01*
X1476993D01*
X1476992Y1565736D01*
X1475449Y1563066D01*
X1475447Y1563061D01*
G02X1473188Y1563800I-1072J545D01*
G01Y1563801D01*
G02X1473322Y1564189I1187J-193D01*
G01X1474886Y1566895D01*
G37*
G36*
G01X1479610D02*
X1479611Y1566898D01*
G02X1480674Y1567538I1063J-563D01*
G02X1481876Y1566336I0J-1202D01*
G01Y1566335D01*
G02X1481723Y1565748I-1202J0D01*
G01X1481718Y1565738D01*
X1481717D01*
X1481716Y1565736D01*
X1480173Y1563066D01*
X1480171Y1563061D01*
G02X1477912Y1563800I-1072J545D01*
G01Y1563801D01*
G02X1478046Y1564189I1187J-193D01*
G01X1479610Y1566895D01*
G37*
G36*
G01X1484336Y1566898D02*
G02X1485399Y1567538I1063J-563D01*
G01X1485401D01*
G02X1486602Y1566336I-1J-1202D01*
G01Y1566335D01*
G02X1486448Y1565748I-1203J2D01*
G01X1486443Y1565738D01*
X1486442D01*
X1486441Y1565736D01*
X1484898Y1563066D01*
X1484896Y1563061D01*
G02X1482637Y1563800I-1072J545D01*
G01Y1563801D01*
G02X1482771Y1564189I1187J-193D01*
G01X1484335Y1566895D01*
X1484336Y1566898D01*
G37*
G36*
G01X1489060D02*
G02X1490123Y1567538I1063J-563D01*
G01X1490125D01*
G02X1491326Y1566336I-1J-1202D01*
G01Y1566335D01*
G02X1491172Y1565748I-1203J2D01*
G01X1491167Y1565738D01*
X1491166D01*
X1491165Y1565736D01*
X1489622Y1563066D01*
X1489620Y1563061D01*
G02X1487361Y1563800I-1072J545D01*
G01Y1563801D01*
G02X1487495Y1564189I1187J-193D01*
G01X1489059Y1566895D01*
X1489060Y1566898D01*
G37*
G36*
G01X1493784D02*
G02X1494847Y1567538I1063J-563D01*
G01X1494849D01*
G02X1496050Y1566336I-1J-1202D01*
G01Y1566335D01*
G02X1495896Y1565748I-1203J2D01*
G01X1495891Y1565738D01*
X1495890D01*
X1495889Y1565736D01*
X1494346Y1563066D01*
X1494344Y1563061D01*
G02X1492085Y1563800I-1072J545D01*
G01Y1563801D01*
G02X1492219Y1564189I1187J-193D01*
G01X1493783Y1566895D01*
X1493784Y1566898D01*
G37*
G36*
G01X1498508Y1566895D02*
X1498509Y1566898D01*
G02X1499572Y1567538I1063J-563D01*
G02X1500774Y1566336I0J-1202D01*
G01Y1566335D01*
G02X1500621Y1565748I-1202J0D01*
G01X1500616Y1565738D01*
X1500615D01*
X1500614Y1565736D01*
X1499071Y1563066D01*
X1499069Y1563061D01*
G02X1496810Y1563800I-1072J545D01*
G01Y1563801D01*
G02X1496944Y1564189I1187J-193D01*
G01X1498508Y1566895D01*
G37*
G36*
G01X1503232D02*
X1503233Y1566898D01*
G02X1504296Y1567538I1063J-563D01*
G02X1505498Y1566336I0J-1202D01*
G01Y1566335D01*
G02X1505345Y1565748I-1202J0D01*
G01X1505340Y1565738D01*
X1505339D01*
X1505338Y1565736D01*
X1503795Y1563066D01*
X1503793Y1563061D01*
G02X1501534Y1563800I-1072J545D01*
G01Y1563801D01*
G02X1501668Y1564189I1187J-193D01*
G01X1503232Y1566895D01*
G37*
G36*
G01X1507958Y1566898D02*
G02X1509021Y1567538I1063J-563D01*
G01X1509023D01*
G02X1510224Y1566336I-1J-1202D01*
G01Y1566335D01*
G02X1510070Y1565748I-1203J2D01*
G01X1510065Y1565738D01*
X1510064D01*
X1510063Y1565736D01*
X1508520Y1563066D01*
X1508518Y1563061D01*
G02X1506259Y1563800I-1072J545D01*
G01Y1563801D01*
G02X1506393Y1564189I1187J-193D01*
G01X1507957Y1566895D01*
X1507958Y1566898D01*
G37*
G36*
G01X1512682D02*
G02X1513745Y1567538I1063J-563D01*
G01X1513747D01*
G02X1514948Y1566336I-1J-1202D01*
G01Y1566335D01*
G02X1514794Y1565748I-1203J2D01*
G01X1514789Y1565738D01*
X1514788D01*
X1514787Y1565736D01*
X1513244Y1563066D01*
X1513242Y1563061D01*
G02X1510983Y1563800I-1072J545D01*
G01Y1563801D01*
G02X1511117Y1564189I1187J-193D01*
G01X1512681Y1566895D01*
X1512682Y1566898D01*
G37*
G36*
G01X1517406D02*
G02X1518469Y1567538I1063J-563D01*
G01X1518471D01*
G02X1519672Y1566336I-1J-1202D01*
G01Y1566335D01*
G02X1519518Y1565748I-1203J2D01*
G01X1519513Y1565738D01*
X1519512D01*
X1519511Y1565736D01*
X1517968Y1563066D01*
X1517966Y1563061D01*
G02X1515707Y1563800I-1072J545D01*
G01Y1563801D01*
G02X1515841Y1564189I1187J-193D01*
G01X1517405Y1566895D01*
X1517406Y1566898D01*
G37*
G36*
G01X1522130Y1566895D02*
X1522131Y1566898D01*
G02X1523194Y1567538I1063J-563D01*
G02X1524396Y1566336I0J-1202D01*
G01Y1566335D01*
G02X1524243Y1565748I-1202J0D01*
G01X1524238Y1565738D01*
X1524237D01*
X1524236Y1565736D01*
X1522693Y1563066D01*
X1522691Y1563061D01*
G02X1520432Y1563800I-1072J545D01*
G01Y1563801D01*
G02X1520566Y1564189I1187J-193D01*
G01X1522130Y1566895D01*
G37*
G36*
G01X1526854D02*
X1526855Y1566898D01*
G02X1527918Y1567538I1063J-563D01*
G02X1529120Y1566336I0J-1202D01*
G01Y1566335D01*
G02X1528967Y1565748I-1202J0D01*
G01X1528962Y1565738D01*
X1528961D01*
X1528960Y1565736D01*
X1527417Y1563066D01*
X1527415Y1563061D01*
G02X1525156Y1563800I-1072J545D01*
G01Y1563801D01*
G02X1525290Y1564189I1187J-193D01*
G01X1526854Y1566895D01*
G37*
G36*
G01X1531580Y1566898D02*
G02X1532643Y1567538I1063J-563D01*
G01X1532645D01*
G02X1533846Y1566336I-1J-1202D01*
G01Y1566335D01*
G02X1533692Y1565748I-1203J2D01*
G01X1533687Y1565738D01*
X1533686D01*
X1533685Y1565736D01*
X1532142Y1563066D01*
X1532140Y1563061D01*
G02X1529881Y1563800I-1072J545D01*
G01Y1563801D01*
G02X1530015Y1564189I1187J-193D01*
G01X1531579Y1566895D01*
X1531580Y1566898D01*
G37*
G36*
G01X1588779Y1566902D02*
G02X1589839Y1567538I1060J-565D01*
G01X1589841D01*
G02X1591042Y1566336I-1J-1202D01*
G02X1590881Y1565736I-1204J1D01*
G01X1589336Y1563063D01*
X1589334Y1563059D01*
G02X1588264Y1562406I-1070J550D01*
G02X1587062Y1563608I0J1202D01*
G01Y1563610D01*
G02X1587211Y1564189I1202J-1D01*
G01X1588777Y1566899D01*
X1588779Y1566902D01*
G37*
G36*
G01X1593503D02*
G02X1594563Y1567538I1060J-565D01*
G01X1594565D01*
G02X1595766Y1566336I-1J-1202D01*
G02X1595605Y1565736I-1204J1D01*
G01X1594060Y1563063D01*
X1594058Y1563059D01*
G02X1592988Y1562406I-1070J550D01*
G02X1591786Y1563608I0J1202D01*
G01Y1563610D01*
G02X1591935Y1564189I1202J-1D01*
G01X1593501Y1566899D01*
X1593503Y1566902D01*
G37*
G36*
G01X1598227D02*
G02X1599287Y1567538I1060J-565D01*
G01X1599289D01*
G02X1600490Y1566336I-1J-1202D01*
G02X1600329Y1565736I-1204J1D01*
G01X1598784Y1563063D01*
X1598782Y1563059D01*
G02X1597712Y1562406I-1070J550D01*
G02X1596510Y1563608I0J1202D01*
G01Y1563610D01*
G02X1596659Y1564189I1202J-1D01*
G01X1598225Y1566899D01*
X1598227Y1566902D01*
G37*
G36*
G01X1602950Y1566899D02*
X1602952Y1566902D01*
G02X1604012Y1567538I1060J-565D01*
G02X1605214Y1566336I0J-1202D01*
G01Y1566335D01*
G02X1605054Y1565736I-1203J1D01*
G01X1603509Y1563063D01*
X1603507Y1563059D01*
G02X1602437Y1562406I-1070J550D01*
G01X1602435D01*
G02X1601234Y1563608I1J1202D01*
G01Y1563610D01*
G02X1601384Y1564189I1203J-3D01*
G01X1602950Y1566899D01*
G37*
G36*
G01X1607674D02*
X1607676Y1566902D01*
G02X1608736Y1567538I1060J-565D01*
G02X1609938Y1566336I0J-1202D01*
G01Y1566335D01*
G02X1609778Y1565736I-1203J1D01*
G01X1608233Y1563063D01*
X1608231Y1563059D01*
G02X1607161Y1562406I-1070J550D01*
G01X1607159D01*
G02X1605958Y1563608I1J1202D01*
G01Y1563610D01*
G02X1606108Y1564189I1203J-3D01*
G01X1607674Y1566899D01*
G37*
G36*
G01X1612401Y1566902D02*
G02X1613461Y1567538I1060J-565D01*
G01X1613463D01*
G02X1614664Y1566336I-1J-1202D01*
G02X1614503Y1565736I-1204J1D01*
G01X1612958Y1563063D01*
X1612956Y1563059D01*
G02X1611886Y1562406I-1070J550D01*
G02X1610684Y1563608I0J1202D01*
G01Y1563610D01*
G02X1610833Y1564189I1202J-1D01*
G01X1612399Y1566899D01*
X1612401Y1566902D01*
G37*
G36*
G01X1617125D02*
G02X1618185Y1567538I1060J-565D01*
G01X1618187D01*
G02X1619388Y1566336I-1J-1202D01*
G02X1619227Y1565736I-1204J1D01*
G01X1617682Y1563063D01*
X1617680Y1563059D01*
G02X1616610Y1562406I-1070J550D01*
G02X1615408Y1563608I0J1202D01*
G01Y1563610D01*
G02X1615557Y1564189I1202J-1D01*
G01X1617123Y1566899D01*
X1617125Y1566902D01*
G37*
G36*
G01X1621849D02*
G02X1622909Y1567538I1060J-565D01*
G01X1622911D01*
G02X1624112Y1566336I-1J-1202D01*
G02X1623951Y1565736I-1204J1D01*
G01X1622406Y1563063D01*
X1622404Y1563059D01*
G02X1621334Y1562406I-1070J550D01*
G02X1620132Y1563608I0J1202D01*
G01Y1563610D01*
G02X1620281Y1564189I1202J-1D01*
G01X1621847Y1566899D01*
X1621849Y1566902D01*
G37*
G36*
G01X1626572Y1566899D02*
X1626574Y1566902D01*
G02X1627634Y1567538I1060J-565D01*
G02X1628836Y1566336I0J-1202D01*
G01Y1566335D01*
G02X1628676Y1565736I-1203J1D01*
G01X1627131Y1563063D01*
X1627129Y1563059D01*
G02X1626059Y1562406I-1070J550D01*
G01X1626057D01*
G02X1624856Y1563608I1J1202D01*
G01Y1563610D01*
G02X1625006Y1564189I1203J-3D01*
G01X1626572Y1566899D01*
G37*
G36*
G01X1631296D02*
X1631298Y1566902D01*
G02X1632358Y1567538I1060J-565D01*
G02X1633560Y1566336I0J-1202D01*
G01Y1566335D01*
G02X1633400Y1565736I-1203J1D01*
G01X1631855Y1563063D01*
X1631853Y1563059D01*
G02X1630783Y1562406I-1070J550D01*
G01X1630781D01*
G02X1629580Y1563608I1J1202D01*
G01Y1563610D01*
G02X1629730Y1564189I1203J-3D01*
G01X1631296Y1566899D01*
G37*
G36*
G01X1636023Y1566902D02*
G02X1637083Y1567538I1060J-565D01*
G01X1637085D01*
G02X1638286Y1566336I-1J-1202D01*
G02X1638125Y1565736I-1204J1D01*
G01X1636580Y1563063D01*
X1636578Y1563059D01*
G02X1635508Y1562406I-1070J550D01*
G02X1634306Y1563608I0J1202D01*
G01Y1563610D01*
G02X1634455Y1564189I1202J-1D01*
G01X1636021Y1566899D01*
X1636023Y1566902D01*
G37*
G36*
G01X1640747D02*
G02X1641807Y1567538I1060J-565D01*
G01X1641809D01*
G02X1643010Y1566336I-1J-1202D01*
G02X1642849Y1565736I-1204J1D01*
G01X1641304Y1563063D01*
X1641302Y1563059D01*
G02X1640232Y1562406I-1070J550D01*
G02X1639030Y1563608I0J1202D01*
G01Y1563610D01*
G02X1639179Y1564189I1202J-1D01*
G01X1640745Y1566899D01*
X1640747Y1566902D01*
G37*
G36*
G01X1645471D02*
G02X1646531Y1567538I1060J-565D01*
G01X1646533D01*
G02X1647734Y1566336I-1J-1202D01*
G02X1647573Y1565736I-1204J1D01*
G01X1646028Y1563063D01*
X1646026Y1563059D01*
G02X1644956Y1562406I-1070J550D01*
G02X1643754Y1563608I0J1202D01*
G01Y1563610D01*
G02X1643903Y1564189I1202J-1D01*
G01X1645469Y1566899D01*
X1645471Y1566902D01*
G37*
G36*
G01X1650194Y1566899D02*
X1650196Y1566902D01*
G02X1651256Y1567538I1060J-565D01*
G02X1652458Y1566336I0J-1202D01*
G01Y1566335D01*
G02X1652298Y1565736I-1203J1D01*
G01X1650753Y1563063D01*
X1650751Y1563059D01*
G02X1649681Y1562406I-1070J550D01*
G01X1649679D01*
G02X1648478Y1563608I1J1202D01*
G01Y1563610D01*
G02X1648628Y1564189I1203J-3D01*
G01X1650194Y1566899D01*
G37*
G36*
G01X1654918D02*
X1654920Y1566902D01*
G02X1655980Y1567538I1060J-565D01*
G02X1657182Y1566336I0J-1202D01*
G01Y1566335D01*
G02X1657022Y1565736I-1203J1D01*
G01X1655477Y1563063D01*
X1655475Y1563059D01*
G02X1654405Y1562406I-1070J550D01*
G01X1654403D01*
G02X1653202Y1563608I1J1202D01*
G01Y1563610D01*
G02X1653352Y1564189I1203J-3D01*
G01X1654918Y1566899D01*
G37*
G36*
G01X1659645Y1566902D02*
G02X1660705Y1567538I1060J-565D01*
G01X1660707D01*
G02X1661908Y1566336I-1J-1202D01*
G02X1661747Y1565736I-1204J1D01*
G01X1660202Y1563063D01*
X1660200Y1563059D01*
G02X1659130Y1562406I-1070J550D01*
G02X1657928Y1563608I0J1202D01*
G01Y1563610D01*
G02X1658077Y1564189I1202J-1D01*
G01X1659643Y1566899D01*
X1659645Y1566902D01*
G37*
G36*
G01X408001Y1575620D02*
G02X407422Y1576805I923J1185D01*
G02X410428I1503J0D01*
G02X409849Y1575620I-1502J0D01*
G03X409772Y1575463I123J-158D01*
G01Y1575147D01*
G03X409849Y1574990I200J1D01*
G02X410428Y1573805I-923J-1185D01*
G02X407422I-1503J0D01*
G02X408001Y1574990I1502J0D01*
G03X408078Y1575147I-123J158D01*
G01Y1575463D01*
G03X408001Y1575620I-200J-1D01*
G37*
G36*
G01X188166Y1590878D02*
G02Y1593882I0J1502D01*
G01X191566D01*
G02Y1590878I0J-1502D01*
G01X188166D01*
G37*
G36*
G01X200226D02*
G02Y1593882I0J1502D01*
G01X203626D01*
G02Y1590878I0J-1502D01*
G01X200226D01*
G37*
G36*
G01X212286D02*
G02Y1593882I0J1502D01*
G01X215686D01*
G02Y1590878I0J-1502D01*
G01X212286D01*
G37*
G36*
G01X224346D02*
G02Y1593882I0J1502D01*
G01X227746D01*
G02Y1590878I0J-1502D01*
G01X224346D01*
G37*
G36*
G01X236406D02*
G02Y1593882I0J1502D01*
G01X239806D01*
G02Y1590878I0J-1502D01*
G01X236406D01*
G37*
G36*
G01X248466D02*
G02Y1593882I0J1502D01*
G01X251866D01*
G02Y1590878I0J-1502D01*
G01X248466D01*
G37*
G36*
G01X260526D02*
G02Y1593882I0J1502D01*
G01X263926D01*
G02Y1590878I0J-1502D01*
G01X260526D01*
G37*
G36*
G01X272586D02*
G02Y1593882I0J1502D01*
G01X275986D01*
G02Y1590878I0J-1502D01*
G01X272586D01*
G37*
G36*
G01X284646D02*
G02Y1593882I0J1502D01*
G01X288046D01*
G02Y1590878I0J-1502D01*
G01X284646D01*
G37*
G36*
G01X296706D02*
G02Y1593882I0J1502D01*
G01X300106D01*
G02Y1590878I0J-1502D01*
G01X296706D01*
G37*
G36*
G01X308766D02*
G02Y1593882I0J1502D01*
G01X312166D01*
G02Y1590878I0J-1502D01*
G01X308766D01*
G37*
G36*
G01X320826D02*
G02Y1593882I0J1502D01*
G01X324226D01*
G02Y1590878I0J-1502D01*
G01X320826D01*
G37*
G36*
G01X332886D02*
G02Y1593882I0J1502D01*
G01X336286D01*
G02Y1590878I0J-1502D01*
G01X332886D01*
G37*
G36*
G01X344946D02*
G02Y1593882I0J1502D01*
G01X348346D01*
G02Y1590878I0J-1502D01*
G01X344946D01*
G37*
G36*
G01X357006D02*
G02Y1593882I0J1502D01*
G01X360406D01*
G02Y1590878I0J-1502D01*
G01X357006D01*
G37*
G36*
G01X369066D02*
G02Y1593882I0J1502D01*
G01X372466D01*
G02Y1590878I0J-1502D01*
G01X369066D01*
G37*
G36*
G01X452339D02*
G02Y1593882I0J1502D01*
G01X455739D01*
G02Y1590878I0J-1502D01*
G01X452339D01*
G37*
G36*
G01X464399D02*
G02Y1593882I0J1502D01*
G01X467799D01*
G02Y1590878I0J-1502D01*
G01X464399D01*
G37*
G36*
G01X476459D02*
G02Y1593882I0J1502D01*
G01X479859D01*
G02Y1590878I0J-1502D01*
G01X476459D01*
G37*
G36*
G01X488519D02*
G02Y1593882I0J1502D01*
G01X491919D01*
G02Y1590878I0J-1502D01*
G01X488519D01*
G37*
G36*
G01X500579D02*
G02Y1593882I0J1502D01*
G01X503979D01*
G02Y1590878I0J-1502D01*
G01X500579D01*
G37*
G36*
G01X512639D02*
G02Y1593882I0J1502D01*
G01X516039D01*
G02Y1590878I0J-1502D01*
G01X512639D01*
G37*
G36*
G01X524699D02*
G02Y1593882I0J1502D01*
G01X528099D01*
G02Y1590878I0J-1502D01*
G01X524699D01*
G37*
G36*
G01X536759D02*
G02Y1593882I0J1502D01*
G01X540159D01*
G02Y1590878I0J-1502D01*
G01X536759D01*
G37*
G36*
G01X548819D02*
G02Y1593882I0J1502D01*
G01X552219D01*
G02Y1590878I0J-1502D01*
G01X548819D01*
G37*
G36*
G01X560879D02*
G02Y1593882I0J1502D01*
G01X564279D01*
G02Y1590878I0J-1502D01*
G01X560879D01*
G37*
G36*
G01X572939D02*
G02Y1593882I0J1502D01*
G01X576339D01*
G02Y1590878I0J-1502D01*
G01X572939D01*
G37*
G36*
G01X584999D02*
G02Y1593882I0J1502D01*
G01X588399D01*
G02Y1590878I0J-1502D01*
G01X584999D01*
G37*
G36*
G01X597059D02*
G02Y1593882I0J1502D01*
G01X600459D01*
G02Y1590878I0J-1502D01*
G01X597059D01*
G37*
G36*
G01X609119D02*
G02Y1593882I0J1502D01*
G01X612519D01*
G02Y1590878I0J-1502D01*
G01X609119D01*
G37*
G36*
G01X621179D02*
G02Y1593882I0J1502D01*
G01X624579D01*
G02Y1590878I0J-1502D01*
G01X621179D01*
G37*
G36*
G01X633239D02*
G02Y1593882I0J1502D01*
G01X636639D01*
G02Y1590878I0J-1502D01*
G01X633239D01*
G37*
G36*
G01X422069Y1593930D02*
G02Y1596936I0J1503D01*
G01X425469D01*
G02Y1593930I0J-1503D01*
G01X422069D01*
G37*
G36*
G01X409929Y1595939D02*
G02X412054Y1598064I1063J1062D01*
G01X414459Y1595660D01*
G02X414899Y1594597I-1064J-1063D01*
G02X413396Y1593094I-1503J0D01*
G02X412333Y1593534I0J1504D01*
G01X409929Y1595939D01*
G37*
G36*
G01X194196Y1600878D02*
G02Y1603882I0J1502D01*
G01X197596D01*
G02Y1600878I0J-1502D01*
G01X194196D01*
G37*
G36*
G01X206256D02*
G02Y1603882I0J1502D01*
G01X209656D01*
G02Y1600878I0J-1502D01*
G01X206256D01*
G37*
G36*
G01X218316D02*
G02Y1603882I0J1502D01*
G01X221716D01*
G02Y1600878I0J-1502D01*
G01X218316D01*
G37*
G36*
G01X230376D02*
G02Y1603882I0J1502D01*
G01X233776D01*
G02Y1600878I0J-1502D01*
G01X230376D01*
G37*
G36*
G01X242436D02*
G02Y1603882I0J1502D01*
G01X245836D01*
G02Y1600878I0J-1502D01*
G01X242436D01*
G37*
G36*
G01X254496D02*
G02Y1603882I0J1502D01*
G01X257896D01*
G02Y1600878I0J-1502D01*
G01X254496D01*
G37*
G36*
G01X266556D02*
G02Y1603882I0J1502D01*
G01X269956D01*
G02Y1600878I0J-1502D01*
G01X266556D01*
G37*
G36*
G01X278616D02*
G02Y1603882I0J1502D01*
G01X282016D01*
G02Y1600878I0J-1502D01*
G01X278616D01*
G37*
G36*
G01X290676D02*
G02Y1603882I0J1502D01*
G01X294076D01*
G02Y1600878I0J-1502D01*
G01X290676D01*
G37*
G36*
G01X302736D02*
G02Y1603882I0J1502D01*
G01X306136D01*
G02Y1600878I0J-1502D01*
G01X302736D01*
G37*
G36*
G01X314796D02*
G02Y1603882I0J1502D01*
G01X318196D01*
G02Y1600878I0J-1502D01*
G01X314796D01*
G37*
G36*
G01X326856D02*
G02Y1603882I0J1502D01*
G01X330256D01*
G02Y1600878I0J-1502D01*
G01X326856D01*
G37*
G36*
G01X338916D02*
G02Y1603882I0J1502D01*
G01X342316D01*
G02Y1600878I0J-1502D01*
G01X338916D01*
G37*
G36*
G01X350976D02*
G02Y1603882I0J1502D01*
G01X354376D01*
G02Y1600878I0J-1502D01*
G01X350976D01*
G37*
G36*
G01X363036D02*
G02Y1603882I0J1502D01*
G01X366436D01*
G02Y1600878I0J-1502D01*
G01X363036D01*
G37*
G36*
G01X375096D02*
G02Y1603882I0J1502D01*
G01X378496D01*
G02Y1600878I0J-1502D01*
G01X375096D01*
G37*
G36*
G01X458369D02*
G02Y1603882I0J1502D01*
G01X461769D01*
G02Y1600878I0J-1502D01*
G01X458369D01*
G37*
G36*
G01X470429D02*
G02Y1603882I0J1502D01*
G01X473829D01*
G02Y1600878I0J-1502D01*
G01X470429D01*
G37*
G36*
G01X482489D02*
G02Y1603882I0J1502D01*
G01X485889D01*
G02Y1600878I0J-1502D01*
G01X482489D01*
G37*
G36*
G01X494549D02*
G02Y1603882I0J1502D01*
G01X497949D01*
G02Y1600878I0J-1502D01*
G01X494549D01*
G37*
G36*
G01X506609D02*
G02Y1603882I0J1502D01*
G01X510009D01*
G02Y1600878I0J-1502D01*
G01X506609D01*
G37*
G36*
G01X518669D02*
G02Y1603882I0J1502D01*
G01X522069D01*
G02Y1600878I0J-1502D01*
G01X518669D01*
G37*
G36*
G01X530729D02*
G02Y1603882I0J1502D01*
G01X534129D01*
G02Y1600878I0J-1502D01*
G01X530729D01*
G37*
G36*
G01X542789D02*
G02Y1603882I0J1502D01*
G01X546189D01*
G02Y1600878I0J-1502D01*
G01X542789D01*
G37*
G36*
G01X554849D02*
G02Y1603882I0J1502D01*
G01X558249D01*
G02Y1600878I0J-1502D01*
G01X554849D01*
G37*
G36*
G01X566909D02*
G02Y1603882I0J1502D01*
G01X570309D01*
G02Y1600878I0J-1502D01*
G01X566909D01*
G37*
G36*
G01X578969D02*
G02Y1603882I0J1502D01*
G01X582369D01*
G02Y1600878I0J-1502D01*
G01X578969D01*
G37*
G36*
G01X591029D02*
G02Y1603882I0J1502D01*
G01X594429D01*
G02Y1600878I0J-1502D01*
G01X591029D01*
G37*
G36*
G01X603089D02*
G02Y1603882I0J1502D01*
G01X606489D01*
G02Y1600878I0J-1502D01*
G01X603089D01*
G37*
G36*
G01X615149D02*
G02Y1603882I0J1502D01*
G01X618549D01*
G02Y1600878I0J-1502D01*
G01X615149D01*
G37*
G36*
G01X627209D02*
G02Y1603882I0J1502D01*
G01X630609D01*
G02Y1600878I0J-1502D01*
G01X627209D01*
G37*
G36*
G01X639269D02*
G02Y1603882I0J1502D01*
G01X642669D01*
G02Y1600878I0J-1502D01*
G01X639269D01*
G37*
G36*
G01X1113847Y1603052D02*
G02Y1606056I0J1502D01*
G01X1117247D01*
G02Y1603052I0J-1502D01*
G01X1113847D01*
G37*
G36*
G01X194196Y1612790D02*
G02Y1615794I0J1502D01*
G01X197596D01*
G02Y1612790I0J-1502D01*
G01X194196D01*
G37*
G36*
G01X206256D02*
G02Y1615794I0J1502D01*
G01X209656D01*
G02Y1612790I0J-1502D01*
G01X206256D01*
G37*
G36*
G01X218316D02*
G02Y1615794I0J1502D01*
G01X221716D01*
G02Y1612790I0J-1502D01*
G01X218316D01*
G37*
G36*
G01X230376D02*
G02Y1615794I0J1502D01*
G01X233776D01*
G02Y1612790I0J-1502D01*
G01X230376D01*
G37*
G36*
G01X242436D02*
G02Y1615794I0J1502D01*
G01X245836D01*
G02Y1612790I0J-1502D01*
G01X242436D01*
G37*
G36*
G01X254496D02*
G02Y1615794I0J1502D01*
G01X257896D01*
G02Y1612790I0J-1502D01*
G01X254496D01*
G37*
G36*
G01X266556D02*
G02Y1615794I0J1502D01*
G01X269956D01*
G02Y1612790I0J-1502D01*
G01X266556D01*
G37*
G36*
G01X278616D02*
G02Y1615794I0J1502D01*
G01X282016D01*
G02Y1612790I0J-1502D01*
G01X278616D01*
G37*
G36*
G01X290676D02*
G02Y1615794I0J1502D01*
G01X294076D01*
G02Y1612790I0J-1502D01*
G01X290676D01*
G37*
G36*
G01X302736D02*
G02Y1615794I0J1502D01*
G01X306136D01*
G02Y1612790I0J-1502D01*
G01X302736D01*
G37*
G36*
G01X314796D02*
G02Y1615794I0J1502D01*
G01X318196D01*
G02Y1612790I0J-1502D01*
G01X314796D01*
G37*
G36*
G01X326856D02*
G02Y1615794I0J1502D01*
G01X330256D01*
G02Y1612790I0J-1502D01*
G01X326856D01*
G37*
G36*
G01X338916D02*
G02Y1615794I0J1502D01*
G01X342316D01*
G02Y1612790I0J-1502D01*
G01X338916D01*
G37*
G36*
G01X350976D02*
G02Y1615794I0J1502D01*
G01X354376D01*
G02Y1612790I0J-1502D01*
G01X350976D01*
G37*
G36*
G01X363036D02*
G02Y1615794I0J1502D01*
G01X366436D01*
G02Y1612790I0J-1502D01*
G01X363036D01*
G37*
G36*
G01X375096D02*
G02Y1615794I0J1502D01*
G01X378496D01*
G02Y1612790I0J-1502D01*
G01X375096D01*
G37*
G36*
G01X458369D02*
G02Y1615794I0J1502D01*
G01X461769D01*
G02Y1612790I0J-1502D01*
G01X458369D01*
G37*
G36*
G01X470429D02*
G02Y1615794I0J1502D01*
G01X473829D01*
G02Y1612790I0J-1502D01*
G01X470429D01*
G37*
G36*
G01X482489D02*
G02Y1615794I0J1502D01*
G01X485889D01*
G02Y1612790I0J-1502D01*
G01X482489D01*
G37*
G36*
G01X494549D02*
G02Y1615794I0J1502D01*
G01X497949D01*
G02Y1612790I0J-1502D01*
G01X494549D01*
G37*
G36*
G01X506609D02*
G02Y1615794I0J1502D01*
G01X510009D01*
G02Y1612790I0J-1502D01*
G01X506609D01*
G37*
G36*
G01X518669D02*
G02Y1615794I0J1502D01*
G01X522069D01*
G02Y1612790I0J-1502D01*
G01X518669D01*
G37*
G36*
G01X530729D02*
G02Y1615794I0J1502D01*
G01X534129D01*
G02Y1612790I0J-1502D01*
G01X530729D01*
G37*
G36*
G01X542789D02*
G02Y1615794I0J1502D01*
G01X546189D01*
G02Y1612790I0J-1502D01*
G01X542789D01*
G37*
G36*
G01X554849D02*
G02Y1615794I0J1502D01*
G01X558249D01*
G02Y1612790I0J-1502D01*
G01X554849D01*
G37*
G36*
G01X566909D02*
G02Y1615794I0J1502D01*
G01X570309D01*
G02Y1612790I0J-1502D01*
G01X566909D01*
G37*
G36*
G01X578969D02*
G02Y1615794I0J1502D01*
G01X582369D01*
G02Y1612790I0J-1502D01*
G01X578969D01*
G37*
G36*
G01X591029D02*
G02Y1615794I0J1502D01*
G01X594429D01*
G02Y1612790I0J-1502D01*
G01X591029D01*
G37*
G36*
G01X603089D02*
G02Y1615794I0J1502D01*
G01X606489D01*
G02Y1612790I0J-1502D01*
G01X603089D01*
G37*
G36*
G01X615149D02*
G02Y1615794I0J1502D01*
G01X618549D01*
G02Y1612790I0J-1502D01*
G01X615149D01*
G37*
G36*
G01X627209D02*
G02Y1615794I0J1502D01*
G01X630609D01*
G02Y1612790I0J-1502D01*
G01X627209D01*
G37*
G36*
G01X639269D02*
G02Y1615794I0J1502D01*
G01X642669D01*
G02Y1612790I0J-1502D01*
G01X639269D01*
G37*
G36*
G01X188166Y1622790D02*
G02Y1625794I0J1502D01*
G01X191566D01*
G02Y1622790I0J-1502D01*
G01X188166D01*
G37*
G36*
G01X200226D02*
G02Y1625794I0J1502D01*
G01X203626D01*
G02Y1622790I0J-1502D01*
G01X200226D01*
G37*
G36*
G01X212286D02*
G02Y1625794I0J1502D01*
G01X215686D01*
G02Y1622790I0J-1502D01*
G01X212286D01*
G37*
G36*
G01X224346D02*
G02Y1625794I0J1502D01*
G01X227746D01*
G02Y1622790I0J-1502D01*
G01X224346D01*
G37*
G36*
G01X236406D02*
G02Y1625794I0J1502D01*
G01X239806D01*
G02Y1622790I0J-1502D01*
G01X236406D01*
G37*
G36*
G01X248466D02*
G02Y1625794I0J1502D01*
G01X251866D01*
G02Y1622790I0J-1502D01*
G01X248466D01*
G37*
G36*
G01X260526D02*
G02Y1625794I0J1502D01*
G01X263926D01*
G02Y1622790I0J-1502D01*
G01X260526D01*
G37*
G36*
G01X272586D02*
G02Y1625794I0J1502D01*
G01X275986D01*
G02Y1622790I0J-1502D01*
G01X272586D01*
G37*
G36*
G01X284646D02*
G02Y1625794I0J1502D01*
G01X288046D01*
G02Y1622790I0J-1502D01*
G01X284646D01*
G37*
G36*
G01X296706D02*
G02Y1625794I0J1502D01*
G01X300106D01*
G02Y1622790I0J-1502D01*
G01X296706D01*
G37*
G36*
G01X308766D02*
G02Y1625794I0J1502D01*
G01X312166D01*
G02Y1622790I0J-1502D01*
G01X308766D01*
G37*
G36*
G01X320826D02*
G02Y1625794I0J1502D01*
G01X324226D01*
G02Y1622790I0J-1502D01*
G01X320826D01*
G37*
G36*
G01X332886D02*
G02Y1625794I0J1502D01*
G01X336286D01*
G02Y1622790I0J-1502D01*
G01X332886D01*
G37*
G36*
G01X344946D02*
G02Y1625794I0J1502D01*
G01X348346D01*
G02Y1622790I0J-1502D01*
G01X344946D01*
G37*
G36*
G01X357006D02*
G02Y1625794I0J1502D01*
G01X360406D01*
G02Y1622790I0J-1502D01*
G01X357006D01*
G37*
G36*
G01X369066D02*
G02Y1625794I0J1502D01*
G01X372466D01*
G02Y1622790I0J-1502D01*
G01X369066D01*
G37*
G36*
G01X452339D02*
G02Y1625794I0J1502D01*
G01X455739D01*
G02Y1622790I0J-1502D01*
G01X452339D01*
G37*
G36*
G01X464399D02*
G02Y1625794I0J1502D01*
G01X467799D01*
G02Y1622790I0J-1502D01*
G01X464399D01*
G37*
G36*
G01X476459D02*
G02Y1625794I0J1502D01*
G01X479859D01*
G02Y1622790I0J-1502D01*
G01X476459D01*
G37*
G36*
G01X488519D02*
G02Y1625794I0J1502D01*
G01X491919D01*
G02Y1622790I0J-1502D01*
G01X488519D01*
G37*
G36*
G01X500579D02*
G02Y1625794I0J1502D01*
G01X503979D01*
G02Y1622790I0J-1502D01*
G01X500579D01*
G37*
G36*
G01X512639D02*
G02Y1625794I0J1502D01*
G01X516039D01*
G02Y1622790I0J-1502D01*
G01X512639D01*
G37*
G36*
G01X524699D02*
G02Y1625794I0J1502D01*
G01X528099D01*
G02Y1622790I0J-1502D01*
G01X524699D01*
G37*
G36*
G01X536759D02*
G02Y1625794I0J1502D01*
G01X540159D01*
G02Y1622790I0J-1502D01*
G01X536759D01*
G37*
G36*
G01X548819D02*
G02Y1625794I0J1502D01*
G01X552219D01*
G02Y1622790I0J-1502D01*
G01X548819D01*
G37*
G36*
G01X560879D02*
G02Y1625794I0J1502D01*
G01X564279D01*
G02Y1622790I0J-1502D01*
G01X560879D01*
G37*
G36*
G01X572939D02*
G02Y1625794I0J1502D01*
G01X576339D01*
G02Y1622790I0J-1502D01*
G01X572939D01*
G37*
G36*
G01X584999D02*
G02Y1625794I0J1502D01*
G01X588399D01*
G02Y1622790I0J-1502D01*
G01X584999D01*
G37*
G36*
G01X597059D02*
G02Y1625794I0J1502D01*
G01X600459D01*
G02Y1622790I0J-1502D01*
G01X597059D01*
G37*
G36*
G01X609119D02*
G02Y1625794I0J1502D01*
G01X612519D01*
G02Y1622790I0J-1502D01*
G01X609119D01*
G37*
G36*
G01X621179D02*
G02Y1625794I0J1502D01*
G01X624579D01*
G02Y1622790I0J-1502D01*
G01X621179D01*
G37*
G36*
G01X633239D02*
G02Y1625794I0J1502D01*
G01X636639D01*
G02Y1622790I0J-1502D01*
G01X633239D01*
G37*
G36*
G01X1196039Y1623878D02*
G02Y1626882I0J1502D01*
G01X1199439D01*
G02Y1623878I0J-1502D01*
G01X1196039D01*
G37*
G36*
G01X1208099D02*
G02Y1626882I0J1502D01*
G01X1211499D01*
G02Y1623878I0J-1502D01*
G01X1208099D01*
G37*
G36*
G01X1220159D02*
G02Y1626882I0J1502D01*
G01X1223559D01*
G02Y1623878I0J-1502D01*
G01X1220159D01*
G37*
G36*
G01X1232219D02*
G02Y1626882I0J1502D01*
G01X1235619D01*
G02Y1623878I0J-1502D01*
G01X1232219D01*
G37*
G36*
G01X1244279D02*
G02Y1626882I0J1502D01*
G01X1247679D01*
G02Y1623878I0J-1502D01*
G01X1244279D01*
G37*
G36*
G01X1256339D02*
G02Y1626882I0J1502D01*
G01X1259739D01*
G02Y1623878I0J-1502D01*
G01X1256339D01*
G37*
G36*
G01X1268399D02*
G02Y1626882I0J1502D01*
G01X1271799D01*
G02Y1623878I0J-1502D01*
G01X1268399D01*
G37*
G36*
G01X1280459D02*
G02Y1626882I0J1502D01*
G01X1283859D01*
G02Y1623878I0J-1502D01*
G01X1280459D01*
G37*
G36*
G01X1292519D02*
G02Y1626882I0J1502D01*
G01X1295919D01*
G02Y1623878I0J-1502D01*
G01X1292519D01*
G37*
G36*
G01X1304579D02*
G02Y1626882I0J1502D01*
G01X1307979D01*
G02Y1623878I0J-1502D01*
G01X1304579D01*
G37*
G36*
G01X1316639D02*
G02Y1626882I0J1502D01*
G01X1320039D01*
G02Y1623878I0J-1502D01*
G01X1316639D01*
G37*
G36*
G01X1328699D02*
G02Y1626882I0J1502D01*
G01X1332099D01*
G02Y1623878I0J-1502D01*
G01X1328699D01*
G37*
G36*
G01X1340759D02*
G02Y1626882I0J1502D01*
G01X1344159D01*
G02Y1623878I0J-1502D01*
G01X1340759D01*
G37*
G36*
G01X1352819D02*
G02Y1626882I0J1502D01*
G01X1356219D01*
G02Y1623878I0J-1502D01*
G01X1352819D01*
G37*
G36*
G01X1364879D02*
G02Y1626882I0J1502D01*
G01X1368279D01*
G02Y1623878I0J-1502D01*
G01X1364879D01*
G37*
G36*
G01X1376939D02*
G02Y1626882I0J1502D01*
G01X1380339D01*
G02Y1623878I0J-1502D01*
G01X1376939D01*
G37*
G36*
G01X1460213D02*
G02Y1626882I0J1502D01*
G01X1463613D01*
G02Y1623878I0J-1502D01*
G01X1460213D01*
G37*
G36*
G01X1472273D02*
G02Y1626882I0J1502D01*
G01X1475673D01*
G02Y1623878I0J-1502D01*
G01X1472273D01*
G37*
G36*
G01X1484333D02*
G02Y1626882I0J1502D01*
G01X1487733D01*
G02Y1623878I0J-1502D01*
G01X1484333D01*
G37*
G36*
G01X1496393D02*
G02Y1626882I0J1502D01*
G01X1499793D01*
G02Y1623878I0J-1502D01*
G01X1496393D01*
G37*
G36*
G01X1508453D02*
G02Y1626882I0J1502D01*
G01X1511853D01*
G02Y1623878I0J-1502D01*
G01X1508453D01*
G37*
G36*
G01X1520513D02*
G02Y1626882I0J1502D01*
G01X1523913D01*
G02Y1623878I0J-1502D01*
G01X1520513D01*
G37*
G36*
G01X1532573D02*
G02Y1626882I0J1502D01*
G01X1535973D01*
G02Y1623878I0J-1502D01*
G01X1532573D01*
G37*
G36*
G01X1544633D02*
G02Y1626882I0J1502D01*
G01X1548033D01*
G02Y1623878I0J-1502D01*
G01X1544633D01*
G37*
G36*
G01X1556693D02*
G02Y1626882I0J1502D01*
G01X1560093D01*
G02Y1623878I0J-1502D01*
G01X1556693D01*
G37*
G36*
G01X1568753D02*
G02Y1626882I0J1502D01*
G01X1572153D01*
G02Y1623878I0J-1502D01*
G01X1568753D01*
G37*
G36*
G01X1580813D02*
G02Y1626882I0J1502D01*
G01X1584213D01*
G02Y1623878I0J-1502D01*
G01X1580813D01*
G37*
G36*
G01X1592873D02*
G02Y1626882I0J1502D01*
G01X1596273D01*
G02Y1623878I0J-1502D01*
G01X1592873D01*
G37*
G36*
G01X1604933D02*
G02Y1626882I0J1502D01*
G01X1608333D01*
G02Y1623878I0J-1502D01*
G01X1604933D01*
G37*
G36*
G01X1616993D02*
G02Y1626882I0J1502D01*
G01X1620393D01*
G02Y1623878I0J-1502D01*
G01X1616993D01*
G37*
G36*
G01X1629053D02*
G02Y1626882I0J1502D01*
G01X1632453D01*
G02Y1623878I0J-1502D01*
G01X1629053D01*
G37*
G36*
G01X1641113D02*
G02Y1626882I0J1502D01*
G01X1644513D01*
G02Y1623878I0J-1502D01*
G01X1641113D01*
G37*
G36*
G01X417365Y1626192D02*
G02Y1629198I0J1503D01*
G01X420765D01*
G02Y1626192I0J-1503D01*
G01X417365D01*
G37*
G36*
G01X1202069Y1633878D02*
G02Y1636882I0J1502D01*
G01X1205469D01*
G02Y1633878I0J-1502D01*
G01X1202069D01*
G37*
G36*
G01X1214129D02*
G02Y1636882I0J1502D01*
G01X1217529D01*
G02Y1633878I0J-1502D01*
G01X1214129D01*
G37*
G36*
G01X1226189D02*
G02Y1636882I0J1502D01*
G01X1229589D01*
G02Y1633878I0J-1502D01*
G01X1226189D01*
G37*
G36*
G01X1238249D02*
G02Y1636882I0J1502D01*
G01X1241649D01*
G02Y1633878I0J-1502D01*
G01X1238249D01*
G37*
G36*
G01X1250309D02*
G02Y1636882I0J1502D01*
G01X1253709D01*
G02Y1633878I0J-1502D01*
G01X1250309D01*
G37*
G36*
G01X1262369D02*
G02Y1636882I0J1502D01*
G01X1265769D01*
G02Y1633878I0J-1502D01*
G01X1262369D01*
G37*
G36*
G01X1274429D02*
G02Y1636882I0J1502D01*
G01X1277829D01*
G02Y1633878I0J-1502D01*
G01X1274429D01*
G37*
G36*
G01X1286489D02*
G02Y1636882I0J1502D01*
G01X1289889D01*
G02Y1633878I0J-1502D01*
G01X1286489D01*
G37*
G36*
G01X1298549D02*
G02Y1636882I0J1502D01*
G01X1301949D01*
G02Y1633878I0J-1502D01*
G01X1298549D01*
G37*
G36*
G01X1310609D02*
G02Y1636882I0J1502D01*
G01X1314009D01*
G02Y1633878I0J-1502D01*
G01X1310609D01*
G37*
G36*
G01X1322669D02*
G02Y1636882I0J1502D01*
G01X1326069D01*
G02Y1633878I0J-1502D01*
G01X1322669D01*
G37*
G36*
G01X1334729D02*
G02Y1636882I0J1502D01*
G01X1338129D01*
G02Y1633878I0J-1502D01*
G01X1334729D01*
G37*
G36*
G01X1346789D02*
G02Y1636882I0J1502D01*
G01X1350189D01*
G02Y1633878I0J-1502D01*
G01X1346789D01*
G37*
G36*
G01X1358849D02*
G02Y1636882I0J1502D01*
G01X1362249D01*
G02Y1633878I0J-1502D01*
G01X1358849D01*
G37*
G36*
G01X1370909D02*
G02Y1636882I0J1502D01*
G01X1374309D01*
G02Y1633878I0J-1502D01*
G01X1370909D01*
G37*
G36*
G01X1382969D02*
G02Y1636882I0J1502D01*
G01X1386369D01*
G02Y1633878I0J-1502D01*
G01X1382969D01*
G37*
G36*
G01X1466243D02*
G02Y1636882I0J1502D01*
G01X1469643D01*
G02Y1633878I0J-1502D01*
G01X1466243D01*
G37*
G36*
G01X1478303D02*
G02Y1636882I0J1502D01*
G01X1481703D01*
G02Y1633878I0J-1502D01*
G01X1478303D01*
G37*
G36*
G01X1490363D02*
G02Y1636882I0J1502D01*
G01X1493763D01*
G02Y1633878I0J-1502D01*
G01X1490363D01*
G37*
G36*
G01X1502423D02*
G02Y1636882I0J1502D01*
G01X1505823D01*
G02Y1633878I0J-1502D01*
G01X1502423D01*
G37*
G36*
G01X1514483D02*
G02Y1636882I0J1502D01*
G01X1517883D01*
G02Y1633878I0J-1502D01*
G01X1514483D01*
G37*
G36*
G01X1526543D02*
G02Y1636882I0J1502D01*
G01X1529943D01*
G02Y1633878I0J-1502D01*
G01X1526543D01*
G37*
G36*
G01X1538603D02*
G02Y1636882I0J1502D01*
G01X1542003D01*
G02Y1633878I0J-1502D01*
G01X1538603D01*
G37*
G36*
G01X1550663D02*
G02Y1636882I0J1502D01*
G01X1554063D01*
G02Y1633878I0J-1502D01*
G01X1550663D01*
G37*
G36*
G01X1562723D02*
G02Y1636882I0J1502D01*
G01X1566123D01*
G02Y1633878I0J-1502D01*
G01X1562723D01*
G37*
G36*
G01X1574783D02*
G02Y1636882I0J1502D01*
G01X1578183D01*
G02Y1633878I0J-1502D01*
G01X1574783D01*
G37*
G36*
G01X1586843D02*
G02Y1636882I0J1502D01*
G01X1590243D01*
G02Y1633878I0J-1502D01*
G01X1586843D01*
G37*
G36*
G01X1598903D02*
G02Y1636882I0J1502D01*
G01X1602303D01*
G02Y1633878I0J-1502D01*
G01X1598903D01*
G37*
G36*
G01X1610963D02*
G02Y1636882I0J1502D01*
G01X1614363D01*
G02Y1633878I0J-1502D01*
G01X1610963D01*
G37*
G36*
G01X1623023D02*
G02Y1636882I0J1502D01*
G01X1626423D01*
G02Y1633878I0J-1502D01*
G01X1623023D01*
G37*
G36*
G01X1635083D02*
G02Y1636882I0J1502D01*
G01X1638483D01*
G02Y1633878I0J-1502D01*
G01X1635083D01*
G37*
G36*
G01X1647143D02*
G02Y1636882I0J1502D01*
G01X1650543D01*
G02Y1633878I0J-1502D01*
G01X1647143D01*
G37*
G36*
G01X1202069Y1645790D02*
G02Y1648794I0J1502D01*
G01X1205469D01*
G02Y1645790I0J-1502D01*
G01X1202069D01*
G37*
G36*
G01X1214129D02*
G02Y1648794I0J1502D01*
G01X1217529D01*
G02Y1645790I0J-1502D01*
G01X1214129D01*
G37*
G36*
G01X1226189D02*
G02Y1648794I0J1502D01*
G01X1229589D01*
G02Y1645790I0J-1502D01*
G01X1226189D01*
G37*
G36*
G01X1238249D02*
G02Y1648794I0J1502D01*
G01X1241649D01*
G02Y1645790I0J-1502D01*
G01X1238249D01*
G37*
G36*
G01X1250309D02*
G02Y1648794I0J1502D01*
G01X1253709D01*
G02Y1645790I0J-1502D01*
G01X1250309D01*
G37*
G36*
G01X1262369D02*
G02Y1648794I0J1502D01*
G01X1265769D01*
G02Y1645790I0J-1502D01*
G01X1262369D01*
G37*
G36*
G01X1274429D02*
G02Y1648794I0J1502D01*
G01X1277829D01*
G02Y1645790I0J-1502D01*
G01X1274429D01*
G37*
G36*
G01X1286489D02*
G02Y1648794I0J1502D01*
G01X1289889D01*
G02Y1645790I0J-1502D01*
G01X1286489D01*
G37*
G36*
G01X1298549D02*
G02Y1648794I0J1502D01*
G01X1301949D01*
G02Y1645790I0J-1502D01*
G01X1298549D01*
G37*
G36*
G01X1310609D02*
G02Y1648794I0J1502D01*
G01X1314009D01*
G02Y1645790I0J-1502D01*
G01X1310609D01*
G37*
G36*
G01X1322669D02*
G02Y1648794I0J1502D01*
G01X1326069D01*
G02Y1645790I0J-1502D01*
G01X1322669D01*
G37*
G36*
G01X1334729D02*
G02Y1648794I0J1502D01*
G01X1338129D01*
G02Y1645790I0J-1502D01*
G01X1334729D01*
G37*
G36*
G01X1346789D02*
G02Y1648794I0J1502D01*
G01X1350189D01*
G02Y1645790I0J-1502D01*
G01X1346789D01*
G37*
G36*
G01X1358849D02*
G02Y1648794I0J1502D01*
G01X1362249D01*
G02Y1645790I0J-1502D01*
G01X1358849D01*
G37*
G36*
G01X1370909D02*
G02Y1648794I0J1502D01*
G01X1374309D01*
G02Y1645790I0J-1502D01*
G01X1370909D01*
G37*
G36*
G01X1382969D02*
G02Y1648794I0J1502D01*
G01X1386369D01*
G02Y1645790I0J-1502D01*
G01X1382969D01*
G37*
G36*
G01X1466243D02*
G02Y1648794I0J1502D01*
G01X1469643D01*
G02Y1645790I0J-1502D01*
G01X1466243D01*
G37*
G36*
G01X1478303D02*
G02Y1648794I0J1502D01*
G01X1481703D01*
G02Y1645790I0J-1502D01*
G01X1478303D01*
G37*
G36*
G01X1490363D02*
G02Y1648794I0J1502D01*
G01X1493763D01*
G02Y1645790I0J-1502D01*
G01X1490363D01*
G37*
G36*
G01X1502423D02*
G02Y1648794I0J1502D01*
G01X1505823D01*
G02Y1645790I0J-1502D01*
G01X1502423D01*
G37*
G36*
G01X1514483D02*
G02Y1648794I0J1502D01*
G01X1517883D01*
G02Y1645790I0J-1502D01*
G01X1514483D01*
G37*
G36*
G01X1526543D02*
G02Y1648794I0J1502D01*
G01X1529943D01*
G02Y1645790I0J-1502D01*
G01X1526543D01*
G37*
G36*
G01X1538603D02*
G02Y1648794I0J1502D01*
G01X1542003D01*
G02Y1645790I0J-1502D01*
G01X1538603D01*
G37*
G36*
G01X1550663D02*
G02Y1648794I0J1502D01*
G01X1554063D01*
G02Y1645790I0J-1502D01*
G01X1550663D01*
G37*
G36*
G01X1562723D02*
G02Y1648794I0J1502D01*
G01X1566123D01*
G02Y1645790I0J-1502D01*
G01X1562723D01*
G37*
G36*
G01X1574783D02*
G02Y1648794I0J1502D01*
G01X1578183D01*
G02Y1645790I0J-1502D01*
G01X1574783D01*
G37*
G36*
G01X1586843D02*
G02Y1648794I0J1502D01*
G01X1590243D01*
G02Y1645790I0J-1502D01*
G01X1586843D01*
G37*
G36*
G01X1598903D02*
G02Y1648794I0J1502D01*
G01X1602303D01*
G02Y1645790I0J-1502D01*
G01X1598903D01*
G37*
G36*
G01X1610963D02*
G02Y1648794I0J1502D01*
G01X1614363D01*
G02Y1645790I0J-1502D01*
G01X1610963D01*
G37*
G36*
G01X1623023D02*
G02Y1648794I0J1502D01*
G01X1626423D01*
G02Y1645790I0J-1502D01*
G01X1623023D01*
G37*
G36*
G01X1635083D02*
G02Y1648794I0J1502D01*
G01X1638483D01*
G02Y1645790I0J-1502D01*
G01X1635083D01*
G37*
G36*
G01X1647143D02*
G02Y1648794I0J1502D01*
G01X1650543D01*
G02Y1645790I0J-1502D01*
G01X1647143D01*
G37*
G36*
G01X228902Y1656537D02*
G02X229205Y1656840I303J0D01*
G01X232905D01*
G02X233208Y1656537I0J-303D01*
G01Y1646531D01*
G02X232905Y1646228I-303J0D01*
G01X229205D01*
G02X228902Y1646531I0J303D01*
G01Y1656537D01*
G37*
G36*
G01X276146D02*
G02X276449Y1656840I303J0D01*
G01X280149D01*
G02X280452Y1656537I0J-303D01*
G01Y1646531D01*
G02X280149Y1646228I-303J0D01*
G01X276449D01*
G02X276146Y1646531I0J303D01*
G01Y1656537D01*
G37*
G36*
G01X382478Y1657961D02*
G02X382681Y1658164I203J0D01*
G01X401967D01*
G02X402170Y1657961I0J-203D01*
G01Y1631213D01*
G02X401967Y1631010I-203J0D01*
G01X382681D01*
G02X382478Y1631213I0J203D01*
G01Y1657961D01*
G37*
G36*
G01X1196039Y1655790D02*
G02Y1658794I0J1502D01*
G01X1199439D01*
G02Y1655790I0J-1502D01*
G01X1196039D01*
G37*
G36*
G01X1208099D02*
G02Y1658794I0J1502D01*
G01X1211499D01*
G02Y1655790I0J-1502D01*
G01X1208099D01*
G37*
G36*
G01X1220159D02*
G02Y1658794I0J1502D01*
G01X1223559D01*
G02Y1655790I0J-1502D01*
G01X1220159D01*
G37*
G36*
G01X1232219D02*
G02Y1658794I0J1502D01*
G01X1235619D01*
G02Y1655790I0J-1502D01*
G01X1232219D01*
G37*
G36*
G01X1244279D02*
G02Y1658794I0J1502D01*
G01X1247679D01*
G02Y1655790I0J-1502D01*
G01X1244279D01*
G37*
G36*
G01X1256339D02*
G02Y1658794I0J1502D01*
G01X1259739D01*
G02Y1655790I0J-1502D01*
G01X1256339D01*
G37*
G36*
G01X1268399D02*
G02Y1658794I0J1502D01*
G01X1271799D01*
G02Y1655790I0J-1502D01*
G01X1268399D01*
G37*
G36*
G01X1280459D02*
G02Y1658794I0J1502D01*
G01X1283859D01*
G02Y1655790I0J-1502D01*
G01X1280459D01*
G37*
G36*
G01X1292519D02*
G02Y1658794I0J1502D01*
G01X1295919D01*
G02Y1655790I0J-1502D01*
G01X1292519D01*
G37*
G36*
G01X1304579D02*
G02Y1658794I0J1502D01*
G01X1307979D01*
G02Y1655790I0J-1502D01*
G01X1304579D01*
G37*
G36*
G01X1316639D02*
G02Y1658794I0J1502D01*
G01X1320039D01*
G02Y1655790I0J-1502D01*
G01X1316639D01*
G37*
G36*
G01X1328699D02*
G02Y1658794I0J1502D01*
G01X1332099D01*
G02Y1655790I0J-1502D01*
G01X1328699D01*
G37*
G36*
G01X1340759D02*
G02Y1658794I0J1502D01*
G01X1344159D01*
G02Y1655790I0J-1502D01*
G01X1340759D01*
G37*
G36*
G01X1352819D02*
G02Y1658794I0J1502D01*
G01X1356219D01*
G02Y1655790I0J-1502D01*
G01X1352819D01*
G37*
G36*
G01X1364879D02*
G02Y1658794I0J1502D01*
G01X1368279D01*
G02Y1655790I0J-1502D01*
G01X1364879D01*
G37*
G36*
G01X1376939D02*
G02Y1658794I0J1502D01*
G01X1380339D01*
G02Y1655790I0J-1502D01*
G01X1376939D01*
G37*
G36*
G01X1460213D02*
G02Y1658794I0J1502D01*
G01X1463613D01*
G02Y1655790I0J-1502D01*
G01X1460213D01*
G37*
G36*
G01X1472273D02*
G02Y1658794I0J1502D01*
G01X1475673D01*
G02Y1655790I0J-1502D01*
G01X1472273D01*
G37*
G36*
G01X1484333D02*
G02Y1658794I0J1502D01*
G01X1487733D01*
G02Y1655790I0J-1502D01*
G01X1484333D01*
G37*
G36*
G01X1496393D02*
G02Y1658794I0J1502D01*
G01X1499793D01*
G02Y1655790I0J-1502D01*
G01X1496393D01*
G37*
G36*
G01X1508453D02*
G02Y1658794I0J1502D01*
G01X1511853D01*
G02Y1655790I0J-1502D01*
G01X1508453D01*
G37*
G36*
G01X1520513D02*
G02Y1658794I0J1502D01*
G01X1523913D01*
G02Y1655790I0J-1502D01*
G01X1520513D01*
G37*
G36*
G01X1532573D02*
G02Y1658794I0J1502D01*
G01X1535973D01*
G02Y1655790I0J-1502D01*
G01X1532573D01*
G37*
G36*
G01X1544633D02*
G02Y1658794I0J1502D01*
G01X1548033D01*
G02Y1655790I0J-1502D01*
G01X1544633D01*
G37*
G36*
G01X1556693D02*
G02Y1658794I0J1502D01*
G01X1560093D01*
G02Y1655790I0J-1502D01*
G01X1556693D01*
G37*
G36*
G01X1568753D02*
G02Y1658794I0J1502D01*
G01X1572153D01*
G02Y1655790I0J-1502D01*
G01X1568753D01*
G37*
G36*
G01X1580813D02*
G02Y1658794I0J1502D01*
G01X1584213D01*
G02Y1655790I0J-1502D01*
G01X1580813D01*
G37*
G36*
G01X1592873D02*
G02Y1658794I0J1502D01*
G01X1596273D01*
G02Y1655790I0J-1502D01*
G01X1592873D01*
G37*
G36*
G01X1604933D02*
G02Y1658794I0J1502D01*
G01X1608333D01*
G02Y1655790I0J-1502D01*
G01X1604933D01*
G37*
G36*
G01X1616993D02*
G02Y1658794I0J1502D01*
G01X1620393D01*
G02Y1655790I0J-1502D01*
G01X1616993D01*
G37*
G36*
G01X1629053D02*
G02Y1658794I0J1502D01*
G01X1632453D01*
G02Y1655790I0J-1502D01*
G01X1629053D01*
G37*
G36*
G01X1641113D02*
G02Y1658794I0J1502D01*
G01X1644513D01*
G02Y1655790I0J-1502D01*
G01X1641113D01*
G37*
G36*
G01X237079Y1660776D02*
X240779D01*
G02X241082Y1660474I1J-302D01*
G01Y1650468D01*
G02X240779Y1650166I-303J1D01*
G01X237079D01*
G02X236776Y1650468I-1J302D01*
G01Y1660474D01*
G02X237079Y1660776I303J-1D01*
G37*
G36*
G01X268575D02*
X272275D01*
G02X272578Y1660474I1J-302D01*
G01Y1650468D01*
G02X272275Y1650166I-303J1D01*
G01X268575D01*
G02X268272Y1650468I-1J302D01*
G01Y1660474D01*
G02X268575Y1660776I303J-1D01*
G37*
G36*
G01X284323D02*
X288023D01*
G02X288326Y1660474I1J-302D01*
G01Y1650468D01*
G02X288023Y1650166I-303J1D01*
G01X284323D01*
G02X284020Y1650468I-1J302D01*
G01Y1660474D01*
G02X284323Y1660776I303J-1D01*
G37*
G36*
G01X109073Y1658732D02*
G02Y1661738I0J1503D01*
G01X112473D01*
G02Y1658732I0J-1503D01*
G01X109073D01*
G37*
G36*
G01X1125784Y1661202D02*
G02Y1664208I0J1503D01*
G01X1129184D01*
G02Y1661202I0J-1503D01*
G01X1125784D01*
G37*
G36*
G01X1438232Y1664144D02*
G02X1438436Y1664348I204J0D01*
G01X1457722D01*
G02X1457926Y1664144I0J-204D01*
G01Y1658186D01*
X1457330D01*
G03X1457154Y1658019I22J-199D01*
G01Y1656621D01*
G03X1457330Y1656454I198J32D01*
G01X1457926D01*
Y1637396D01*
G02X1457722Y1637192I-204J0D01*
G01X1438436D01*
G02X1438232Y1637396I0J204D01*
G01Y1664144D01*
G37*
G36*
G01X154111Y1662430D02*
G02Y1665436I0J1503D01*
G01X157511D01*
G02Y1662430I0J-1503D01*
G01X154111D01*
G37*
G36*
G01X228902Y1670711D02*
G02X229205Y1671014I303J0D01*
G01X232905D01*
G02X233208Y1670711I0J-303D01*
G01Y1660705D01*
G02X232905Y1660402I-303J0D01*
G01X229205D01*
G02X228902Y1660705I0J303D01*
G01Y1670711D01*
G37*
G36*
G01X244650D02*
G02X244953Y1671014I303J0D01*
G01X248653D01*
G02X248956Y1670711I0J-303D01*
G01Y1660705D01*
G02X248653Y1660402I-303J0D01*
G01X244953D01*
G02X244650Y1660705I0J303D01*
G01Y1670711D01*
G37*
G36*
G01X276146D02*
G02X276449Y1671014I303J0D01*
G01X280149D01*
G02X280452Y1670711I0J-303D01*
G01Y1660705D01*
G02X280149Y1660402I-303J0D01*
G01X276449D01*
G02X276146Y1660705I0J303D01*
G01Y1670711D01*
G37*
G36*
G01X252827Y1674950D02*
X256527D01*
G02X256830Y1674648I1J-302D01*
G01Y1664642D01*
G02X256527Y1664340I-303J1D01*
G01X252827D01*
G02X252524Y1664642I-1J302D01*
G01Y1674648D01*
G02X252827Y1674950I303J-1D01*
G37*
G36*
G01X268575D02*
X272275D01*
G02X272578Y1674648I1J-302D01*
G01Y1664642D01*
G02X272275Y1664340I-303J1D01*
G01X268575D01*
G02X268272Y1664642I-1J302D01*
G01Y1674648D01*
G02X268575Y1674950I303J-1D01*
G37*
G36*
G01X284323D02*
X288023D01*
G02X288326Y1674648I1J-302D01*
G01Y1664642D01*
G02X288023Y1664340I-303J1D01*
G01X284323D01*
G02X284020Y1664642I-1J302D01*
G01Y1674648D01*
G02X284323Y1674950I303J-1D01*
G37*
G36*
G01X154010Y1675308D02*
G02Y1678314I0J1503D01*
G01X157410D01*
G02Y1675308I0J-1503D01*
G01X154010D01*
G37*
G36*
G01X295832Y1684884D02*
G02X296134Y1685186I302J0D01*
G01X299834D01*
G02X300136Y1684884I0J-302D01*
G01Y1674878D01*
G02X299834Y1674576I-302J0D01*
G01X296134D01*
G02X295832Y1674878I0J302D01*
G01Y1677743D01*
G02X295863Y1677876I302J0D01*
G01X296782Y1679751D01*
G03Y1680013I-267J131D01*
G01X295863Y1681888D01*
G02X295832Y1682021I271J133D01*
G01Y1684884D01*
G37*
G36*
G01X311580D02*
G02X311882Y1685186I302J0D01*
G01X315582D01*
G02X315884Y1684884I0J-302D01*
G01Y1674878D01*
G02X315582Y1674576I-302J0D01*
G01X311882D01*
G02X311580Y1674878I0J302D01*
G01Y1677743D01*
G02X311611Y1677876I302J0D01*
G01X312530Y1679751D01*
G03Y1680013I-267J131D01*
G01X311611Y1681888D01*
G02X311580Y1682021I271J133D01*
G01Y1684884D01*
G37*
G36*
G01X327328D02*
G02X327630Y1685186I302J0D01*
G01X331330D01*
G02X331632Y1684884I0J-302D01*
G01Y1674878D01*
G02X331330Y1674576I-302J0D01*
G01X327630D01*
G02X327328Y1674878I0J302D01*
G01Y1677743D01*
G02X327359Y1677876I302J0D01*
G01X328278Y1679751D01*
G03Y1680013I-267J131D01*
G01X327359Y1681888D01*
G02X327328Y1682021I271J133D01*
G01Y1684884D01*
G37*
G36*
G01X343076D02*
G02X343378Y1685186I302J0D01*
G01X347078D01*
G02X347380Y1684884I0J-302D01*
G01Y1674878D01*
G02X347078Y1674576I-302J0D01*
G01X343378D01*
G02X343076Y1674878I0J302D01*
G01Y1677743D01*
G02X343107Y1677876I302J0D01*
G01X344026Y1679751D01*
G03Y1680013I-267J131D01*
G01X343107Y1681888D01*
G02X343076Y1682021I271J133D01*
G01Y1684884D01*
G37*
G36*
G01X493076D02*
G02X493378Y1685186I302J0D01*
G01X497078D01*
G02X497380Y1684884I0J-302D01*
G01Y1674878D01*
G02X497078Y1674576I-302J0D01*
G01X493378D01*
G02X493076Y1674878I0J302D01*
G01Y1677743D01*
G02X493107Y1677876I302J0D01*
G01X494026Y1679751D01*
G03Y1680013I-267J131D01*
G01X493107Y1681888D01*
G02X493076Y1682021I271J133D01*
G01Y1684884D01*
G37*
G36*
G01X508824D02*
G02X509126Y1685186I302J0D01*
G01X512826D01*
G02X513128Y1684884I0J-302D01*
G01Y1674878D01*
G02X512826Y1674576I-302J0D01*
G01X509126D01*
G02X508824Y1674878I0J302D01*
G01Y1677743D01*
G02X508855Y1677876I302J0D01*
G01X509774Y1679751D01*
G03Y1680013I-267J131D01*
G01X508855Y1681888D01*
G02X508824Y1682021I271J133D01*
G01Y1684884D01*
G37*
G36*
G01X524572D02*
G02X524874Y1685186I302J0D01*
G01X528574D01*
G02X528876Y1684884I0J-302D01*
G01Y1674878D01*
G02X528574Y1674576I-302J0D01*
G01X524874D01*
G02X524572Y1674878I0J302D01*
G01Y1677743D01*
G02X524603Y1677876I302J0D01*
G01X525522Y1679751D01*
G03Y1680013I-267J131D01*
G01X524603Y1681888D01*
G02X524572Y1682021I271J133D01*
G01Y1684884D01*
G37*
G36*
G01X540320D02*
G02X540622Y1685186I302J0D01*
G01X544322D01*
G02X544624Y1684884I0J-302D01*
G01Y1674878D01*
G02X544322Y1674576I-302J0D01*
G01X540622D01*
G02X540320Y1674878I0J302D01*
G01Y1677743D01*
G02X540351Y1677876I302J0D01*
G01X541270Y1679751D01*
G03Y1680013I-267J131D01*
G01X540351Y1681888D01*
G02X540320Y1682021I271J133D01*
G01Y1684884D01*
G37*
G36*
G01X560006D02*
G02X560308Y1685186I302J0D01*
G01X564008D01*
G02X564310Y1684884I0J-302D01*
G01Y1674878D01*
G02X564008Y1674576I-302J0D01*
G01X560308D01*
G02X560006Y1674878I0J302D01*
G01Y1677743D01*
G02X560037Y1677876I302J0D01*
G01X560956Y1679751D01*
G03Y1680013I-267J131D01*
G01X560037Y1681888D01*
G02X560006Y1682021I271J133D01*
G01Y1684884D01*
G37*
G36*
G01X575754D02*
G02X576056Y1685186I302J0D01*
G01X579756D01*
G02X580058Y1684884I0J-302D01*
G01Y1674878D01*
G02X579756Y1674576I-302J0D01*
G01X576056D01*
G02X575754Y1674878I0J302D01*
G01Y1677743D01*
G02X575785Y1677876I302J0D01*
G01X576704Y1679751D01*
G03Y1680013I-267J131D01*
G01X575785Y1681888D01*
G02X575754Y1682021I271J133D01*
G01Y1684884D01*
G37*
G36*
G01X591502D02*
G02X591804Y1685186I302J0D01*
G01X595504D01*
G02X595806Y1684884I0J-302D01*
G01Y1674878D01*
G02X595504Y1674576I-302J0D01*
G01X591804D01*
G02X591502Y1674878I0J302D01*
G01Y1677743D01*
G02X591533Y1677876I302J0D01*
G01X592452Y1679751D01*
G03Y1680013I-267J131D01*
G01X591533Y1681888D01*
G02X591502Y1682021I271J133D01*
G01Y1684884D01*
G37*
G36*
G01X607250D02*
G02X607552Y1685186I302J0D01*
G01X611252D01*
G02X611554Y1684884I0J-302D01*
G01Y1674878D01*
G02X611252Y1674576I-302J0D01*
G01X607552D01*
G02X607250Y1674878I0J302D01*
G01Y1677743D01*
G02X607281Y1677876I302J0D01*
G01X608200Y1679751D01*
G03Y1680013I-267J131D01*
G01X607281Y1681888D01*
G02X607250Y1682021I271J133D01*
G01Y1684884D01*
G37*
G36*
G01X1236776D02*
G02X1237078Y1685186I302J0D01*
G01X1240778D01*
G02X1241080Y1684884I0J-302D01*
G01Y1674878D01*
G02X1240778Y1674576I-302J0D01*
G01X1237078D01*
G02X1236776Y1674878I0J302D01*
G01Y1677743D01*
G02X1236807Y1677876I302J0D01*
G01X1237726Y1679751D01*
G03Y1680013I-267J131D01*
G01X1236807Y1681888D01*
G02X1236776Y1682021I271J133D01*
G01Y1684884D01*
G37*
G36*
G01X1252524D02*
G02X1252826Y1685186I302J0D01*
G01X1256526D01*
G02X1256828Y1684884I0J-302D01*
G01Y1674878D01*
G02X1256526Y1674576I-302J0D01*
G01X1252826D01*
G02X1252524Y1674878I0J302D01*
G01Y1677743D01*
G02X1252555Y1677876I302J0D01*
G01X1253474Y1679751D01*
G03Y1680013I-267J131D01*
G01X1252555Y1681888D01*
G02X1252524Y1682021I271J133D01*
G01Y1684884D01*
G37*
G36*
G01X1268272D02*
G02X1268574Y1685186I302J0D01*
G01X1272274D01*
G02X1272576Y1684884I0J-302D01*
G01Y1674878D01*
G02X1272274Y1674576I-302J0D01*
G01X1268574D01*
G02X1268272Y1674878I0J302D01*
G01Y1677743D01*
G02X1268303Y1677876I302J0D01*
G01X1269222Y1679751D01*
G03Y1680013I-267J131D01*
G01X1268303Y1681888D01*
G02X1268272Y1682021I271J133D01*
G01Y1684884D01*
G37*
G36*
G01X1284020D02*
G02X1284322Y1685186I302J0D01*
G01X1288022D01*
G02X1288324Y1684884I0J-302D01*
G01Y1674878D01*
G02X1288022Y1674576I-302J0D01*
G01X1284322D01*
G02X1284020Y1674878I0J302D01*
G01Y1677743D01*
G02X1284051Y1677876I302J0D01*
G01X1284970Y1679751D01*
G03Y1680013I-267J131D01*
G01X1284051Y1681888D01*
G02X1284020Y1682021I271J133D01*
G01Y1684884D01*
G37*
G36*
G01X1303706D02*
G02X1304008Y1685186I302J0D01*
G01X1307708D01*
G02X1308010Y1684884I0J-302D01*
G01Y1674878D01*
G02X1307708Y1674576I-302J0D01*
G01X1304008D01*
G02X1303706Y1674878I0J302D01*
G01Y1677743D01*
G02X1303737Y1677876I302J0D01*
G01X1304656Y1679751D01*
G03Y1680013I-267J131D01*
G01X1303737Y1681888D01*
G02X1303706Y1682021I271J133D01*
G01Y1684884D01*
G37*
G36*
G01X1319454D02*
G02X1319756Y1685186I302J0D01*
G01X1323456D01*
G02X1323758Y1684884I0J-302D01*
G01Y1674878D01*
G02X1323456Y1674576I-302J0D01*
G01X1319756D01*
G02X1319454Y1674878I0J302D01*
G01Y1677743D01*
G02X1319485Y1677876I302J0D01*
G01X1320404Y1679751D01*
G03Y1680013I-267J131D01*
G01X1319485Y1681888D01*
G02X1319454Y1682021I271J133D01*
G01Y1684884D01*
G37*
G36*
G01X1335202D02*
G02X1335504Y1685186I302J0D01*
G01X1339204D01*
G02X1339506Y1684884I0J-302D01*
G01Y1674878D01*
G02X1339204Y1674576I-302J0D01*
G01X1335504D01*
G02X1335202Y1674878I0J302D01*
G01Y1677743D01*
G02X1335233Y1677876I302J0D01*
G01X1336152Y1679751D01*
G03Y1680013I-267J131D01*
G01X1335233Y1681888D01*
G02X1335202Y1682021I271J133D01*
G01Y1684884D01*
G37*
G36*
G01X1350950D02*
G02X1351252Y1685186I302J0D01*
G01X1354952D01*
G02X1355254Y1684884I0J-302D01*
G01Y1674878D01*
G02X1354952Y1674576I-302J0D01*
G01X1351252D01*
G02X1350950Y1674878I0J302D01*
G01Y1677743D01*
G02X1350981Y1677876I302J0D01*
G01X1351900Y1679751D01*
G03Y1680013I-267J131D01*
G01X1350981Y1681888D01*
G02X1350950Y1682021I271J133D01*
G01Y1684884D01*
G37*
G36*
G01X1500950D02*
G02X1501252Y1685186I302J0D01*
G01X1504952D01*
G02X1505254Y1684884I0J-302D01*
G01Y1674878D01*
G02X1504952Y1674576I-302J0D01*
G01X1501252D01*
G02X1500950Y1674878I0J302D01*
G01Y1677743D01*
G02X1500981Y1677876I302J0D01*
G01X1501900Y1679751D01*
G03Y1680013I-267J131D01*
G01X1500981Y1681888D01*
G02X1500950Y1682021I271J133D01*
G01Y1684884D01*
G37*
G36*
G01X1516698D02*
G02X1517000Y1685186I302J0D01*
G01X1520700D01*
G02X1521002Y1684884I0J-302D01*
G01Y1674878D01*
G02X1520700Y1674576I-302J0D01*
G01X1517000D01*
G02X1516698Y1674878I0J302D01*
G01Y1677743D01*
G02X1516729Y1677876I302J0D01*
G01X1517648Y1679751D01*
G03Y1680013I-267J131D01*
G01X1516729Y1681888D01*
G02X1516698Y1682021I271J133D01*
G01Y1684884D01*
G37*
G36*
G01X1532446D02*
G02X1532748Y1685186I302J0D01*
G01X1536448D01*
G02X1536750Y1684884I0J-302D01*
G01Y1674878D01*
G02X1536448Y1674576I-302J0D01*
G01X1532748D01*
G02X1532446Y1674878I0J302D01*
G01Y1677743D01*
G02X1532477Y1677876I302J0D01*
G01X1533396Y1679751D01*
G03Y1680013I-267J131D01*
G01X1532477Y1681888D01*
G02X1532446Y1682021I271J133D01*
G01Y1684884D01*
G37*
G36*
G01X1548194D02*
G02X1548496Y1685186I302J0D01*
G01X1552196D01*
G02X1552498Y1684884I0J-302D01*
G01Y1674878D01*
G02X1552196Y1674576I-302J0D01*
G01X1548496D01*
G02X1548194Y1674878I0J302D01*
G01Y1677743D01*
G02X1548225Y1677876I302J0D01*
G01X1549144Y1679751D01*
G03Y1680013I-267J131D01*
G01X1548225Y1681888D01*
G02X1548194Y1682021I271J133D01*
G01Y1684884D01*
G37*
G36*
G01X1567880D02*
G02X1568182Y1685186I302J0D01*
G01X1571882D01*
G02X1572184Y1684884I0J-302D01*
G01Y1674878D01*
G02X1571882Y1674576I-302J0D01*
G01X1568182D01*
G02X1567880Y1674878I0J302D01*
G01Y1677743D01*
G02X1567911Y1677876I302J0D01*
G01X1568830Y1679751D01*
G03Y1680013I-267J131D01*
G01X1567911Y1681888D01*
G02X1567880Y1682021I271J133D01*
G01Y1684884D01*
G37*
G36*
G01X1583628D02*
G02X1583930Y1685186I302J0D01*
G01X1587630D01*
G02X1587932Y1684884I0J-302D01*
G01Y1674878D01*
G02X1587630Y1674576I-302J0D01*
G01X1583930D01*
G02X1583628Y1674878I0J302D01*
G01Y1677743D01*
G02X1583659Y1677876I302J0D01*
G01X1584578Y1679751D01*
G03Y1680013I-267J131D01*
G01X1583659Y1681888D01*
G02X1583628Y1682021I271J133D01*
G01Y1684884D01*
G37*
G36*
G01X1599376D02*
G02X1599678Y1685186I302J0D01*
G01X1603378D01*
G02X1603680Y1684884I0J-302D01*
G01Y1674878D01*
G02X1603378Y1674576I-302J0D01*
G01X1599678D01*
G02X1599376Y1674878I0J302D01*
G01Y1677743D01*
G02X1599407Y1677876I302J0D01*
G01X1600326Y1679751D01*
G03Y1680013I-267J131D01*
G01X1599407Y1681888D01*
G02X1599376Y1682021I271J133D01*
G01Y1684884D01*
G37*
G36*
G01X1615124D02*
G02X1615426Y1685186I302J0D01*
G01X1619126D01*
G02X1619428Y1684884I0J-302D01*
G01Y1674878D01*
G02X1619126Y1674576I-302J0D01*
G01X1615426D01*
G02X1615124Y1674878I0J302D01*
G01Y1677743D01*
G02X1615155Y1677876I302J0D01*
G01X1616074Y1679751D01*
G03Y1680013I-267J131D01*
G01X1615155Y1681888D01*
G02X1615124Y1682021I271J133D01*
G01Y1684884D01*
G37*
G36*
G01X229205Y1685186D02*
X232905D01*
G02X233208Y1684884I1J-302D01*
G01Y1674878D01*
G02X232905Y1674576I-303J1D01*
G01X229205D01*
G02X228902Y1674878I-1J302D01*
G01Y1677742D01*
G02X228934Y1677876I303J-1D01*
G01X229853Y1679751D01*
G03Y1680013I-267J131D01*
G01X228934Y1681888D01*
G02X228902Y1682022I270J135D01*
G01Y1684884D01*
G02X229205Y1685186I303J-1D01*
G37*
G36*
G01X244953D02*
X248653D01*
G02X248956Y1684884I1J-302D01*
G01Y1674878D01*
G02X248653Y1674576I-303J1D01*
G01X244953D01*
G02X244650Y1674878I-1J302D01*
G01Y1677742D01*
G02X244682Y1677876I303J-1D01*
G01X245601Y1679751D01*
G03Y1680013I-267J131D01*
G01X244682Y1681888D01*
G02X244650Y1682022I270J135D01*
G01Y1684884D01*
G02X244953Y1685186I303J-1D01*
G37*
G36*
G01X260701D02*
X264401D01*
G02X264704Y1684884I1J-302D01*
G01Y1674878D01*
G02X264401Y1674576I-303J1D01*
G01X260701D01*
G02X260398Y1674878I-1J302D01*
G01Y1677742D01*
G02X260430Y1677876I303J-1D01*
G01X261349Y1679751D01*
G03Y1680013I-267J131D01*
G01X260430Y1681888D01*
G02X260398Y1682022I270J135D01*
G01Y1684884D01*
G02X260701Y1685186I303J-1D01*
G37*
G36*
G01X276449D02*
X280149D01*
G02X280452Y1684884I1J-302D01*
G01Y1674878D01*
G02X280149Y1674576I-303J1D01*
G01X276449D01*
G02X276146Y1674878I-1J302D01*
G01Y1677742D01*
G02X276178Y1677876I303J-1D01*
G01X277097Y1679751D01*
G03Y1680013I-267J131D01*
G01X276178Y1681888D01*
G02X276146Y1682022I270J135D01*
G01Y1684884D01*
G02X276449Y1685186I303J-1D01*
G37*
G36*
G01X107569Y1684260D02*
G02Y1687266I0J1503D01*
G01X110969D01*
G02Y1684260I0J-1503D01*
G01X107569D01*
G37*
G36*
G01X500950Y1688820D02*
G02X501252Y1689122I302J0D01*
G01X504952D01*
G02X505254Y1688820I0J-302D01*
G01Y1678814D01*
G02X504952Y1678512I-302J0D01*
G01X501252D01*
G02X500950Y1678814I0J302D01*
G01Y1681679D01*
G02X500981Y1681812I302J0D01*
G01X501900Y1683687D01*
G03Y1683949I-267J131D01*
G01X500981Y1685824D01*
G02X500950Y1685957I271J133D01*
G01Y1688820D01*
G37*
G36*
G01X516698D02*
G02X517000Y1689122I302J0D01*
G01X520700D01*
G02X521002Y1688820I0J-302D01*
G01Y1678814D01*
G02X520700Y1678512I-302J0D01*
G01X517000D01*
G02X516698Y1678814I0J302D01*
G01Y1681679D01*
G02X516729Y1681812I302J0D01*
G01X517648Y1683687D01*
G03Y1683949I-267J131D01*
G01X516729Y1685824D01*
G02X516698Y1685957I271J133D01*
G01Y1688820D01*
G37*
G36*
G01X532446D02*
G02X532748Y1689122I302J0D01*
G01X536448D01*
G02X536750Y1688820I0J-302D01*
G01Y1678814D01*
G02X536448Y1678512I-302J0D01*
G01X532748D01*
G02X532446Y1678814I0J302D01*
G01Y1681679D01*
G02X532477Y1681812I302J0D01*
G01X533396Y1683687D01*
G03Y1683949I-267J131D01*
G01X532477Y1685824D01*
G02X532446Y1685957I271J133D01*
G01Y1688820D01*
G37*
G36*
G01X548194D02*
G02X548496Y1689122I302J0D01*
G01X552196D01*
G02X552498Y1688820I0J-302D01*
G01Y1678814D01*
G02X552196Y1678512I-302J0D01*
G01X548496D01*
G02X548194Y1678814I0J302D01*
G01Y1681679D01*
G02X548225Y1681812I302J0D01*
G01X549144Y1683687D01*
G03Y1683949I-267J131D01*
G01X548225Y1685824D01*
G02X548194Y1685957I271J133D01*
G01Y1688820D01*
G37*
G36*
G01X567880D02*
G02X568182Y1689122I302J0D01*
G01X571882D01*
G02X572184Y1688820I0J-302D01*
G01Y1678814D01*
G02X571882Y1678512I-302J0D01*
G01X568182D01*
G02X567880Y1678814I0J302D01*
G01Y1681679D01*
G02X567911Y1681812I302J0D01*
G01X568830Y1683687D01*
G03Y1683949I-267J131D01*
G01X567911Y1685824D01*
G02X567880Y1685957I271J133D01*
G01Y1688820D01*
G37*
G36*
G01X583628D02*
G02X583930Y1689122I302J0D01*
G01X587630D01*
G02X587932Y1688820I0J-302D01*
G01Y1678814D01*
G02X587630Y1678512I-302J0D01*
G01X583930D01*
G02X583628Y1678814I0J302D01*
G01Y1681679D01*
G02X583659Y1681812I302J0D01*
G01X584578Y1683687D01*
G03Y1683949I-267J131D01*
G01X583659Y1685824D01*
G02X583628Y1685957I271J133D01*
G01Y1688820D01*
G37*
G36*
G01X599376D02*
G02X599678Y1689122I302J0D01*
G01X603378D01*
G02X603680Y1688820I0J-302D01*
G01Y1678814D01*
G02X603378Y1678512I-302J0D01*
G01X599678D01*
G02X599376Y1678814I0J302D01*
G01Y1681679D01*
G02X599407Y1681812I302J0D01*
G01X600326Y1683687D01*
G03Y1683949I-267J131D01*
G01X599407Y1685824D01*
G02X599376Y1685957I271J133D01*
G01Y1688820D01*
G37*
G36*
G01X615124D02*
G02X615426Y1689122I302J0D01*
G01X619126D01*
G02X619428Y1688820I0J-302D01*
G01Y1678814D01*
G02X619126Y1678512I-302J0D01*
G01X615426D01*
G02X615124Y1678814I0J302D01*
G01Y1681679D01*
G02X615155Y1681812I302J0D01*
G01X616074Y1683687D01*
G03Y1683949I-267J131D01*
G01X615155Y1685824D01*
G02X615124Y1685957I271J133D01*
G01Y1688820D01*
G37*
G36*
G01X1244650D02*
G02X1244952Y1689122I302J0D01*
G01X1248652D01*
G02X1248954Y1688820I0J-302D01*
G01Y1678814D01*
G02X1248652Y1678512I-302J0D01*
G01X1244952D01*
G02X1244650Y1678814I0J302D01*
G01Y1681679D01*
G02X1244681Y1681812I302J0D01*
G01X1245600Y1683687D01*
G03Y1683949I-267J131D01*
G01X1244681Y1685824D01*
G02X1244650Y1685957I271J133D01*
G01Y1688820D01*
G37*
G36*
G01X1260398D02*
G02X1260700Y1689122I302J0D01*
G01X1264400D01*
G02X1264702Y1688820I0J-302D01*
G01Y1678814D01*
G02X1264400Y1678512I-302J0D01*
G01X1260700D01*
G02X1260398Y1678814I0J302D01*
G01Y1681679D01*
G02X1260429Y1681812I302J0D01*
G01X1261348Y1683687D01*
G03Y1683949I-267J131D01*
G01X1260429Y1685824D01*
G02X1260398Y1685957I271J133D01*
G01Y1688820D01*
G37*
G36*
G01X1276146D02*
G02X1276448Y1689122I302J0D01*
G01X1280148D01*
G02X1280450Y1688820I0J-302D01*
G01Y1678814D01*
G02X1280148Y1678512I-302J0D01*
G01X1276448D01*
G02X1276146Y1678814I0J302D01*
G01Y1681679D01*
G02X1276177Y1681812I302J0D01*
G01X1277096Y1683687D01*
G03Y1683949I-267J131D01*
G01X1276177Y1685824D01*
G02X1276146Y1685957I271J133D01*
G01Y1688820D01*
G37*
G36*
G01X1291894D02*
G02X1292196Y1689122I302J0D01*
G01X1295896D01*
G02X1296198Y1688820I0J-302D01*
G01Y1678814D01*
G02X1295896Y1678512I-302J0D01*
G01X1292196D01*
G02X1291894Y1678814I0J302D01*
G01Y1681679D01*
G02X1291925Y1681812I302J0D01*
G01X1292844Y1683687D01*
G03Y1683949I-267J131D01*
G01X1291925Y1685824D01*
G02X1291894Y1685957I271J133D01*
G01Y1688820D01*
G37*
G36*
G01X1311580D02*
G02X1311882Y1689122I302J0D01*
G01X1315582D01*
G02X1315884Y1688820I0J-302D01*
G01Y1678814D01*
G02X1315582Y1678512I-302J0D01*
G01X1311882D01*
G02X1311580Y1678814I0J302D01*
G01Y1681679D01*
G02X1311611Y1681812I302J0D01*
G01X1312530Y1683687D01*
G03Y1683949I-267J131D01*
G01X1311611Y1685824D01*
G02X1311580Y1685957I271J133D01*
G01Y1688820D01*
G37*
G36*
G01X1327328D02*
G02X1327630Y1689122I302J0D01*
G01X1331330D01*
G02X1331632Y1688820I0J-302D01*
G01Y1678814D01*
G02X1331330Y1678512I-302J0D01*
G01X1327630D01*
G02X1327328Y1678814I0J302D01*
G01Y1681679D01*
G02X1327359Y1681812I302J0D01*
G01X1328278Y1683687D01*
G03Y1683949I-267J131D01*
G01X1327359Y1685824D01*
G02X1327328Y1685957I271J133D01*
G01Y1688820D01*
G37*
G36*
G01X1343076D02*
G02X1343378Y1689122I302J0D01*
G01X1347078D01*
G02X1347380Y1688820I0J-302D01*
G01Y1678814D01*
G02X1347078Y1678512I-302J0D01*
G01X1343378D01*
G02X1343076Y1678814I0J302D01*
G01Y1681679D01*
G02X1343107Y1681812I302J0D01*
G01X1344026Y1683687D01*
G03Y1683949I-267J131D01*
G01X1343107Y1685824D01*
G02X1343076Y1685957I271J133D01*
G01Y1688820D01*
G37*
G36*
G01X1358824D02*
G02X1359126Y1689122I302J0D01*
G01X1362826D01*
G02X1363128Y1688820I0J-302D01*
G01Y1678814D01*
G02X1362826Y1678512I-302J0D01*
G01X1359126D01*
G02X1358824Y1678814I0J302D01*
G01Y1681679D01*
G02X1358855Y1681812I302J0D01*
G01X1359774Y1683687D01*
G03Y1683949I-267J131D01*
G01X1358855Y1685824D01*
G02X1358824Y1685957I271J133D01*
G01Y1688820D01*
G37*
G36*
G01X1508824D02*
G02X1509126Y1689122I302J0D01*
G01X1512826D01*
G02X1513128Y1688820I0J-302D01*
G01Y1678814D01*
G02X1512826Y1678512I-302J0D01*
G01X1509126D01*
G02X1508824Y1678814I0J302D01*
G01Y1681679D01*
G02X1508855Y1681812I302J0D01*
G01X1509774Y1683687D01*
G03Y1683949I-267J131D01*
G01X1508855Y1685824D01*
G02X1508824Y1685957I271J133D01*
G01Y1688820D01*
G37*
G36*
G01X1524572D02*
G02X1524874Y1689122I302J0D01*
G01X1528574D01*
G02X1528876Y1688820I0J-302D01*
G01Y1678814D01*
G02X1528574Y1678512I-302J0D01*
G01X1524874D01*
G02X1524572Y1678814I0J302D01*
G01Y1681679D01*
G02X1524603Y1681812I302J0D01*
G01X1525522Y1683687D01*
G03Y1683949I-267J131D01*
G01X1524603Y1685824D01*
G02X1524572Y1685957I271J133D01*
G01Y1688820D01*
G37*
G36*
G01X1540320D02*
G02X1540622Y1689122I302J0D01*
G01X1544322D01*
G02X1544624Y1688820I0J-302D01*
G01Y1678814D01*
G02X1544322Y1678512I-302J0D01*
G01X1540622D01*
G02X1540320Y1678814I0J302D01*
G01Y1681679D01*
G02X1540351Y1681812I302J0D01*
G01X1541270Y1683687D01*
G03Y1683949I-267J131D01*
G01X1540351Y1685824D01*
G02X1540320Y1685957I271J133D01*
G01Y1688820D01*
G37*
G36*
G01X1556068D02*
G02X1556370Y1689122I302J0D01*
G01X1560070D01*
G02X1560372Y1688820I0J-302D01*
G01Y1678814D01*
G02X1560070Y1678512I-302J0D01*
G01X1556370D01*
G02X1556068Y1678814I0J302D01*
G01Y1681679D01*
G02X1556099Y1681812I302J0D01*
G01X1557018Y1683687D01*
G03Y1683949I-267J131D01*
G01X1556099Y1685824D01*
G02X1556068Y1685957I271J133D01*
G01Y1688820D01*
G37*
G36*
G01X1575754D02*
G02X1576056Y1689122I302J0D01*
G01X1579756D01*
G02X1580058Y1688820I0J-302D01*
G01Y1678814D01*
G02X1579756Y1678512I-302J0D01*
G01X1576056D01*
G02X1575754Y1678814I0J302D01*
G01Y1681679D01*
G02X1575785Y1681812I302J0D01*
G01X1576704Y1683687D01*
G03Y1683949I-267J131D01*
G01X1575785Y1685824D01*
G02X1575754Y1685957I271J133D01*
G01Y1688820D01*
G37*
G36*
G01X1591502D02*
G02X1591804Y1689122I302J0D01*
G01X1595504D01*
G02X1595806Y1688820I0J-302D01*
G01Y1678814D01*
G02X1595504Y1678512I-302J0D01*
G01X1591804D01*
G02X1591502Y1678814I0J302D01*
G01Y1681679D01*
G02X1591533Y1681812I302J0D01*
G01X1592452Y1683687D01*
G03Y1683949I-267J131D01*
G01X1591533Y1685824D01*
G02X1591502Y1685957I271J133D01*
G01Y1688820D01*
G37*
G36*
G01X1607250D02*
G02X1607552Y1689122I302J0D01*
G01X1611252D01*
G02X1611554Y1688820I0J-302D01*
G01Y1678814D01*
G02X1611252Y1678512I-302J0D01*
G01X1607552D01*
G02X1607250Y1678814I0J302D01*
G01Y1681679D01*
G02X1607281Y1681812I302J0D01*
G01X1608200Y1683687D01*
G03Y1683949I-267J131D01*
G01X1607281Y1685824D01*
G02X1607250Y1685957I271J133D01*
G01Y1688820D01*
G37*
G36*
G01X1622998D02*
G02X1623300Y1689122I302J0D01*
G01X1627000D01*
G02X1627302Y1688820I0J-302D01*
G01Y1678814D01*
G02X1627000Y1678512I-302J0D01*
G01X1623300D01*
G02X1622998Y1678814I0J302D01*
G01Y1681679D01*
G02X1623029Y1681812I302J0D01*
G01X1623948Y1683687D01*
G03Y1683949I-267J131D01*
G01X1623029Y1685824D01*
G02X1622998Y1685957I271J133D01*
G01Y1688820D01*
G37*
G36*
G01X236776Y1688821D02*
G02X237079Y1689124I303J0D01*
G01X240779D01*
G02X241082Y1688821I0J-303D01*
G01Y1678815D01*
G02X240779Y1678512I-303J0D01*
G01X237079D01*
G02X236776Y1678815I0J303D01*
G01Y1681679D01*
G02X236808Y1681813I303J-1D01*
G01X237727Y1683688D01*
G03Y1683950I-267J131D01*
G01X236808Y1685825D01*
G02X236776Y1685959I270J135D01*
G01Y1688821D01*
G37*
G36*
G01X252524D02*
G02X252827Y1689124I303J0D01*
G01X256527D01*
G02X256830Y1688821I0J-303D01*
G01Y1678815D01*
G02X256527Y1678512I-303J0D01*
G01X252827D01*
G02X252524Y1678815I0J303D01*
G01Y1681679D01*
G02X252556Y1681813I303J-1D01*
G01X253475Y1683688D01*
G03Y1683950I-267J131D01*
G01X252556Y1685825D01*
G02X252524Y1685959I270J135D01*
G01Y1688821D01*
G37*
G36*
G01X268272D02*
G02X268575Y1689124I303J0D01*
G01X272275D01*
G02X272578Y1688821I0J-303D01*
G01Y1678815D01*
G02X272275Y1678512I-303J0D01*
G01X268575D01*
G02X268272Y1678815I0J303D01*
G01Y1681679D01*
G02X268304Y1681813I303J-1D01*
G01X269223Y1683688D01*
G03Y1683950I-267J131D01*
G01X268304Y1685825D01*
G02X268272Y1685959I270J135D01*
G01Y1688821D01*
G37*
G36*
G01X284020D02*
G02X284323Y1689124I303J0D01*
G01X288023D01*
G02X288326Y1688821I0J-303D01*
G01Y1678815D01*
G02X288023Y1678512I-303J0D01*
G01X284323D01*
G02X284020Y1678815I0J303D01*
G01Y1681679D01*
G02X284052Y1681813I303J-1D01*
G01X284971Y1683688D01*
G03Y1683950I-267J131D01*
G01X284052Y1685825D01*
G02X284020Y1685959I270J135D01*
G01Y1688821D01*
G37*
G36*
G01X303706D02*
G02X304008Y1689124I302J1D01*
G01X307708D01*
G02X308010Y1688821I-1J-303D01*
G01Y1678815D01*
G02X307708Y1678512I-302J-1D01*
G01X304008D01*
G02X303706Y1678815I1J303D01*
G01Y1681680D01*
G02X303737Y1681813I302J0D01*
G01X304656Y1683688D01*
G03Y1683950I-267J131D01*
G01X303737Y1685825D01*
G02X303706Y1685958I271J133D01*
G01Y1688821D01*
G37*
G36*
G01X319454D02*
G02X319756Y1689124I302J1D01*
G01X323456D01*
G02X323758Y1688821I-1J-303D01*
G01Y1678815D01*
G02X323456Y1678512I-302J-1D01*
G01X319756D01*
G02X319454Y1678815I1J303D01*
G01Y1681680D01*
G02X319485Y1681813I302J0D01*
G01X320404Y1683688D01*
G03Y1683950I-267J131D01*
G01X319485Y1685825D01*
G02X319454Y1685958I271J133D01*
G01Y1688821D01*
G37*
G36*
G01X335202D02*
G02X335504Y1689124I302J1D01*
G01X339204D01*
G02X339506Y1688821I-1J-303D01*
G01Y1678815D01*
G02X339204Y1678512I-302J-1D01*
G01X335504D01*
G02X335202Y1678815I1J303D01*
G01Y1681680D01*
G02X335233Y1681813I302J0D01*
G01X336152Y1683688D01*
G03Y1683950I-267J131D01*
G01X335233Y1685825D01*
G02X335202Y1685958I271J133D01*
G01Y1688821D01*
G37*
G36*
G01X350950D02*
G02X351252Y1689124I302J1D01*
G01X354952D01*
G02X355254Y1688821I-1J-303D01*
G01Y1678815D01*
G02X354952Y1678512I-302J-1D01*
G01X351252D01*
G02X350950Y1678815I1J303D01*
G01Y1681680D01*
G02X350981Y1681813I302J0D01*
G01X351900Y1683688D01*
G03Y1683950I-267J131D01*
G01X350981Y1685825D01*
G02X350950Y1685958I271J133D01*
G01Y1688821D01*
G37*
G36*
G01X228902Y1699057D02*
G02X229205Y1699360I303J0D01*
G01X232905D01*
G02X233208Y1699057I0J-303D01*
G01Y1689051D01*
G02X232905Y1688748I-303J0D01*
G01X229205D01*
G02X228902Y1689051I0J303D01*
G01Y1699057D01*
G37*
G36*
G01X244650D02*
G02X244953Y1699360I303J0D01*
G01X248653D01*
G02X248956Y1699057I0J-303D01*
G01Y1689051D01*
G02X248653Y1688748I-303J0D01*
G01X244953D01*
G02X244650Y1689051I0J303D01*
G01Y1699057D01*
G37*
G36*
G01X260398D02*
G02X260701Y1699360I303J0D01*
G01X264401D01*
G02X264704Y1699057I0J-303D01*
G01Y1689051D01*
G02X264401Y1688748I-303J0D01*
G01X260701D01*
G02X260398Y1689051I0J303D01*
G01Y1699057D01*
G37*
G36*
G01X276146D02*
G02X276449Y1699360I303J0D01*
G01X280149D01*
G02X280452Y1699057I0J-303D01*
G01Y1689051D01*
G02X280149Y1688748I-303J0D01*
G01X276449D01*
G02X276146Y1689051I0J303D01*
G01Y1699057D01*
G37*
G36*
G01X295832D02*
G02X296134Y1699360I302J1D01*
G01X299834D01*
G02X300136Y1699057I-1J-303D01*
G01Y1689051D01*
G02X299834Y1688748I-302J-1D01*
G01X296134D01*
G02X295832Y1689051I1J303D01*
G01Y1699057D01*
G37*
G36*
G01X311580D02*
G02X311882Y1699360I302J1D01*
G01X315582D01*
G02X315884Y1699057I-1J-303D01*
G01Y1689051D01*
G02X315582Y1688748I-302J-1D01*
G01X311882D01*
G02X311580Y1689051I1J303D01*
G01Y1699057D01*
G37*
G36*
G01X327328D02*
G02X327630Y1699360I302J1D01*
G01X331330D01*
G02X331632Y1699057I-1J-303D01*
G01Y1689051D01*
G02X331330Y1688748I-302J-1D01*
G01X327630D01*
G02X327328Y1689051I1J303D01*
G01Y1699057D01*
G37*
G36*
G01X343076D02*
G02X343378Y1699360I302J1D01*
G01X347078D01*
G02X347380Y1699057I-1J-303D01*
G01Y1689051D01*
G02X347078Y1688748I-302J-1D01*
G01X343378D01*
G02X343076Y1689051I1J303D01*
G01Y1699057D01*
G37*
G36*
G01X493076D02*
G02X493378Y1699360I302J1D01*
G01X497078D01*
G02X497380Y1699057I-1J-303D01*
G01Y1689051D01*
G02X497078Y1688748I-302J-1D01*
G01X493378D01*
G02X493076Y1689051I1J303D01*
G01Y1699057D01*
G37*
G36*
G01X508824D02*
G02X509126Y1699360I302J1D01*
G01X512826D01*
G02X513128Y1699057I-1J-303D01*
G01Y1689051D01*
G02X512826Y1688748I-302J-1D01*
G01X509126D01*
G02X508824Y1689051I1J303D01*
G01Y1699057D01*
G37*
G36*
G01X524572D02*
G02X524874Y1699360I302J1D01*
G01X528574D01*
G02X528876Y1699057I-1J-303D01*
G01Y1689051D01*
G02X528574Y1688748I-302J-1D01*
G01X524874D01*
G02X524572Y1689051I1J303D01*
G01Y1699057D01*
G37*
G36*
G01X540320D02*
G02X540622Y1699360I302J1D01*
G01X544322D01*
G02X544624Y1699057I-1J-303D01*
G01Y1689051D01*
G02X544322Y1688748I-302J-1D01*
G01X540622D01*
G02X540320Y1689051I1J303D01*
G01Y1699057D01*
G37*
G36*
G01X560006D02*
G02X560308Y1699360I302J1D01*
G01X564008D01*
G02X564310Y1699057I-1J-303D01*
G01Y1689051D01*
G02X564008Y1688748I-302J-1D01*
G01X560308D01*
G02X560006Y1689051I1J303D01*
G01Y1699057D01*
G37*
G36*
G01X575754D02*
G02X576056Y1699360I302J1D01*
G01X579756D01*
G02X580058Y1699057I-1J-303D01*
G01Y1689051D01*
G02X579756Y1688748I-302J-1D01*
G01X576056D01*
G02X575754Y1689051I1J303D01*
G01Y1699057D01*
G37*
G36*
G01X591502D02*
G02X591804Y1699360I302J1D01*
G01X595504D01*
G02X595806Y1699057I-1J-303D01*
G01Y1689051D01*
G02X595504Y1688748I-302J-1D01*
G01X591804D01*
G02X591502Y1689051I1J303D01*
G01Y1699057D01*
G37*
G36*
G01X607250D02*
G02X607552Y1699360I302J1D01*
G01X611252D01*
G02X611554Y1699057I-1J-303D01*
G01Y1689051D01*
G02X611252Y1688748I-302J-1D01*
G01X607552D01*
G02X607250Y1689051I1J303D01*
G01Y1699057D01*
G37*
G36*
G01X1236776D02*
G02X1237079Y1699360I303J0D01*
G01X1240779D01*
G02X1241082Y1699057I0J-303D01*
G01Y1689051D01*
G02X1240779Y1688748I-303J0D01*
G01X1237079D01*
G02X1236776Y1689051I0J303D01*
G01Y1699057D01*
G37*
G36*
G01X1252524D02*
G02X1252827Y1699360I303J0D01*
G01X1256527D01*
G02X1256830Y1699057I0J-303D01*
G01Y1689051D01*
G02X1256527Y1688748I-303J0D01*
G01X1252827D01*
G02X1252524Y1689051I0J303D01*
G01Y1699057D01*
G37*
G36*
G01X1268272D02*
G02X1268575Y1699360I303J0D01*
G01X1272275D01*
G02X1272578Y1699057I0J-303D01*
G01Y1689051D01*
G02X1272275Y1688748I-303J0D01*
G01X1268575D01*
G02X1268272Y1689051I0J303D01*
G01Y1699057D01*
G37*
G36*
G01X1284020D02*
G02X1284323Y1699360I303J0D01*
G01X1288023D01*
G02X1288326Y1699057I0J-303D01*
G01Y1689051D01*
G02X1288023Y1688748I-303J0D01*
G01X1284323D01*
G02X1284020Y1689051I0J303D01*
G01Y1699057D01*
G37*
G36*
G01X1303706D02*
G02X1304009Y1699360I303J0D01*
G01X1307709D01*
G02X1308012Y1699057I0J-303D01*
G01Y1689051D01*
G02X1307709Y1688748I-303J0D01*
G01X1304009D01*
G02X1303706Y1689051I0J303D01*
G01Y1699057D01*
G37*
G36*
G01X1319454D02*
G02X1319757Y1699360I303J0D01*
G01X1323457D01*
G02X1323760Y1699057I0J-303D01*
G01Y1689051D01*
G02X1323457Y1688748I-303J0D01*
G01X1319757D01*
G02X1319454Y1689051I0J303D01*
G01Y1699057D01*
G37*
G36*
G01X1335202D02*
G02X1335505Y1699360I303J0D01*
G01X1339205D01*
G02X1339508Y1699057I0J-303D01*
G01Y1689051D01*
G02X1339205Y1688748I-303J0D01*
G01X1335505D01*
G02X1335202Y1689051I0J303D01*
G01Y1699057D01*
G37*
G36*
G01X1350950D02*
G02X1351253Y1699360I303J0D01*
G01X1354953D01*
G02X1355256Y1699057I0J-303D01*
G01Y1689051D01*
G02X1354953Y1688748I-303J0D01*
G01X1351253D01*
G02X1350950Y1689051I0J303D01*
G01Y1699057D01*
G37*
G36*
G01X1500950D02*
G02X1501253Y1699360I303J0D01*
G01X1504953D01*
G02X1505256Y1699057I0J-303D01*
G01Y1689051D01*
G02X1504953Y1688748I-303J0D01*
G01X1501253D01*
G02X1500950Y1689051I0J303D01*
G01Y1699057D01*
G37*
G36*
G01X1516698D02*
G02X1517001Y1699360I303J0D01*
G01X1520701D01*
G02X1521004Y1699057I0J-303D01*
G01Y1689051D01*
G02X1520701Y1688748I-303J0D01*
G01X1517001D01*
G02X1516698Y1689051I0J303D01*
G01Y1699057D01*
G37*
G36*
G01X1532446D02*
G02X1532749Y1699360I303J0D01*
G01X1536449D01*
G02X1536752Y1699057I0J-303D01*
G01Y1689051D01*
G02X1536449Y1688748I-303J0D01*
G01X1532749D01*
G02X1532446Y1689051I0J303D01*
G01Y1699057D01*
G37*
G36*
G01X1548194D02*
G02X1548497Y1699360I303J0D01*
G01X1552197D01*
G02X1552500Y1699057I0J-303D01*
G01Y1689051D01*
G02X1552197Y1688748I-303J0D01*
G01X1548497D01*
G02X1548194Y1689051I0J303D01*
G01Y1699057D01*
G37*
G36*
G01X1567880D02*
G02X1568183Y1699360I303J0D01*
G01X1571883D01*
G02X1572186Y1699057I0J-303D01*
G01Y1689051D01*
G02X1571883Y1688748I-303J0D01*
G01X1568183D01*
G02X1567880Y1689051I0J303D01*
G01Y1699057D01*
G37*
G36*
G01X1583628D02*
G02X1583931Y1699360I303J0D01*
G01X1587631D01*
G02X1587934Y1699057I0J-303D01*
G01Y1689051D01*
G02X1587631Y1688748I-303J0D01*
G01X1583931D01*
G02X1583628Y1689051I0J303D01*
G01Y1699057D01*
G37*
G36*
G01X1599376D02*
G02X1599679Y1699360I303J0D01*
G01X1603379D01*
G02X1603682Y1699057I0J-303D01*
G01Y1689051D01*
G02X1603379Y1688748I-303J0D01*
G01X1599679D01*
G02X1599376Y1689051I0J303D01*
G01Y1699057D01*
G37*
G36*
G01X1615124D02*
G02X1615427Y1699360I303J0D01*
G01X1619127D01*
G02X1619430Y1699057I0J-303D01*
G01Y1689051D01*
G02X1619127Y1688748I-303J0D01*
G01X1615427D01*
G02X1615124Y1689051I0J303D01*
G01Y1699057D01*
G37*
G36*
G01X303706Y1702994D02*
G02X304008Y1703296I302J0D01*
G01X307708D01*
G02X308010Y1702994I0J-302D01*
G01Y1692988D01*
G02X307708Y1692686I-302J0D01*
G01X304008D01*
G02X303706Y1692988I0J302D01*
G01Y1702994D01*
G37*
G36*
G01X319454D02*
G02X319756Y1703296I302J0D01*
G01X323456D01*
G02X323758Y1702994I0J-302D01*
G01Y1692988D01*
G02X323456Y1692686I-302J0D01*
G01X319756D01*
G02X319454Y1692988I0J302D01*
G01Y1702994D01*
G37*
G36*
G01X335202D02*
G02X335504Y1703296I302J0D01*
G01X339204D01*
G02X339506Y1702994I0J-302D01*
G01Y1692988D01*
G02X339204Y1692686I-302J0D01*
G01X335504D01*
G02X335202Y1692988I0J302D01*
G01Y1702994D01*
G37*
G36*
G01X350950D02*
G02X351252Y1703296I302J0D01*
G01X354952D01*
G02X355254Y1702994I0J-302D01*
G01Y1692988D01*
G02X354952Y1692686I-302J0D01*
G01X351252D01*
G02X350950Y1692988I0J302D01*
G01Y1702994D01*
G37*
G36*
G01X500950D02*
G02X501252Y1703296I302J0D01*
G01X504952D01*
G02X505254Y1702994I0J-302D01*
G01Y1692988D01*
G02X504952Y1692686I-302J0D01*
G01X501252D01*
G02X500950Y1692988I0J302D01*
G01Y1702994D01*
G37*
G36*
G01X516698D02*
G02X517000Y1703296I302J0D01*
G01X520700D01*
G02X521002Y1702994I0J-302D01*
G01Y1692988D01*
G02X520700Y1692686I-302J0D01*
G01X517000D01*
G02X516698Y1692988I0J302D01*
G01Y1702994D01*
G37*
G36*
G01X532446D02*
G02X532748Y1703296I302J0D01*
G01X536448D01*
G02X536750Y1702994I0J-302D01*
G01Y1692988D01*
G02X536448Y1692686I-302J0D01*
G01X532748D01*
G02X532446Y1692988I0J302D01*
G01Y1702994D01*
G37*
G36*
G01X548194D02*
G02X548496Y1703296I302J0D01*
G01X552196D01*
G02X552498Y1702994I0J-302D01*
G01Y1692988D01*
G02X552196Y1692686I-302J0D01*
G01X548496D01*
G02X548194Y1692988I0J302D01*
G01Y1702994D01*
G37*
G36*
G01X567880D02*
G02X568182Y1703296I302J0D01*
G01X571882D01*
G02X572184Y1702994I0J-302D01*
G01Y1692988D01*
G02X571882Y1692686I-302J0D01*
G01X568182D01*
G02X567880Y1692988I0J302D01*
G01Y1702994D01*
G37*
G36*
G01X583628D02*
G02X583930Y1703296I302J0D01*
G01X587630D01*
G02X587932Y1702994I0J-302D01*
G01Y1692988D01*
G02X587630Y1692686I-302J0D01*
G01X583930D01*
G02X583628Y1692988I0J302D01*
G01Y1702994D01*
G37*
G36*
G01X599376D02*
G02X599678Y1703296I302J0D01*
G01X603378D01*
G02X603680Y1702994I0J-302D01*
G01Y1692988D01*
G02X603378Y1692686I-302J0D01*
G01X599678D01*
G02X599376Y1692988I0J302D01*
G01Y1702994D01*
G37*
G36*
G01X615124D02*
G02X615426Y1703296I302J0D01*
G01X619126D01*
G02X619428Y1702994I0J-302D01*
G01Y1692988D01*
G02X619126Y1692686I-302J0D01*
G01X615426D01*
G02X615124Y1692988I0J302D01*
G01Y1702994D01*
G37*
G36*
G01X237079Y1703296D02*
X240779D01*
G02X241082Y1702994I1J-302D01*
G01Y1692988D01*
G02X240779Y1692686I-303J1D01*
G01X237079D01*
G02X236776Y1692988I-1J302D01*
G01Y1702994D01*
G02X237079Y1703296I303J-1D01*
G37*
G36*
G01X252827D02*
X256527D01*
G02X256830Y1702994I1J-302D01*
G01Y1692988D01*
G02X256527Y1692686I-303J1D01*
G01X252827D01*
G02X252524Y1692988I-1J302D01*
G01Y1702994D01*
G02X252827Y1703296I303J-1D01*
G37*
G36*
G01X268575D02*
X272275D01*
G02X272578Y1702994I1J-302D01*
G01Y1692988D01*
G02X272275Y1692686I-303J1D01*
G01X268575D01*
G02X268272Y1692988I-1J302D01*
G01Y1702994D01*
G02X268575Y1703296I303J-1D01*
G37*
G36*
G01X284323D02*
X288023D01*
G02X288326Y1702994I1J-302D01*
G01Y1692988D01*
G02X288023Y1692686I-303J1D01*
G01X284323D01*
G02X284020Y1692988I-1J302D01*
G01Y1702994D01*
G02X284323Y1703296I303J-1D01*
G37*
G36*
G01X1244953D02*
X1248653D01*
G02X1248956Y1702994I1J-302D01*
G01Y1692988D01*
G02X1248653Y1692686I-303J1D01*
G01X1244953D01*
G02X1244650Y1692988I-1J302D01*
G01Y1702994D01*
G02X1244953Y1703296I303J-1D01*
G37*
G36*
G01X1260701D02*
X1264401D01*
G02X1264704Y1702994I1J-302D01*
G01Y1692988D01*
G02X1264401Y1692686I-303J1D01*
G01X1260701D01*
G02X1260398Y1692988I-1J302D01*
G01Y1702994D01*
G02X1260701Y1703296I303J-1D01*
G37*
G36*
G01X1276449D02*
X1280149D01*
G02X1280452Y1702994I1J-302D01*
G01Y1692988D01*
G02X1280149Y1692686I-303J1D01*
G01X1276449D01*
G02X1276146Y1692988I-1J302D01*
G01Y1702994D01*
G02X1276449Y1703296I303J-1D01*
G37*
G36*
G01X1292197D02*
X1295897D01*
G02X1296200Y1702994I1J-302D01*
G01Y1692988D01*
G02X1295897Y1692686I-303J1D01*
G01X1292197D01*
G02X1291894Y1692988I-1J302D01*
G01Y1702994D01*
G02X1292197Y1703296I303J-1D01*
G37*
G36*
G01X1311883D02*
X1315583D01*
G02X1315886Y1702994I1J-302D01*
G01Y1692988D01*
G02X1315583Y1692686I-303J1D01*
G01X1311883D01*
G02X1311580Y1692988I-1J302D01*
G01Y1702994D01*
G02X1311883Y1703296I303J-1D01*
G37*
G36*
G01X1327631D02*
X1331331D01*
G02X1331634Y1702994I1J-302D01*
G01Y1692988D01*
G02X1331331Y1692686I-303J1D01*
G01X1327631D01*
G02X1327328Y1692988I-1J302D01*
G01Y1702994D01*
G02X1327631Y1703296I303J-1D01*
G37*
G36*
G01X1343379D02*
X1347079D01*
G02X1347382Y1702994I1J-302D01*
G01Y1692988D01*
G02X1347079Y1692686I-303J1D01*
G01X1343379D01*
G02X1343076Y1692988I-1J302D01*
G01Y1702994D01*
G02X1343379Y1703296I303J-1D01*
G37*
G36*
G01X1359127D02*
X1362827D01*
G02X1363130Y1702994I1J-302D01*
G01Y1692988D01*
G02X1362827Y1692686I-303J1D01*
G01X1359127D01*
G02X1358824Y1692988I-1J302D01*
G01Y1702994D01*
G02X1359127Y1703296I303J-1D01*
G37*
G36*
G01X1509127D02*
X1512827D01*
G02X1513130Y1702994I1J-302D01*
G01Y1692988D01*
G02X1512827Y1692686I-303J1D01*
G01X1509127D01*
G02X1508824Y1692988I-1J302D01*
G01Y1702994D01*
G02X1509127Y1703296I303J-1D01*
G37*
G36*
G01X1524875D02*
X1528575D01*
G02X1528878Y1702994I1J-302D01*
G01Y1692988D01*
G02X1528575Y1692686I-303J1D01*
G01X1524875D01*
G02X1524572Y1692988I-1J302D01*
G01Y1702994D01*
G02X1524875Y1703296I303J-1D01*
G37*
G36*
G01X1540623D02*
X1544323D01*
G02X1544626Y1702994I1J-302D01*
G01Y1692988D01*
G02X1544323Y1692686I-303J1D01*
G01X1540623D01*
G02X1540320Y1692988I-1J302D01*
G01Y1702994D01*
G02X1540623Y1703296I303J-1D01*
G37*
G36*
G01X1556371D02*
X1560071D01*
G02X1560374Y1702994I1J-302D01*
G01Y1692988D01*
G02X1560071Y1692686I-303J1D01*
G01X1556371D01*
G02X1556068Y1692988I-1J302D01*
G01Y1702994D01*
G02X1556371Y1703296I303J-1D01*
G37*
G36*
G01X1576057D02*
X1579757D01*
G02X1580060Y1702994I1J-302D01*
G01Y1692988D01*
G02X1579757Y1692686I-303J1D01*
G01X1576057D01*
G02X1575754Y1692988I-1J302D01*
G01Y1702994D01*
G02X1576057Y1703296I303J-1D01*
G37*
G36*
G01X1591805D02*
X1595505D01*
G02X1595808Y1702994I1J-302D01*
G01Y1692988D01*
G02X1595505Y1692686I-303J1D01*
G01X1591805D01*
G02X1591502Y1692988I-1J302D01*
G01Y1702994D01*
G02X1591805Y1703296I303J-1D01*
G37*
G36*
G01X1607553D02*
X1611253D01*
G02X1611556Y1702994I1J-302D01*
G01Y1692988D01*
G02X1611253Y1692686I-303J1D01*
G01X1607553D01*
G02X1607250Y1692988I-1J302D01*
G01Y1702994D01*
G02X1607553Y1703296I303J-1D01*
G37*
G36*
G01X1623301D02*
X1627001D01*
G02X1627304Y1702994I1J-302D01*
G01Y1692988D01*
G02X1627001Y1692686I-303J1D01*
G01X1623301D01*
G02X1622998Y1692988I-1J302D01*
G01Y1702994D01*
G02X1623301Y1703296I303J-1D01*
G37*
G36*
G01X295832Y1713230D02*
G02X296134Y1713532I302J0D01*
G01X299834D01*
G02X300136Y1713230I0J-302D01*
G01Y1703224D01*
G02X299834Y1702922I-302J0D01*
G01X296134D01*
G02X295832Y1703224I0J302D01*
G01Y1713230D01*
G37*
G36*
G01X311580D02*
G02X311882Y1713532I302J0D01*
G01X315582D01*
G02X315884Y1713230I0J-302D01*
G01Y1703224D01*
G02X315582Y1702922I-302J0D01*
G01X311882D01*
G02X311580Y1703224I0J302D01*
G01Y1713230D01*
G37*
G36*
G01X327328D02*
G02X327630Y1713532I302J0D01*
G01X331330D01*
G02X331632Y1713230I0J-302D01*
G01Y1703224D01*
G02X331330Y1702922I-302J0D01*
G01X327630D01*
G02X327328Y1703224I0J302D01*
G01Y1713230D01*
G37*
G36*
G01X343076D02*
G02X343378Y1713532I302J0D01*
G01X347078D01*
G02X347380Y1713230I0J-302D01*
G01Y1703224D01*
G02X347078Y1702922I-302J0D01*
G01X343378D01*
G02X343076Y1703224I0J302D01*
G01Y1713230D01*
G37*
G36*
G01X493076D02*
G02X493378Y1713532I302J0D01*
G01X497078D01*
G02X497380Y1713230I0J-302D01*
G01Y1703224D01*
G02X497078Y1702922I-302J0D01*
G01X493378D01*
G02X493076Y1703224I0J302D01*
G01Y1713230D01*
G37*
G36*
G01X508824D02*
G02X509126Y1713532I302J0D01*
G01X512826D01*
G02X513128Y1713230I0J-302D01*
G01Y1703224D01*
G02X512826Y1702922I-302J0D01*
G01X509126D01*
G02X508824Y1703224I0J302D01*
G01Y1713230D01*
G37*
G36*
G01X524572D02*
G02X524874Y1713532I302J0D01*
G01X528574D01*
G02X528876Y1713230I0J-302D01*
G01Y1703224D01*
G02X528574Y1702922I-302J0D01*
G01X524874D01*
G02X524572Y1703224I0J302D01*
G01Y1713230D01*
G37*
G36*
G01X540320D02*
G02X540622Y1713532I302J0D01*
G01X544322D01*
G02X544624Y1713230I0J-302D01*
G01Y1703224D01*
G02X544322Y1702922I-302J0D01*
G01X540622D01*
G02X540320Y1703224I0J302D01*
G01Y1713230D01*
G37*
G36*
G01X1303706D02*
G02X1304008Y1713532I302J0D01*
G01X1307708D01*
G02X1308010Y1713230I0J-302D01*
G01Y1703224D01*
G02X1307708Y1702922I-302J0D01*
G01X1304008D01*
G02X1303706Y1703224I0J302D01*
G01Y1713230D01*
G37*
G36*
G01X1319454D02*
G02X1319756Y1713532I302J0D01*
G01X1323456D01*
G02X1323758Y1713230I0J-302D01*
G01Y1703224D01*
G02X1323456Y1702922I-302J0D01*
G01X1319756D01*
G02X1319454Y1703224I0J302D01*
G01Y1713230D01*
G37*
G36*
G01X1335202D02*
G02X1335504Y1713532I302J0D01*
G01X1339204D01*
G02X1339506Y1713230I0J-302D01*
G01Y1703224D01*
G02X1339204Y1702922I-302J0D01*
G01X1335504D01*
G02X1335202Y1703224I0J302D01*
G01Y1713230D01*
G37*
G36*
G01X1350950D02*
G02X1351252Y1713532I302J0D01*
G01X1354952D01*
G02X1355254Y1713230I0J-302D01*
G01Y1703224D01*
G02X1354952Y1702922I-302J0D01*
G01X1351252D01*
G02X1350950Y1703224I0J302D01*
G01Y1713230D01*
G37*
G36*
G01X1500950D02*
G02X1501252Y1713532I302J0D01*
G01X1504952D01*
G02X1505254Y1713230I0J-302D01*
G01Y1703224D01*
G02X1504952Y1702922I-302J0D01*
G01X1501252D01*
G02X1500950Y1703224I0J302D01*
G01Y1713230D01*
G37*
G36*
G01X1516698D02*
G02X1517000Y1713532I302J0D01*
G01X1520700D01*
G02X1521002Y1713230I0J-302D01*
G01Y1703224D01*
G02X1520700Y1702922I-302J0D01*
G01X1517000D01*
G02X1516698Y1703224I0J302D01*
G01Y1713230D01*
G37*
G36*
G01X1532446D02*
G02X1532748Y1713532I302J0D01*
G01X1536448D01*
G02X1536750Y1713230I0J-302D01*
G01Y1703224D01*
G02X1536448Y1702922I-302J0D01*
G01X1532748D01*
G02X1532446Y1703224I0J302D01*
G01Y1713230D01*
G37*
G36*
G01X1548194D02*
G02X1548496Y1713532I302J0D01*
G01X1552196D01*
G02X1552498Y1713230I0J-302D01*
G01Y1703224D01*
G02X1552196Y1702922I-302J0D01*
G01X1548496D01*
G02X1548194Y1703224I0J302D01*
G01Y1713230D01*
G37*
G36*
G01X229205Y1713532D02*
X232905D01*
G02X233208Y1713230I1J-302D01*
G01Y1703224D01*
G02X232905Y1702922I-303J1D01*
G01X229205D01*
G02X228902Y1703224I-1J302D01*
G01Y1713230D01*
G02X229205Y1713532I303J-1D01*
G37*
G36*
G01X244953D02*
X248653D01*
G02X248956Y1713230I1J-302D01*
G01Y1703224D01*
G02X248653Y1702922I-303J1D01*
G01X244953D01*
G02X244650Y1703224I-1J302D01*
G01Y1713230D01*
G02X244953Y1713532I303J-1D01*
G37*
G36*
G01X260701D02*
X264401D01*
G02X264704Y1713230I1J-302D01*
G01Y1703224D01*
G02X264401Y1702922I-303J1D01*
G01X260701D01*
G02X260398Y1703224I-1J302D01*
G01Y1713230D01*
G02X260701Y1713532I303J-1D01*
G37*
G36*
G01X276449D02*
X280149D01*
G02X280452Y1713230I1J-302D01*
G01Y1703224D01*
G02X280149Y1702922I-303J1D01*
G01X276449D01*
G02X276146Y1703224I-1J302D01*
G01Y1713230D01*
G02X276449Y1713532I303J-1D01*
G37*
G36*
G01X560307D02*
X564007D01*
G02X564310Y1713230I1J-302D01*
G01Y1703224D01*
G02X564007Y1702922I-303J1D01*
G01X560307D01*
G02X560004Y1703224I-1J302D01*
G01Y1713230D01*
G02X560307Y1713532I303J-1D01*
G37*
G36*
G01X576055D02*
X579755D01*
G02X580058Y1713230I1J-302D01*
G01Y1703224D01*
G02X579755Y1702922I-303J1D01*
G01X576055D01*
G02X575752Y1703224I-1J302D01*
G01Y1713230D01*
G02X576055Y1713532I303J-1D01*
G37*
G36*
G01X591803D02*
X595503D01*
G02X595806Y1713230I1J-302D01*
G01Y1703224D01*
G02X595503Y1702922I-303J1D01*
G01X591803D01*
G02X591500Y1703224I-1J302D01*
G01Y1713230D01*
G02X591803Y1713532I303J-1D01*
G37*
G36*
G01X607551D02*
X611251D01*
G02X611554Y1713230I1J-302D01*
G01Y1703224D01*
G02X611251Y1702922I-303J1D01*
G01X607551D01*
G02X607248Y1703224I-1J302D01*
G01Y1713230D01*
G02X607551Y1713532I303J-1D01*
G37*
G36*
G01X1237079D02*
X1240779D01*
G02X1241082Y1713230I1J-302D01*
G01Y1703224D01*
G02X1240779Y1702922I-303J1D01*
G01X1237079D01*
G02X1236776Y1703224I-1J302D01*
G01Y1713230D01*
G02X1237079Y1713532I303J-1D01*
G37*
G36*
G01X1252827D02*
X1256527D01*
G02X1256830Y1713230I1J-302D01*
G01Y1703224D01*
G02X1256527Y1702922I-303J1D01*
G01X1252827D01*
G02X1252524Y1703224I-1J302D01*
G01Y1713230D01*
G02X1252827Y1713532I303J-1D01*
G37*
G36*
G01X1268575D02*
X1272275D01*
G02X1272578Y1713230I1J-302D01*
G01Y1703224D01*
G02X1272275Y1702922I-303J1D01*
G01X1268575D01*
G02X1268272Y1703224I-1J302D01*
G01Y1713230D01*
G02X1268575Y1713532I303J-1D01*
G37*
G36*
G01X1284323D02*
X1288023D01*
G02X1288326Y1713230I1J-302D01*
G01Y1703224D01*
G02X1288023Y1702922I-303J1D01*
G01X1284323D01*
G02X1284020Y1703224I-1J302D01*
G01Y1713230D01*
G02X1284323Y1713532I303J-1D01*
G37*
G36*
G01X1568181D02*
X1571881D01*
G02X1572184Y1713230I1J-302D01*
G01Y1703224D01*
G02X1571881Y1702922I-303J1D01*
G01X1568181D01*
G02X1567878Y1703224I-1J302D01*
G01Y1713230D01*
G02X1568181Y1713532I303J-1D01*
G37*
G36*
G01X1583929D02*
X1587629D01*
G02X1587932Y1713230I1J-302D01*
G01Y1703224D01*
G02X1587629Y1702922I-303J1D01*
G01X1583929D01*
G02X1583626Y1703224I-1J302D01*
G01Y1713230D01*
G02X1583929Y1713532I303J-1D01*
G37*
G36*
G01X1599677D02*
X1603377D01*
G02X1603680Y1713230I1J-302D01*
G01Y1703224D01*
G02X1603377Y1702922I-303J1D01*
G01X1599677D01*
G02X1599374Y1703224I-1J302D01*
G01Y1713230D01*
G02X1599677Y1713532I303J-1D01*
G37*
G36*
G01X1615425D02*
X1619125D01*
G02X1619428Y1713230I1J-302D01*
G01Y1703224D01*
G02X1619125Y1702922I-303J1D01*
G01X1615425D01*
G02X1615122Y1703224I-1J302D01*
G01Y1713230D01*
G02X1615425Y1713532I303J-1D01*
G37*
G36*
G01X236776Y1717167D02*
G02X237079Y1717470I303J0D01*
G01X240779D01*
G02X241082Y1717167I0J-303D01*
G01Y1707161D01*
G02X240779Y1706858I-303J0D01*
G01X237079D01*
G02X236776Y1707161I0J303D01*
G01Y1717167D01*
G37*
G36*
G01X252524D02*
G02X252827Y1717470I303J0D01*
G01X256527D01*
G02X256830Y1717167I0J-303D01*
G01Y1707161D01*
G02X256527Y1706858I-303J0D01*
G01X252827D01*
G02X252524Y1707161I0J303D01*
G01Y1717167D01*
G37*
G36*
G01X268272D02*
G02X268575Y1717470I303J0D01*
G01X272275D01*
G02X272578Y1717167I0J-303D01*
G01Y1707161D01*
G02X272275Y1706858I-303J0D01*
G01X268575D01*
G02X268272Y1707161I0J303D01*
G01Y1717167D01*
G37*
G36*
G01X284020D02*
G02X284323Y1717470I303J0D01*
G01X288023D01*
G02X288326Y1717167I0J-303D01*
G01Y1707161D01*
G02X288023Y1706858I-303J0D01*
G01X284323D01*
G02X284020Y1707161I0J303D01*
G01Y1717167D01*
G37*
G36*
G01X303706D02*
G02X304008Y1717470I302J1D01*
G01X307708D01*
G02X308010Y1717167I-1J-303D01*
G01Y1707161D01*
G02X307708Y1706858I-302J-1D01*
G01X304008D01*
G02X303706Y1707161I1J303D01*
G01Y1717167D01*
G37*
G36*
G01X319454D02*
G02X319756Y1717470I302J1D01*
G01X323456D01*
G02X323758Y1717167I-1J-303D01*
G01Y1707161D01*
G02X323456Y1706858I-302J-1D01*
G01X319756D01*
G02X319454Y1707161I1J303D01*
G01Y1717167D01*
G37*
G36*
G01X335202D02*
G02X335504Y1717470I302J1D01*
G01X339204D01*
G02X339506Y1717167I-1J-303D01*
G01Y1707161D01*
G02X339204Y1706858I-302J-1D01*
G01X335504D01*
G02X335202Y1707161I1J303D01*
G01Y1717167D01*
G37*
G36*
G01X350950D02*
G02X351252Y1717470I302J1D01*
G01X354952D01*
G02X355254Y1717167I-1J-303D01*
G01Y1707161D01*
G02X354952Y1706858I-302J-1D01*
G01X351252D01*
G02X350950Y1707161I1J303D01*
G01Y1717167D01*
G37*
G36*
G01X500950D02*
G02X501252Y1717470I302J1D01*
G01X504952D01*
G02X505254Y1717167I-1J-303D01*
G01Y1707161D01*
G02X504952Y1706858I-302J-1D01*
G01X501252D01*
G02X500950Y1707161I1J303D01*
G01Y1717167D01*
G37*
G36*
G01X516698D02*
G02X517000Y1717470I302J1D01*
G01X520700D01*
G02X521002Y1717167I-1J-303D01*
G01Y1707161D01*
G02X520700Y1706858I-302J-1D01*
G01X517000D01*
G02X516698Y1707161I1J303D01*
G01Y1717167D01*
G37*
G36*
G01X532446D02*
G02X532748Y1717470I302J1D01*
G01X536448D01*
G02X536750Y1717167I-1J-303D01*
G01Y1707161D01*
G02X536448Y1706858I-302J-1D01*
G01X532748D01*
G02X532446Y1707161I1J303D01*
G01Y1717167D01*
G37*
G36*
G01X548194D02*
G02X548496Y1717470I302J1D01*
G01X552196D01*
G02X552498Y1717167I-1J-303D01*
G01Y1707161D01*
G02X552196Y1706858I-302J-1D01*
G01X548496D01*
G02X548194Y1707161I1J303D01*
G01Y1717167D01*
G37*
G36*
G01X567878D02*
G02X568181Y1717470I303J0D01*
G01X571881D01*
G02X572184Y1717167I0J-303D01*
G01Y1707161D01*
G02X571881Y1706858I-303J0D01*
G01X568181D01*
G02X567878Y1707161I0J303D01*
G01Y1717167D01*
G37*
G36*
G01X583626D02*
G02X583929Y1717470I303J0D01*
G01X587629D01*
G02X587932Y1717167I0J-303D01*
G01Y1707161D01*
G02X587629Y1706858I-303J0D01*
G01X583929D01*
G02X583626Y1707161I0J303D01*
G01Y1717167D01*
G37*
G36*
G01X599374D02*
G02X599677Y1717470I303J0D01*
G01X603377D01*
G02X603680Y1717167I0J-303D01*
G01Y1707161D01*
G02X603377Y1706858I-303J0D01*
G01X599677D01*
G02X599374Y1707161I0J303D01*
G01Y1717167D01*
G37*
G36*
G01X615122D02*
G02X615425Y1717470I303J0D01*
G01X619125D01*
G02X619428Y1717167I0J-303D01*
G01Y1707161D01*
G02X619125Y1706858I-303J0D01*
G01X615425D01*
G02X615122Y1707161I0J303D01*
G01Y1717167D01*
G37*
G36*
G01X1244650D02*
G02X1244953Y1717470I303J0D01*
G01X1248653D01*
G02X1248956Y1717167I0J-303D01*
G01Y1707161D01*
G02X1248653Y1706858I-303J0D01*
G01X1244953D01*
G02X1244650Y1707161I0J303D01*
G01Y1717167D01*
G37*
G36*
G01X1260398D02*
G02X1260701Y1717470I303J0D01*
G01X1264401D01*
G02X1264704Y1717167I0J-303D01*
G01Y1707161D01*
G02X1264401Y1706858I-303J0D01*
G01X1260701D01*
G02X1260398Y1707161I0J303D01*
G01Y1717167D01*
G37*
G36*
G01X1276146D02*
G02X1276449Y1717470I303J0D01*
G01X1280149D01*
G02X1280452Y1717167I0J-303D01*
G01Y1707161D01*
G02X1280149Y1706858I-303J0D01*
G01X1276449D01*
G02X1276146Y1707161I0J303D01*
G01Y1717167D01*
G37*
G36*
G01X1291894D02*
G02X1292197Y1717470I303J0D01*
G01X1295897D01*
G02X1296200Y1717167I0J-303D01*
G01Y1707161D01*
G02X1295897Y1706858I-303J0D01*
G01X1292197D01*
G02X1291894Y1707161I0J303D01*
G01Y1717167D01*
G37*
G36*
G01X1311580D02*
G02X1311882Y1717470I302J1D01*
G01X1315582D01*
G02X1315884Y1717167I-1J-303D01*
G01Y1707161D01*
G02X1315582Y1706858I-302J-1D01*
G01X1311882D01*
G02X1311580Y1707161I1J303D01*
G01Y1717167D01*
G37*
G36*
G01X1327328D02*
G02X1327630Y1717470I302J1D01*
G01X1331330D01*
G02X1331632Y1717167I-1J-303D01*
G01Y1707161D01*
G02X1331330Y1706858I-302J-1D01*
G01X1327630D01*
G02X1327328Y1707161I1J303D01*
G01Y1717167D01*
G37*
G36*
G01X1343076D02*
G02X1343378Y1717470I302J1D01*
G01X1347078D01*
G02X1347380Y1717167I-1J-303D01*
G01Y1707161D01*
G02X1347078Y1706858I-302J-1D01*
G01X1343378D01*
G02X1343076Y1707161I1J303D01*
G01Y1717167D01*
G37*
G36*
G01X1358824D02*
G02X1359126Y1717470I302J1D01*
G01X1362826D01*
G02X1363128Y1717167I-1J-303D01*
G01Y1707161D01*
G02X1362826Y1706858I-302J-1D01*
G01X1359126D01*
G02X1358824Y1707161I1J303D01*
G01Y1717167D01*
G37*
G36*
G01X1508824D02*
G02X1509126Y1717470I302J1D01*
G01X1512826D01*
G02X1513128Y1717167I-1J-303D01*
G01Y1707161D01*
G02X1512826Y1706858I-302J-1D01*
G01X1509126D01*
G02X1508824Y1707161I1J303D01*
G01Y1717167D01*
G37*
G36*
G01X1524572D02*
G02X1524874Y1717470I302J1D01*
G01X1528574D01*
G02X1528876Y1717167I-1J-303D01*
G01Y1707161D01*
G02X1528574Y1706858I-302J-1D01*
G01X1524874D01*
G02X1524572Y1707161I1J303D01*
G01Y1717167D01*
G37*
G36*
G01X1540320D02*
G02X1540622Y1717470I302J1D01*
G01X1544322D01*
G02X1544624Y1717167I-1J-303D01*
G01Y1707161D01*
G02X1544322Y1706858I-302J-1D01*
G01X1540622D01*
G02X1540320Y1707161I1J303D01*
G01Y1717167D01*
G37*
G36*
G01X1556068D02*
G02X1556370Y1717470I302J1D01*
G01X1560070D01*
G02X1560372Y1717167I-1J-303D01*
G01Y1707161D01*
G02X1560070Y1706858I-302J-1D01*
G01X1556370D01*
G02X1556068Y1707161I1J303D01*
G01Y1717167D01*
G37*
G36*
G01X1575752D02*
G02X1576055Y1717470I303J0D01*
G01X1579755D01*
G02X1580058Y1717167I0J-303D01*
G01Y1707161D01*
G02X1579755Y1706858I-303J0D01*
G01X1576055D01*
G02X1575752Y1707161I0J303D01*
G01Y1717167D01*
G37*
G36*
G01X1591500D02*
G02X1591803Y1717470I303J0D01*
G01X1595503D01*
G02X1595806Y1717167I0J-303D01*
G01Y1707161D01*
G02X1595503Y1706858I-303J0D01*
G01X1591803D01*
G02X1591500Y1707161I0J303D01*
G01Y1717167D01*
G37*
G36*
G01X1607248D02*
G02X1607551Y1717470I303J0D01*
G01X1611251D01*
G02X1611554Y1717167I0J-303D01*
G01Y1707161D01*
G02X1611251Y1706858I-303J0D01*
G01X1607551D01*
G02X1607248Y1707161I0J303D01*
G01Y1717167D01*
G37*
G36*
G01X1622996D02*
G02X1623299Y1717470I303J0D01*
G01X1626999D01*
G02X1627302Y1717167I0J-303D01*
G01Y1707161D01*
G02X1626999Y1706858I-303J0D01*
G01X1623299D01*
G02X1622996Y1707161I0J303D01*
G01Y1717167D01*
G37*
G36*
G01X815268Y1720554D02*
G02X816152Y1720920I884J-885D01*
G01X901868D01*
G02X902752Y1720554I0J-1251D01*
G01X906384Y1716922D01*
G02X906750Y1716038I-885J-884D01*
G01Y1662730D01*
G03X906809Y1662588I200J0D01*
G01X925253Y1644144D01*
G03X925395Y1644085I142J141D01*
G01X1071615D01*
G02X1072499Y1643719I0J-1251D01*
G01X1104694Y1611524D01*
G02X1105060Y1610640I-885J-884D01*
G01Y1554972D01*
G02X1104267Y1553063I-2700J2D01*
G01X1102758Y1551554D01*
G02X1102734Y1551530I-1921J1897D01*
G01X1102705Y1551502D01*
X1102674Y1551429D01*
X1102672Y1551104D01*
G03X1102731Y1550962I200J0D01*
G01X1105128Y1548565D01*
G02X1105494Y1547681I-885J-884D01*
G01Y1546325D01*
G03X1105553Y1546183I200J0D01*
G01X1106834Y1544902D01*
G02X1107200Y1544018I-885J-884D01*
G01Y1528083D01*
X1107264Y1527984D01*
X1107318Y1527960D01*
G02Y1525222I-618J-1369D01*
G01X1107264Y1525198D01*
X1107200Y1525099D01*
Y1512882D01*
G02X1106834Y1511998I-1251J0D01*
G01X1104042Y1509206D01*
G02X1103158Y1508840I-884J885D01*
G01X1082180D01*
G02X1081296Y1509206I0J1251D01*
G01X1079878Y1510624D01*
G03X1079731Y1510683I-142J-141D01*
G01X1079401Y1510675D01*
X1079326Y1510640D01*
X1079299Y1510610D01*
G02X1079205Y1510512I-1995J1819D01*
G01X1078341Y1509648D01*
G03X1078339Y1509646I140J-142D01*
G01X1078143Y1509442D01*
G02X1077714Y1509153I-898J870D01*
G01X1077169Y1508932D01*
G02X1076699Y1508840I-471J1158D01*
G01X943079D01*
G02X941170Y1509633I2J2700D01*
G01X939306Y1511497D01*
G03X939304Y1511499I-142J-140D01*
G01X939100Y1511695D01*
G02X938811Y1512124I870J898D01*
G01X938590Y1512669D01*
G02X938498Y1513139I1158J471D01*
G01Y1547259D01*
G02X939291Y1549168I2700J-2D01*
G01X939871Y1549749D01*
G03Y1550031I-142J141D01*
G01X939599Y1550303D01*
G02X939233Y1551187I885J884D01*
G01Y1595231D01*
G03X939033Y1595431I-200J0D01*
G01X923917D01*
G03X923775Y1595372I0J-200D01*
G01X921862Y1593459D01*
G03X921803Y1593317I141J-142D01*
G01Y1590235D01*
G02X921437Y1589351I-1251J0D01*
G01X920893Y1588807D01*
G03X920834Y1588665I141J-142D01*
G01Y1575212D01*
G02X920468Y1574328I-1251J0D01*
G01X919595Y1573455D01*
G02X918711Y1573089I-884J885D01*
G01X904513D01*
G02X903629Y1573455I0J1251D01*
G01X902723Y1574361D01*
G02X902357Y1575245I885J884D01*
G01Y1588311D01*
G03X902298Y1588453I-200J0D01*
G01X901997Y1588754D01*
G02X901631Y1589638I885J884D01*
G01Y1598584D01*
G03X901572Y1598726I-200J0D01*
G01X894103Y1606195D01*
G03X893961Y1606254I-142J-141D01*
G01X887750D01*
G03X887562Y1606122I0J-200D01*
G02X886150Y1605131I-1412J510D01*
G02X885513Y1605273I0J1502D01*
G01X885456Y1605300D01*
X885332Y1605279D01*
X879652Y1599599D01*
G03X879593Y1599457I141J-142D01*
G01Y1589767D01*
G02X879227Y1588883I-1251J0D01*
G01X878892Y1588548D01*
G03X878833Y1588406I141J-142D01*
G01Y1575147D01*
G02X878467Y1574263I-1251J0D01*
G01X877692Y1573488D01*
G02X876808Y1573122I-884J885D01*
G01X862383D01*
G02X861499Y1573488I0J1251D01*
G01X860690Y1574297D01*
G02X860324Y1575181I885J884D01*
G01Y1588310D01*
G03X860265Y1588452I-200J0D01*
G01X860012Y1588705D01*
G02X859646Y1589589I885J884D01*
G01Y1598680D01*
G03X859587Y1598822I-200J0D01*
G01X852067Y1606342D01*
G03X851925Y1606401I-142J-141D01*
G01X845728D01*
X845620Y1606318D01*
X845603Y1606252D01*
G02X844150Y1605131I-1453J381D01*
G01X844149D01*
G02X843483Y1605287I1J1502D01*
G03X843252Y1605249I-89J-179D01*
G01X837586Y1599583D01*
G03X837527Y1599441I141J-142D01*
G01Y1589622D01*
G02X837161Y1588738I-1251J0D01*
G01X837069Y1588646D01*
G03X837010Y1588504I141J-142D01*
G01Y1575374D01*
G02X836644Y1574490I-1251J0D01*
G01X835416Y1573262D01*
G02X834532Y1572896I-884J885D01*
G01X820575D01*
G02X819691Y1573262I0J1251D01*
G01X818721Y1574232D01*
G02X818355Y1575116I885J884D01*
G01Y1588116D01*
G03X818296Y1588258I-200J0D01*
G01X817979Y1588575D01*
G02X817613Y1589459I885J884D01*
G01Y1598907D01*
G03X817554Y1599049I-200J0D01*
G01X810360Y1606243D01*
G03X810218Y1606302I-142J-141D01*
G01X803767D01*
G03X803577Y1606164I0J-200D01*
G02X802150Y1605131I-1427J469D01*
G02X801147Y1605516I1J1501D01*
G03X801012Y1605567I-134J-149D01*
G01X800892Y1605566D01*
G03X800752Y1605508I1J-200D01*
G01X795843Y1600599D01*
G03X795784Y1600457I141J-142D01*
G01Y1589718D01*
G02X795418Y1588834I-1251J0D01*
G01X795004Y1588420D01*
G03X794945Y1588278I141J-142D01*
G01Y1575245D01*
G02X794579Y1574361I-1251J0D01*
G01X793554Y1573336D01*
G02X792670Y1572970I-884J885D01*
G01X778599D01*
G02X777715Y1573336I0J1251D01*
G01X776721Y1574330D01*
G02X776355Y1575214I885J884D01*
G01Y1588309D01*
G03X776296Y1588451I-200J0D01*
G01X768907Y1595840D01*
G03X768765Y1595899I-142J-141D01*
G01X752860D01*
G03X752718Y1595840I0J-200D01*
G01X742663Y1585785D01*
G03X742604Y1585643I141J-142D01*
G01Y1575099D01*
G02X742238Y1574215I-1251J0D01*
G01X741510Y1573487D01*
G02X740626Y1573121I-884J885D01*
G01X726236D01*
G02X725352Y1573487I0J1251D01*
G01X724543Y1574296D01*
G02X724177Y1575180I885J884D01*
G01Y1616962D01*
G02X724543Y1617846I1251J0D01*
G01X726716Y1620019D01*
G02X727600Y1620385I884J-885D01*
G01X739420D01*
G03X739562Y1620444I0J200D01*
G01X742109Y1622991D01*
G02X742993Y1623357I884J-885D01*
G01X768182D01*
G03X768324Y1623416I0J200D01*
G01X772047Y1627139D01*
G03X772106Y1627281I-141J142D01*
G01Y1660280D01*
G02X772472Y1661164I1251J0D01*
G01X808681Y1697373D01*
G03X808740Y1697515I-141J142D01*
G01Y1713508D01*
G02X809106Y1714392I1251J0D01*
G01X815268Y1720554D01*
G37*
G36*
G01X435748Y1712135D02*
G02X446338I5295J6330D01*
G01X446297Y1712101D01*
X446260Y1712004D01*
X446322Y1711612D01*
G03X446443Y1711458I198J31D01*
G02X455296Y1698268I-5399J-13190D01*
G02X426790I-14253J0D01*
G02X435643Y1711458I14252J0D01*
G01X435692Y1711478D01*
X435756Y1711560D01*
X435826Y1712004D01*
X435789Y1712101D01*
X435748Y1712135D01*
G37*
G36*
G01X1411142D02*
G02X1421732I5295J6330D01*
G01X1421691Y1712101D01*
X1421654Y1712004D01*
X1421716Y1711612D01*
G03X1421837Y1711458I198J31D01*
G02X1430690Y1698268I-5399J-13190D01*
G02X1402184I-14253J0D01*
G02X1402186Y1698468I14253J-43D01*
G01X1402185D01*
G02X1411037Y1711458I14252J-201D01*
G01X1411086Y1711478D01*
X1411150Y1711560D01*
X1411219Y1712004D01*
X1411182Y1712102D01*
X1411142Y1712135D01*
G37*
G36*
G01X295832Y1727404D02*
G02X296134Y1727706I302J0D01*
G01X299834D01*
G02X300136Y1727404I0J-302D01*
G01Y1717398D01*
G02X299834Y1717096I-302J0D01*
G01X296134D01*
G02X295832Y1717398I0J302D01*
G01Y1727404D01*
G37*
G36*
G01X311580D02*
G02X311882Y1727706I302J0D01*
G01X315582D01*
G02X315884Y1727404I0J-302D01*
G01Y1717398D01*
G02X315582Y1717096I-302J0D01*
G01X311882D01*
G02X311580Y1717398I0J302D01*
G01Y1727404D01*
G37*
G36*
G01X327328D02*
G02X327630Y1727706I302J0D01*
G01X331330D01*
G02X331632Y1727404I0J-302D01*
G01Y1717398D01*
G02X331330Y1717096I-302J0D01*
G01X327630D01*
G02X327328Y1717398I0J302D01*
G01Y1727404D01*
G37*
G36*
G01X343076D02*
G02X343378Y1727706I302J0D01*
G01X347078D01*
G02X347380Y1727404I0J-302D01*
G01Y1717398D01*
G02X347078Y1717096I-302J0D01*
G01X343378D01*
G02X343076Y1717398I0J302D01*
G01Y1727404D01*
G37*
G36*
G01X493076Y1727403D02*
G02X493378Y1727706I302J1D01*
G01X497078D01*
G02X497380Y1727403I-1J-303D01*
G01Y1717397D01*
G02X497078Y1717094I-302J-1D01*
G01X493378D01*
G02X493076Y1717397I1J303D01*
G01Y1727403D01*
G37*
G36*
G01X508824D02*
G02X509126Y1727706I302J1D01*
G01X512826D01*
G02X513128Y1727403I-1J-303D01*
G01Y1717397D01*
G02X512826Y1717094I-302J-1D01*
G01X509126D01*
G02X508824Y1717397I1J303D01*
G01Y1727403D01*
G37*
G36*
G01X524572D02*
G02X524874Y1727706I302J1D01*
G01X528574D01*
G02X528876Y1727403I-1J-303D01*
G01Y1717397D01*
G02X528574Y1717094I-302J-1D01*
G01X524874D01*
G02X524572Y1717397I1J303D01*
G01Y1727403D01*
G37*
G36*
G01X540320D02*
G02X540622Y1727706I302J1D01*
G01X544322D01*
G02X544624Y1727403I-1J-303D01*
G01Y1717397D01*
G02X544322Y1717094I-302J-1D01*
G01X540622D01*
G02X540320Y1717397I1J303D01*
G01Y1727403D01*
G37*
G36*
G01X560004D02*
G02X560307Y1727706I303J0D01*
G01X564007D01*
G02X564310Y1727403I0J-303D01*
G01Y1717397D01*
G02X564007Y1717094I-303J0D01*
G01X560307D01*
G02X560004Y1717397I0J303D01*
G01Y1727403D01*
G37*
G36*
G01X575752D02*
G02X576055Y1727706I303J0D01*
G01X579755D01*
G02X580058Y1727403I0J-303D01*
G01Y1717397D01*
G02X579755Y1717094I-303J0D01*
G01X576055D01*
G02X575752Y1717397I0J303D01*
G01Y1727403D01*
G37*
G36*
G01X591500D02*
G02X591803Y1727706I303J0D01*
G01X595503D01*
G02X595806Y1727403I0J-303D01*
G01Y1717397D01*
G02X595503Y1717094I-303J0D01*
G01X591803D01*
G02X591500Y1717397I0J303D01*
G01Y1727403D01*
G37*
G36*
G01X607248D02*
G02X607551Y1727706I303J0D01*
G01X611251D01*
G02X611554Y1727403I0J-303D01*
G01Y1717397D01*
G02X611251Y1717094I-303J0D01*
G01X607551D01*
G02X607248Y1717397I0J303D01*
G01Y1727403D01*
G37*
G36*
G01X1303706Y1727404D02*
G02X1304008Y1727706I302J0D01*
G01X1307708D01*
G02X1308010Y1727404I0J-302D01*
G01Y1717398D01*
G02X1307708Y1717096I-302J0D01*
G01X1304008D01*
G02X1303706Y1717398I0J302D01*
G01Y1727404D01*
G37*
G36*
G01X1319454D02*
G02X1319756Y1727706I302J0D01*
G01X1323456D01*
G02X1323758Y1727404I0J-302D01*
G01Y1717398D01*
G02X1323456Y1717096I-302J0D01*
G01X1319756D01*
G02X1319454Y1717398I0J302D01*
G01Y1727404D01*
G37*
G36*
G01X1335202D02*
G02X1335504Y1727706I302J0D01*
G01X1339204D01*
G02X1339506Y1727404I0J-302D01*
G01Y1717398D01*
G02X1339204Y1717096I-302J0D01*
G01X1335504D01*
G02X1335202Y1717398I0J302D01*
G01Y1727404D01*
G37*
G36*
G01X1350950D02*
G02X1351252Y1727706I302J0D01*
G01X1354952D01*
G02X1355254Y1727404I0J-302D01*
G01Y1717398D01*
G02X1354952Y1717096I-302J0D01*
G01X1351252D01*
G02X1350950Y1717398I0J302D01*
G01Y1727404D01*
G37*
G36*
G01X1500950Y1727403D02*
G02X1501252Y1727706I302J1D01*
G01X1504952D01*
G02X1505254Y1727403I-1J-303D01*
G01Y1717397D01*
G02X1504952Y1717094I-302J-1D01*
G01X1501252D01*
G02X1500950Y1717397I1J303D01*
G01Y1727403D01*
G37*
G36*
G01X1516698D02*
G02X1517000Y1727706I302J1D01*
G01X1520700D01*
G02X1521002Y1727403I-1J-303D01*
G01Y1717397D01*
G02X1520700Y1717094I-302J-1D01*
G01X1517000D01*
G02X1516698Y1717397I1J303D01*
G01Y1727403D01*
G37*
G36*
G01X1532446D02*
G02X1532748Y1727706I302J1D01*
G01X1536448D01*
G02X1536750Y1727403I-1J-303D01*
G01Y1717397D01*
G02X1536448Y1717094I-302J-1D01*
G01X1532748D01*
G02X1532446Y1717397I1J303D01*
G01Y1727403D01*
G37*
G36*
G01X1548194D02*
G02X1548496Y1727706I302J1D01*
G01X1552196D01*
G02X1552498Y1727403I-1J-303D01*
G01Y1717397D01*
G02X1552196Y1717094I-302J-1D01*
G01X1548496D01*
G02X1548194Y1717397I1J303D01*
G01Y1727403D01*
G37*
G36*
G01X1567878D02*
G02X1568181Y1727706I303J0D01*
G01X1571881D01*
G02X1572184Y1727403I0J-303D01*
G01Y1717397D01*
G02X1571881Y1717094I-303J0D01*
G01X1568181D01*
G02X1567878Y1717397I0J303D01*
G01Y1727403D01*
G37*
G36*
G01X1583626D02*
G02X1583929Y1727706I303J0D01*
G01X1587629D01*
G02X1587932Y1727403I0J-303D01*
G01Y1717397D01*
G02X1587629Y1717094I-303J0D01*
G01X1583929D01*
G02X1583626Y1717397I0J303D01*
G01Y1727403D01*
G37*
G36*
G01X1599374D02*
G02X1599677Y1727706I303J0D01*
G01X1603377D01*
G02X1603680Y1727403I0J-303D01*
G01Y1717397D01*
G02X1603377Y1717094I-303J0D01*
G01X1599677D01*
G02X1599374Y1717397I0J303D01*
G01Y1727403D01*
G37*
G36*
G01X1615122D02*
G02X1615425Y1727706I303J0D01*
G01X1619125D01*
G02X1619428Y1727403I0J-303D01*
G01Y1717397D01*
G02X1619125Y1717094I-303J0D01*
G01X1615425D01*
G02X1615122Y1717397I0J303D01*
G01Y1727403D01*
G37*
G36*
G01X229205Y1727706D02*
X232905D01*
G02X233208Y1727404I1J-302D01*
G01Y1717398D01*
G02X232905Y1717096I-303J1D01*
G01X229205D01*
G02X228902Y1717398I-1J302D01*
G01Y1727404D01*
G02X229205Y1727706I303J-1D01*
G37*
G36*
G01X244953D02*
X248653D01*
G02X248956Y1727404I1J-302D01*
G01Y1717398D01*
G02X248653Y1717096I-303J1D01*
G01X244953D01*
G02X244650Y1717398I-1J302D01*
G01Y1727404D01*
G02X244953Y1727706I303J-1D01*
G37*
G36*
G01X260701D02*
X264401D01*
G02X264704Y1727404I1J-302D01*
G01Y1717398D01*
G02X264401Y1717096I-303J1D01*
G01X260701D01*
G02X260398Y1717398I-1J302D01*
G01Y1727404D01*
G02X260701Y1727706I303J-1D01*
G37*
G36*
G01X276449D02*
X280149D01*
G02X280452Y1727404I1J-302D01*
G01Y1717398D01*
G02X280149Y1717096I-303J1D01*
G01X276449D01*
G02X276146Y1717398I-1J302D01*
G01Y1727404D01*
G02X276449Y1727706I303J-1D01*
G37*
G36*
G01X1237079D02*
X1240779D01*
G02X1241082Y1727404I1J-302D01*
G01Y1717398D01*
G02X1240779Y1717096I-303J1D01*
G01X1237079D01*
G02X1236776Y1717398I-1J302D01*
G01Y1727404D01*
G02X1237079Y1727706I303J-1D01*
G37*
G36*
G01X1252827D02*
X1256527D01*
G02X1256830Y1727404I1J-302D01*
G01Y1717398D01*
G02X1256527Y1717096I-303J1D01*
G01X1252827D01*
G02X1252524Y1717398I-1J302D01*
G01Y1727404D01*
G02X1252827Y1727706I303J-1D01*
G37*
G36*
G01X1268575D02*
X1272275D01*
G02X1272578Y1727404I1J-302D01*
G01Y1717398D01*
G02X1272275Y1717096I-303J1D01*
G01X1268575D01*
G02X1268272Y1717398I-1J302D01*
G01Y1727404D01*
G02X1268575Y1727706I303J-1D01*
G37*
G36*
G01X1284323D02*
X1288023D01*
G02X1288326Y1727404I1J-302D01*
G01Y1717398D01*
G02X1288023Y1717096I-303J1D01*
G01X1284323D01*
G02X1284020Y1717398I-1J302D01*
G01Y1727404D01*
G02X1284323Y1727706I303J-1D01*
G37*
G36*
G01X500950Y1731340D02*
G02X501252Y1731642I302J0D01*
G01X504952D01*
G02X505254Y1731340I0J-302D01*
G01Y1721334D01*
G02X504952Y1721032I-302J0D01*
G01X501252D01*
G02X500950Y1721334I0J302D01*
G01Y1731340D01*
G37*
G36*
G01X516698D02*
G02X517000Y1731642I302J0D01*
G01X520700D01*
G02X521002Y1731340I0J-302D01*
G01Y1721334D01*
G02X520700Y1721032I-302J0D01*
G01X517000D01*
G02X516698Y1721334I0J302D01*
G01Y1731340D01*
G37*
G36*
G01X532446D02*
G02X532748Y1731642I302J0D01*
G01X536448D01*
G02X536750Y1731340I0J-302D01*
G01Y1721334D01*
G02X536448Y1721032I-302J0D01*
G01X532748D01*
G02X532446Y1721334I0J302D01*
G01Y1731340D01*
G37*
G36*
G01X548194D02*
G02X548496Y1731642I302J0D01*
G01X552196D01*
G02X552498Y1731340I0J-302D01*
G01Y1721334D01*
G02X552196Y1721032I-302J0D01*
G01X548496D01*
G02X548194Y1721334I0J302D01*
G01Y1731340D01*
G37*
G36*
G01X1508824D02*
G02X1509126Y1731642I302J0D01*
G01X1512826D01*
G02X1513128Y1731340I0J-302D01*
G01Y1721334D01*
G02X1512826Y1721032I-302J0D01*
G01X1509126D01*
G02X1508824Y1721334I0J302D01*
G01Y1731340D01*
G37*
G36*
G01X1524572D02*
G02X1524874Y1731642I302J0D01*
G01X1528574D01*
G02X1528876Y1731340I0J-302D01*
G01Y1721334D01*
G02X1528574Y1721032I-302J0D01*
G01X1524874D01*
G02X1524572Y1721334I0J302D01*
G01Y1731340D01*
G37*
G36*
G01X1540320D02*
G02X1540622Y1731642I302J0D01*
G01X1544322D01*
G02X1544624Y1731340I0J-302D01*
G01Y1721334D01*
G02X1544322Y1721032I-302J0D01*
G01X1540622D01*
G02X1540320Y1721334I0J302D01*
G01Y1731340D01*
G37*
G36*
G01X1556068D02*
G02X1556370Y1731642I302J0D01*
G01X1560070D01*
G02X1560372Y1731340I0J-302D01*
G01Y1721334D01*
G02X1560070Y1721032I-302J0D01*
G01X1556370D01*
G02X1556068Y1721334I0J302D01*
G01Y1731340D01*
G37*
G36*
G01X568181Y1731642D02*
X571881D01*
G02X572184Y1731340I1J-302D01*
G01Y1721334D01*
G02X571881Y1721032I-303J1D01*
G01X568181D01*
G02X567878Y1721334I-1J302D01*
G01Y1731340D01*
G02X568181Y1731642I303J-1D01*
G37*
G36*
G01X583929D02*
X587629D01*
G02X587932Y1731340I1J-302D01*
G01Y1721334D01*
G02X587629Y1721032I-303J1D01*
G01X583929D01*
G02X583626Y1721334I-1J302D01*
G01Y1731340D01*
G02X583929Y1731642I303J-1D01*
G37*
G36*
G01X599677D02*
X603377D01*
G02X603680Y1731340I1J-302D01*
G01Y1721334D01*
G02X603377Y1721032I-303J1D01*
G01X599677D01*
G02X599374Y1721334I-1J302D01*
G01Y1731340D01*
G02X599677Y1731642I303J-1D01*
G37*
G36*
G01X615425D02*
X619125D01*
G02X619428Y1731340I1J-302D01*
G01Y1721334D01*
G02X619125Y1721032I-303J1D01*
G01X615425D01*
G02X615122Y1721334I-1J302D01*
G01Y1731340D01*
G02X615425Y1731642I303J-1D01*
G37*
G36*
G01X1576055D02*
X1579755D01*
G02X1580058Y1731340I1J-302D01*
G01Y1721334D01*
G02X1579755Y1721032I-303J1D01*
G01X1576055D01*
G02X1575752Y1721334I-1J302D01*
G01Y1731340D01*
G02X1576055Y1731642I303J-1D01*
G37*
G36*
G01X1591803D02*
X1595503D01*
G02X1595806Y1731340I1J-302D01*
G01Y1721334D01*
G02X1595503Y1721032I-303J1D01*
G01X1591803D01*
G02X1591500Y1721334I-1J302D01*
G01Y1731340D01*
G02X1591803Y1731642I303J-1D01*
G37*
G36*
G01X1607551D02*
X1611251D01*
G02X1611554Y1731340I1J-302D01*
G01Y1721334D01*
G02X1611251Y1721032I-303J1D01*
G01X1607551D01*
G02X1607248Y1721334I-1J302D01*
G01Y1731340D01*
G02X1607551Y1731642I303J-1D01*
G37*
G36*
G01X1623299D02*
X1626999D01*
G02X1627302Y1731340I1J-302D01*
G01Y1721334D01*
G02X1626999Y1721032I-303J1D01*
G01X1623299D01*
G02X1622996Y1721334I-1J302D01*
G01Y1731340D01*
G02X1623299Y1731642I303J-1D01*
G37*
G36*
G01X236776Y1731341D02*
G02X237079Y1731644I303J0D01*
G01X240779D01*
G02X241082Y1731341I0J-303D01*
G01Y1721335D01*
G02X240779Y1721032I-303J0D01*
G01X237079D01*
G02X236776Y1721335I0J303D01*
G01Y1731341D01*
G37*
G36*
G01X252524D02*
G02X252827Y1731644I303J0D01*
G01X256527D01*
G02X256830Y1731341I0J-303D01*
G01Y1721335D01*
G02X256527Y1721032I-303J0D01*
G01X252827D01*
G02X252524Y1721335I0J303D01*
G01Y1731341D01*
G37*
G36*
G01X268272D02*
G02X268575Y1731644I303J0D01*
G01X272275D01*
G02X272578Y1731341I0J-303D01*
G01Y1721335D01*
G02X272275Y1721032I-303J0D01*
G01X268575D01*
G02X268272Y1721335I0J303D01*
G01Y1731341D01*
G37*
G36*
G01X284020D02*
G02X284323Y1731644I303J0D01*
G01X288023D01*
G02X288326Y1731341I0J-303D01*
G01Y1721335D01*
G02X288023Y1721032I-303J0D01*
G01X284323D01*
G02X284020Y1721335I0J303D01*
G01Y1731341D01*
G37*
G36*
G01X303706D02*
G02X304008Y1731644I302J1D01*
G01X307708D01*
G02X308010Y1731341I-1J-303D01*
G01Y1721335D01*
G02X307708Y1721032I-302J-1D01*
G01X304008D01*
G02X303706Y1721335I1J303D01*
G01Y1731341D01*
G37*
G36*
G01X319454D02*
G02X319756Y1731644I302J1D01*
G01X323456D01*
G02X323758Y1731341I-1J-303D01*
G01Y1721335D01*
G02X323456Y1721032I-302J-1D01*
G01X319756D01*
G02X319454Y1721335I1J303D01*
G01Y1731341D01*
G37*
G36*
G01X335202D02*
G02X335504Y1731644I302J1D01*
G01X339204D01*
G02X339506Y1731341I-1J-303D01*
G01Y1721335D01*
G02X339204Y1721032I-302J-1D01*
G01X335504D01*
G02X335202Y1721335I1J303D01*
G01Y1731341D01*
G37*
G36*
G01X350950D02*
G02X351252Y1731644I302J1D01*
G01X354952D01*
G02X355254Y1731341I-1J-303D01*
G01Y1721335D01*
G02X354952Y1721032I-302J-1D01*
G01X351252D01*
G02X350950Y1721335I1J303D01*
G01Y1731341D01*
G37*
G36*
G01X1244650D02*
G02X1244953Y1731644I303J0D01*
G01X1248653D01*
G02X1248956Y1731341I0J-303D01*
G01Y1721335D01*
G02X1248653Y1721032I-303J0D01*
G01X1244953D01*
G02X1244650Y1721335I0J303D01*
G01Y1731341D01*
G37*
G36*
G01X1260398D02*
G02X1260701Y1731644I303J0D01*
G01X1264401D01*
G02X1264704Y1731341I0J-303D01*
G01Y1721335D01*
G02X1264401Y1721032I-303J0D01*
G01X1260701D01*
G02X1260398Y1721335I0J303D01*
G01Y1731341D01*
G37*
G36*
G01X1276146D02*
G02X1276449Y1731644I303J0D01*
G01X1280149D01*
G02X1280452Y1731341I0J-303D01*
G01Y1721335D01*
G02X1280149Y1721032I-303J0D01*
G01X1276449D01*
G02X1276146Y1721335I0J303D01*
G01Y1731341D01*
G37*
G36*
G01X1291894D02*
G02X1292197Y1731644I303J0D01*
G01X1295897D01*
G02X1296200Y1731341I0J-303D01*
G01Y1721335D01*
G02X1295897Y1721032I-303J0D01*
G01X1292197D01*
G02X1291894Y1721335I0J303D01*
G01Y1731341D01*
G37*
G36*
G01X1311580D02*
G02X1311882Y1731644I302J1D01*
G01X1315582D01*
G02X1315884Y1731341I-1J-303D01*
G01Y1721335D01*
G02X1315582Y1721032I-302J-1D01*
G01X1311882D01*
G02X1311580Y1721335I1J303D01*
G01Y1731341D01*
G37*
G36*
G01X1327328D02*
G02X1327630Y1731644I302J1D01*
G01X1331330D01*
G02X1331632Y1731341I-1J-303D01*
G01Y1721335D01*
G02X1331330Y1721032I-302J-1D01*
G01X1327630D01*
G02X1327328Y1721335I1J303D01*
G01Y1731341D01*
G37*
G36*
G01X1343076D02*
G02X1343378Y1731644I302J1D01*
G01X1347078D01*
G02X1347380Y1731341I-1J-303D01*
G01Y1721335D01*
G02X1347078Y1721032I-302J-1D01*
G01X1343378D01*
G02X1343076Y1721335I1J303D01*
G01Y1731341D01*
G37*
G36*
G01X1358824D02*
G02X1359126Y1731644I302J1D01*
G01X1362826D01*
G02X1363128Y1731341I-1J-303D01*
G01Y1721335D01*
G02X1362826Y1721032I-302J-1D01*
G01X1359126D01*
G02X1358824Y1721335I1J303D01*
G01Y1731341D01*
G37*
G54D87*
X1469192Y1095024D03*
X1461790D03*
X1472893D03*
X1469192Y1075890D03*
X1461790D03*
Y1082268D03*
Y1088646D03*
X1469192Y1082268D03*
Y1088646D03*
X1472893Y1075890D03*
Y1082268D03*
Y1088646D03*
X1469192Y1069512D03*
Y1063134D03*
X1461790Y1069512D03*
Y1063134D03*
X1472893Y1069512D03*
Y1063134D03*
X1446987Y1095024D03*
X1450688D03*
X1458089D03*
X1450688Y1075890D03*
X1446987D03*
X1450688Y1082268D03*
X1446987D03*
X1450688Y1088646D03*
X1446987D03*
X1458089Y1075890D03*
Y1082268D03*
Y1088646D03*
X1450688Y1063134D03*
X1446987D03*
X1450688Y1069512D03*
X1446987D03*
X1458089D03*
Y1063134D03*
X1439586Y1095024D03*
X1435885D03*
Y1101402D03*
X1439586D03*
X1435885Y1088646D03*
X1439586D03*
X1435885Y1082268D03*
X1439586D03*
X1435885Y1075890D03*
X1439586D03*
X1435885Y1069512D03*
X1439586D03*
X1435885Y1063134D03*
X1439586D03*
X1430334Y1091835D03*
X1426633D03*
Y1098213D03*
X1430334D03*
X1426633Y1085457D03*
X1430334D03*
X1426633Y1079079D03*
X1430334D03*
X1426633Y1066323D03*
X1430334D03*
X1426633Y1072701D03*
X1430334D03*
X1426633Y1059945D03*
X1430334D03*
X1404453Y1098213D03*
X1408154D03*
X1404453Y1091835D03*
X1408154D03*
X1404453Y1085457D03*
X1408154D03*
X1404453Y1079079D03*
X1408154D03*
X1404453Y1072701D03*
X1408154D03*
X1404453Y1066323D03*
X1408154D03*
X1404453Y1059945D03*
X1408154D03*
X1387800Y1095024D03*
X1395201D03*
X1398902D03*
X1395201Y1101402D03*
X1398902D03*
X1395201Y1088646D03*
X1398902D03*
X1395201Y1082268D03*
X1398902D03*
X1387800Y1088646D03*
Y1082268D03*
Y1075890D03*
X1395201D03*
X1398902D03*
X1387800Y1063134D03*
Y1069512D03*
X1395201D03*
X1398902D03*
X1395201Y1063134D03*
X1398902D03*
X1372996Y1095024D03*
X1376697D03*
X1384099D03*
Y1088646D03*
Y1082268D03*
X1372996Y1088646D03*
X1376697D03*
X1372996Y1082268D03*
X1376697D03*
X1372996Y1075890D03*
X1376697D03*
X1384099D03*
X1372996Y1063134D03*
X1376697D03*
X1372996Y1069512D03*
X1376697D03*
X1384099Y1063134D03*
Y1069512D03*
X1365595Y1095024D03*
X1361894D03*
Y1088646D03*
X1365595D03*
X1361894Y1082268D03*
X1365595D03*
X1361894Y1075890D03*
X1365595D03*
X1361894Y1069512D03*
X1365595D03*
X1361894Y1063134D03*
X1365595D03*
X454192Y1098214D03*
X450491D03*
X463444Y1101403D03*
X459743D03*
X450491Y1091836D03*
X454192D03*
Y1072702D03*
X450491D03*
X454192Y1079080D03*
X450491D03*
X454192Y1085458D03*
X450491D03*
X454192Y1059946D03*
X450491D03*
X454192Y1066324D03*
X450491D03*
X459743Y1095025D03*
X463444D03*
Y1075891D03*
X459743D03*
X463444Y1082269D03*
X459743D03*
X463444Y1088647D03*
X459743D03*
X463444Y1063135D03*
X459743D03*
X463444Y1069513D03*
X459743D03*
X496751Y1095025D03*
Y1088647D03*
Y1082269D03*
Y1075891D03*
Y1063135D03*
Y1069513D03*
X481947Y1095025D03*
X485648D03*
X493050D03*
Y1088647D03*
Y1082269D03*
X481947Y1088647D03*
X485648D03*
X481947Y1082269D03*
X485648D03*
X481947Y1075891D03*
X485648D03*
X493050D03*
X481947Y1063135D03*
X485648D03*
X481947Y1069513D03*
X485648D03*
X493050Y1063135D03*
Y1069513D03*
X474546Y1095025D03*
X470845D03*
Y1088647D03*
X474546D03*
X470845Y1082269D03*
X474546D03*
X470845Y1075891D03*
X474546D03*
X470845Y1069513D03*
X474546D03*
X470845Y1063135D03*
X474546D03*
X422760D03*
X419059D03*
X432012Y1059946D03*
X428311D03*
X432012Y1066324D03*
X428311D03*
X432012Y1072702D03*
X428311D03*
X422760Y1075891D03*
X419059D03*
X422760Y1069513D03*
X419059D03*
X411658D03*
X407957D03*
X411658Y1063135D03*
X407957D03*
X411658Y1075891D03*
X407957D03*
X400555D03*
X396854D03*
X400555Y1069513D03*
X396854D03*
X400555Y1063135D03*
X396854D03*
X389453D03*
X385752D03*
X389453Y1069513D03*
X385752D03*
X389453Y1075891D03*
X385752D03*
X400555Y1082269D03*
X396854D03*
X389453D03*
X385752D03*
X389453Y1088647D03*
X385752D03*
X400555D03*
X396854D03*
X411658Y1082269D03*
X407957D03*
X411658Y1088647D03*
X407957D03*
X422760Y1082269D03*
X419059D03*
X432012Y1079080D03*
X428311D03*
X432012Y1085458D03*
X428311D03*
X422760Y1088647D03*
X419059D03*
X432012Y1091836D03*
X428311D03*
X432012Y1098214D03*
X428311D03*
X422760Y1101403D03*
X419059D03*
X422760Y1095025D03*
X419059D03*
X411658D03*
X407957D03*
X400555D03*
X396854D03*
X385752D03*
X389453D03*
G54D108*
X766889Y1486756D03*
Y1530256D03*
G54D90*
X263316Y87665D03*
X712291Y106722D03*
X820901Y147112D03*
X1005307Y155043D03*
X101675Y160694D03*
X1571516Y319099D03*
X1290127Y410635D03*
X788710Y1488821D03*
G54D86*
X398673Y-18871D03*
Y-8871D03*
X373673D03*
Y-18871D03*
X398673Y-28871D03*
X373673D03*
X718093Y-8871D03*
Y-18871D03*
X743093D03*
Y-8871D03*
X718093Y-28871D03*
X743093D03*
X850152Y-5011D03*
X825152D03*
X850152Y-15011D03*
X825152D03*
X850152Y-35011D03*
Y-25011D03*
X825152D03*
Y-35011D03*
X850152Y4989D03*
X825152D03*
X850152Y14989D03*
X825152D03*
X850152Y24989D03*
X825152D03*
X1169572Y-5011D03*
X1194572D03*
X1169572Y-15011D03*
X1194572D03*
X1169572Y-25011D03*
Y-35011D03*
X1194572D03*
Y-25011D03*
X1169572Y4989D03*
X1194572D03*
X1169572Y14989D03*
X1194572D03*
X1169572Y24989D03*
X1194572D03*
X1253672Y-15011D03*
X1228672D03*
X1253672Y-35011D03*
Y-25011D03*
X1228672D03*
Y-35011D03*
X1253672Y-5011D03*
X1228672D03*
X1253672Y4989D03*
Y14989D03*
X1228672D03*
Y4989D03*
X1253672Y24989D03*
X1228672D03*
X1428431Y-15011D03*
X1453431D03*
X1428431Y-25011D03*
Y-35011D03*
X1453431D03*
Y-25011D03*
X1428431Y-5011D03*
X1453431D03*
X1428431Y14989D03*
Y4989D03*
X1453431D03*
Y14989D03*
X1428431Y24989D03*
X1453431D03*
X1546966Y-39212D03*
Y-29212D03*
X1521966D03*
Y-39212D03*
X1546966Y-19212D03*
X1521966D03*
X1721725Y-29212D03*
Y-39212D03*
X1746725D03*
Y-29212D03*
X1721725Y-19212D03*
X1746725D03*
G54D88*
X60303Y20354D03*
X1534712D03*
X505185Y41141D03*
G54D89*
X312921Y24291D03*
X1787330D03*
X929331Y160413D03*
X922441Y237697D03*
G54D97*
X676509Y224606D03*
G54D95*
Y145866D03*
G54D110*
X791280Y1704890D03*
X1066280D03*
G54D105*
X1340948Y1179681D03*
G54D100*
X433624Y594259D03*
X1415690Y601230D03*
X1487677Y640145D03*
X1524437Y640365D03*
X326731Y653394D03*
X363731D03*
X1291146Y1375715D03*
X1320516D03*
X1166535Y1412479D03*
X1700840Y1424519D03*
X754645Y1426892D03*
G54D91*
X526460Y99195D03*
X400426Y114515D03*
X553780Y122940D03*
X570860Y123010D03*
X417486Y125879D03*
X35852Y668745D03*
Y679710D03*
Y690616D03*
Y701522D03*
X372000Y833497D03*
Y844727D03*
X1342036Y1204729D03*
X313284Y1216822D03*
X390974Y1221149D03*
X388630Y1238447D03*
X814296Y1385745D03*
X50880Y1417263D03*
X558876Y1456605D03*
X1115098Y1470571D03*
X427286Y1481890D03*
X555348D03*
X544794Y1482382D03*
X672856D03*
X544794Y1495782D03*
X672856D03*
X427286Y1503690D03*
X555348D03*
X1170986Y1514890D03*
X1299048D03*
X1435160D03*
X1563222D03*
X1288494Y1515382D03*
X1416556D03*
X1552668D03*
X1680730D03*
X426704Y1525031D03*
X554766D03*
X1288494Y1528782D03*
X1416556D03*
X1552668D03*
X1680730D03*
X1170986Y1536690D03*
X1299048D03*
X1435160D03*
X1563222D03*
X188254Y1546697D03*
X192978D03*
X207152D03*
X211876D03*
X226050D03*
X230774D03*
X254396D03*
X259120D03*
X316316D03*
X321040D03*
X335214D03*
X339938D03*
X354112D03*
X358836D03*
X382458D03*
X387182D03*
X461876D03*
X466600D03*
X480774D03*
X485498D03*
X499672D03*
X504396D03*
X509120D03*
X513844D03*
X589938D03*
X594662D03*
X608836D03*
X613560D03*
X627734D03*
X632458D03*
X637182D03*
X641906D03*
X1170404Y1558031D03*
X1298466D03*
X1434578D03*
X1562640D03*
X1205576Y1579697D03*
X1210300D03*
X1224474D03*
X1229198D03*
X1243372D03*
X1248096D03*
X1252820D03*
X1257544D03*
X1333638D03*
X1338362D03*
X1352536D03*
X1357260D03*
X1371434D03*
X1376158D03*
X1380882D03*
X1385606D03*
X1469750D03*
X1474474D03*
X1488648D03*
X1493372D03*
X1507546D03*
X1512270D03*
X1516994D03*
X1521718D03*
X1597812D03*
X1602536D03*
X1616710D03*
X1621434D03*
X1635608D03*
X1640332D03*
X1645056D03*
X1649780D03*
X1131824Y1602293D03*
X436776Y1612094D03*
X142576Y1641863D03*
X1141084Y1644972D03*
X1090958Y1648228D03*
X40922Y1656569D03*
X85836Y1656843D03*
X165336Y1676777D03*
G54D109*
X138071Y1482244D03*
X698819D03*
X1145945Y1515236D03*
X1706693D03*
X163662Y1593661D03*
X673228D03*
X1171536Y1626654D03*
X1681102D03*
G54D92*
X559069Y103685D03*
X482255Y131522D03*
X704771Y169488D03*
X716699Y175387D03*
X704771Y181299D03*
X716699Y187387D03*
X704771Y193110D03*
X716699Y198887D03*
X704771Y204921D03*
X716699Y210721D03*
X704771Y216732D03*
X1007587Y763246D03*
Y774180D03*
Y785182D03*
Y796184D03*
Y807118D03*
X385001Y815227D03*
X1007587Y818052D03*
X371999Y821227D03*
X1007587Y829054D03*
Y840056D03*
X1315657Y1197832D03*
X1346063Y1216029D03*
X1370685Y1224732D03*
X58349Y1408031D03*
X653999Y1425057D03*
X546253Y1455807D03*
X163113Y1481890D03*
X291175D03*
X280621Y1482382D03*
X408683D03*
X280621Y1495782D03*
X408683D03*
X163113Y1503690D03*
X291175D03*
X162531Y1525031D03*
X290593D03*
X197703Y1546697D03*
X202427D03*
X216601D03*
X221325D03*
X235499D03*
X240223D03*
X244947D03*
X249671D03*
X325765D03*
X330489D03*
X344663D03*
X349387D03*
X363561D03*
X368285D03*
X373009D03*
X377733D03*
X452427D03*
X457151D03*
X471325D03*
X476049D03*
X490223D03*
X494947D03*
X518569D03*
X523293D03*
X580489D03*
X585213D03*
X599387D03*
X604111D03*
X618285D03*
X623009D03*
X646631D03*
X651355D03*
X1196127Y1579697D03*
X1200851D03*
X1215025D03*
X1219749D03*
X1233923D03*
X1238647D03*
X1262269D03*
X1266993D03*
X1324189D03*
X1328913D03*
X1343087D03*
X1347811D03*
X1361985D03*
X1366709D03*
X1390331D03*
X1395055D03*
X1460301D03*
X1465025D03*
X1479199D03*
X1483923D03*
X1498097D03*
X1502821D03*
X1526443D03*
X1531167D03*
X1588363D03*
X1593087D03*
X1607261D03*
X1611985D03*
X1626159D03*
X1630883D03*
X1654505D03*
X1659229D03*
X1142917Y1585014D03*
X1118133Y1589698D03*
X403837Y1610756D03*
X154945Y1626050D03*
X163735Y1633669D03*
X193679Y1641752D03*
X307255Y1645450D03*
X205479Y1650430D03*
X1146501Y1653908D03*
X297323Y1655472D03*
X99443Y1660231D03*
X165491Y1663882D03*
X87891Y1672821D03*
X41679Y1675023D03*
X100443Y1685763D03*
G54D111*
X1766929Y1714960D03*
G54D93*
X516020Y107320D03*
X535170Y113180D03*
X405606Y127765D03*
X80948Y523563D03*
X80318Y541363D03*
G54D101*
X117933Y605376D03*
X1094076Y605378D03*
X1739745Y605411D03*
X763602Y605413D03*
G54D84*
X1729562Y-24215D03*
Y-34215D03*
X1436268Y9986D03*
Y-14D03*
Y-20014D03*
Y-30014D03*
X725930Y-13874D03*
Y-23874D03*
X390846Y-13874D03*
Y-23874D03*
G54D83*
X1837795Y18819D03*
X19685Y-29134D03*
X1800449Y126194D03*
X44000Y154200D03*
X31818Y1424257D03*
X1804650Y1667292D03*
X441043Y1672205D03*
X1416437D03*
X1885039Y49021D03*
X2081889Y-29134D03*
X2081889Y1803261D03*
X1871260Y1291627D03*
G54D99*
X62813Y414050D03*
X47619Y417134D03*
X1025493Y763769D03*
G54D96*
X805690Y204724D03*
X1057659D03*
G54D94*
X1829921Y130314D03*
G54D85*
X1539139Y-24215D03*
Y-34215D03*
X1245845Y9986D03*
Y-14D03*
Y-20014D03*
Y-30014D03*
X1177409Y19986D03*
Y9986D03*
Y-10014D03*
Y-20014D03*
X842325Y19986D03*
Y9986D03*
Y-10014D03*
Y-20014D03*
G54D106*
X1296331Y1199922D03*
X320189Y1199923D03*
G54D104*
X1582551Y1019213D03*
X1251055D03*
X606409Y1019214D03*
X274913D03*
G54D102*
X1296331Y838504D03*
X320189Y838505D03*
G54D103*
X1537275Y838504D03*
X561133Y838505D03*
X1537275Y1199922D03*
X561133Y1199923D03*
G54D107*
X841240Y1420331D03*
X1016240D03*
G54D98*
X177413Y277208D03*
X1153555D03*
X704185Y277236D03*
X1680327D03*
%LPC*%
G75*
G36*
G01X386552Y1069513D02*
G02I-800J0D01*
G37*
G36*
G01Y1063135D02*
G02I-800J0D01*
G37*
G36*
G01X390253Y1069513D02*
G02I-800J0D01*
G37*
G36*
G01Y1063135D02*
G02I-800J0D01*
G37*
G36*
G01X386552Y1075891D02*
G02I-800J0D01*
G37*
G36*
G01X390253D02*
G02I-800J0D01*
G37*
G36*
G01X386552Y1088647D02*
G02I-800J0D01*
G37*
G36*
G01Y1082269D02*
G02I-800J0D01*
G37*
G36*
G01X390253Y1088647D02*
G02I-800J0D01*
G37*
G36*
G01Y1082269D02*
G02I-800J0D01*
G37*
G36*
G01X386552Y1095025D02*
G02I-800J0D01*
G37*
G36*
G01X390253D02*
G02I-800J0D01*
G37*
G36*
G01X397654Y1069513D02*
G02I-800J0D01*
G37*
G36*
G01Y1063135D02*
G02I-800J0D01*
G37*
G36*
G01X408757Y1069513D02*
G02I-800J0D01*
G37*
G36*
G01Y1063135D02*
G02I-800J0D01*
G37*
G36*
G01X401355Y1069513D02*
G02I-800J0D01*
G37*
G36*
G01Y1063135D02*
G02I-800J0D01*
G37*
G36*
G01X397654Y1075891D02*
G02I-800J0D01*
G37*
G36*
G01X408757D02*
G02I-800J0D01*
G37*
G36*
G01X401355D02*
G02I-800J0D01*
G37*
G36*
G01X397654Y1088647D02*
G02I-800J0D01*
G37*
G36*
G01Y1082269D02*
G02I-800J0D01*
G37*
G36*
G01X408757Y1088647D02*
G02I-800J0D01*
G37*
G36*
G01Y1082269D02*
G02I-800J0D01*
G37*
G36*
G01X401355Y1088647D02*
G02I-800J0D01*
G37*
G36*
G01Y1082269D02*
G02I-800J0D01*
G37*
G36*
G01X397654Y1095025D02*
G02I-800J0D01*
G37*
G36*
G01X408757D02*
G02I-800J0D01*
G37*
G36*
G01X401355D02*
G02I-800J0D01*
G37*
G36*
G01X419859Y1063135D02*
G02I-800J0D01*
G37*
G36*
G01Y1069513D02*
G02I-800J0D01*
G37*
G36*
G01X423560Y1063135D02*
G02I-800J0D01*
G37*
G36*
G01X412458Y1069513D02*
G02I-800J0D01*
G37*
G36*
G01Y1063135D02*
G02I-800J0D01*
G37*
G36*
G01X423560Y1069513D02*
G02I-800J0D01*
G37*
G36*
G01X419859Y1075891D02*
G02I-800J0D01*
G37*
G36*
G01X423560D02*
G02I-800J0D01*
G37*
G36*
G01X412458D02*
G02I-800J0D01*
G37*
G36*
G01X419859Y1082269D02*
G02I-800J0D01*
G37*
G36*
G01Y1088647D02*
G02I-800J0D01*
G37*
G36*
G01X423560Y1082269D02*
G02I-800J0D01*
G37*
G36*
G01X412458Y1088647D02*
G02I-800J0D01*
G37*
G36*
G01Y1082269D02*
G02I-800J0D01*
G37*
G36*
G01X423560Y1088647D02*
G02I-800J0D01*
G37*
G36*
G01X419859Y1095025D02*
G02I-800J0D01*
G37*
G36*
G01Y1101403D02*
G02I-800J0D01*
G37*
G36*
G01X423560Y1095025D02*
G02I-800J0D01*
G37*
G36*
G01Y1101403D02*
G02I-800J0D01*
G37*
G36*
G01X412458Y1095025D02*
G02I-800J0D01*
G37*
G36*
G01X429111Y1059946D02*
G02I-800J0D01*
G37*
G36*
G01X432812D02*
G02I-800J0D01*
G37*
G36*
G01X429111Y1072702D02*
G02I-800J0D01*
G37*
G36*
G01Y1066324D02*
G02I-800J0D01*
G37*
G36*
G01X432812Y1072702D02*
G02I-800J0D01*
G37*
G36*
G01Y1066324D02*
G02I-800J0D01*
G37*
G36*
G01X429111Y1079080D02*
G02I-800J0D01*
G37*
G36*
G01X432812D02*
G02I-800J0D01*
G37*
G36*
G01X429111Y1085458D02*
G02I-800J0D01*
G37*
G36*
G01X432812D02*
G02I-800J0D01*
G37*
G36*
G01X429111Y1098214D02*
G02I-800J0D01*
G37*
G36*
G01Y1091836D02*
G02I-800J0D01*
G37*
G36*
G01X432812Y1098214D02*
G02I-800J0D01*
G37*
G36*
G01Y1091836D02*
G02I-800J0D01*
G37*
G36*
G01X454992Y1059946D02*
G02I-800J0D01*
G37*
G36*
G01X451291D02*
G02I-800J0D01*
G37*
G36*
G01X454992Y1066324D02*
G02I-800J0D01*
G37*
G36*
G01Y1072702D02*
G02I-800J0D01*
G37*
G36*
G01X451291Y1066324D02*
G02I-800J0D01*
G37*
G36*
G01Y1072702D02*
G02I-800J0D01*
G37*
G36*
G01X454992Y1079080D02*
G02I-800J0D01*
G37*
G36*
G01X451291D02*
G02I-800J0D01*
G37*
G36*
G01X454992Y1085458D02*
G02I-800J0D01*
G37*
G36*
G01X451291D02*
G02I-800J0D01*
G37*
G36*
G01X454992Y1091836D02*
G02I-800J0D01*
G37*
G36*
G01Y1098214D02*
G02I-800J0D01*
G37*
G36*
G01X451291Y1091836D02*
G02I-800J0D01*
G37*
G36*
G01Y1098214D02*
G02I-800J0D01*
G37*
G36*
G01X464244Y1063135D02*
G02I-800J0D01*
G37*
G36*
G01Y1069513D02*
G02I-800J0D01*
G37*
G36*
G01X460543Y1063135D02*
G02I-800J0D01*
G37*
G36*
G01Y1069513D02*
G02I-800J0D01*
G37*
G36*
G01X464244Y1075891D02*
G02I-800J0D01*
G37*
G36*
G01X460543D02*
G02I-800J0D01*
G37*
G36*
G01X464244Y1082269D02*
G02I-800J0D01*
G37*
G36*
G01Y1088647D02*
G02I-800J0D01*
G37*
G36*
G01X460543Y1082269D02*
G02I-800J0D01*
G37*
G36*
G01Y1088647D02*
G02I-800J0D01*
G37*
G36*
G01X464244Y1101403D02*
G02I-800J0D01*
G37*
G36*
G01Y1095025D02*
G02I-800J0D01*
G37*
G36*
G01X460543Y1101403D02*
G02I-800J0D01*
G37*
G36*
G01Y1095025D02*
G02I-800J0D01*
G37*
G36*
G01X475346Y1063135D02*
G02I-800J0D01*
G37*
G36*
G01Y1069513D02*
G02I-800J0D01*
G37*
G36*
G01X482748Y1063135D02*
G02I-800J0D01*
G37*
G36*
G01Y1069513D02*
G02I-800J0D01*
G37*
G36*
G01X471645Y1063135D02*
G02I-800J0D01*
G37*
G36*
G01Y1069513D02*
G02I-800J0D01*
G37*
G36*
G01X475346Y1075891D02*
G02I-800J0D01*
G37*
G36*
G01X482748D02*
G02I-800J0D01*
G37*
G36*
G01X471645D02*
G02I-800J0D01*
G37*
G36*
G01X475346Y1082269D02*
G02I-800J0D01*
G37*
G36*
G01Y1088647D02*
G02I-800J0D01*
G37*
G36*
G01X482748Y1082269D02*
G02I-800J0D01*
G37*
G36*
G01Y1088647D02*
G02I-800J0D01*
G37*
G36*
G01X471645Y1082269D02*
G02I-800J0D01*
G37*
G36*
G01Y1088647D02*
G02I-800J0D01*
G37*
G36*
G01X475346Y1095025D02*
G02I-800J0D01*
G37*
G36*
G01X482748D02*
G02I-800J0D01*
G37*
G36*
G01X471645D02*
G02I-800J0D01*
G37*
G36*
G01X486449Y1063135D02*
G02I-800J0D01*
G37*
G36*
G01Y1069513D02*
G02I-800J0D01*
G37*
G36*
G01X497551Y1063135D02*
G02I-800J0D01*
G37*
G36*
G01Y1069513D02*
G02I-800J0D01*
G37*
G36*
G01X493850Y1063135D02*
G02I-800J0D01*
G37*
G36*
G01Y1069513D02*
G02I-800J0D01*
G37*
G36*
G01X486449Y1075891D02*
G02I-800J0D01*
G37*
G36*
G01X497551D02*
G02I-800J0D01*
G37*
G36*
G01X493850D02*
G02I-800J0D01*
G37*
G36*
G01X486449Y1082269D02*
G02I-800J0D01*
G37*
G36*
G01Y1088647D02*
G02I-800J0D01*
G37*
G36*
G01X497551Y1082269D02*
G02I-800J0D01*
G37*
G36*
G01Y1088647D02*
G02I-800J0D01*
G37*
G36*
G01X493850Y1082269D02*
G02I-800J0D01*
G37*
G36*
G01Y1088647D02*
G02I-800J0D01*
G37*
G36*
G01X486449Y1095025D02*
G02I-800J0D01*
G37*
G36*
G01X497551D02*
G02I-800J0D01*
G37*
G36*
G01X493850D02*
G02I-800J0D01*
G37*
G36*
G01X816753Y1718420D02*
X901267D01*
G02X901409Y1718361I0J-200D01*
G01X904191Y1715579D01*
G02X904250Y1715437I-141J-142D01*
G01Y1662129D01*
G03X904616Y1661245I1251J0D01*
G01X923910Y1641951D01*
G03X924794Y1641585I884J885D01*
G01X1071014D01*
G02X1071156Y1641526I0J-200D01*
G01X1102501Y1610181D01*
G02X1102560Y1610039I-141J-142D01*
G01Y1554974D01*
G02X1102501Y1554832I-200J0D01*
G03X1102500Y1554831I883J-884D01*
G01X1100990Y1553321D01*
G03X1100989Y1553320I883J-884D01*
G02X1100847Y1553261I-142J141D01*
G01X1094691D01*
G02X1094581Y1553294I0J200D01*
G03X1092934Y1553786I-1647J-2511D01*
G03X1091528Y1553436I1J-3002D01*
G02X1091340I-94J177D01*
G03X1089934Y1553786I-1407J-2652D01*
G03X1088287Y1553294I0J-3003D01*
G02X1088177Y1553261I-110J167D01*
G01X1059235D01*
G02X1059120Y1553297I0J200D01*
G03X1057396Y1553842I-1725J-2457D01*
G03X1055990Y1553492I1J-3002D01*
G02X1055802I-94J177D01*
G03X1054396Y1553842I-1407J-2652D01*
G03X1052672Y1553297I1J-3002D01*
G02X1052557Y1553261I-115J164D01*
G01X1027635D01*
G02X1027520Y1553297I0J200D01*
G03X1025796Y1553842I-1725J-2457D01*
G03X1024390Y1553492I1J-3002D01*
G02X1024202I-94J177D01*
G03X1022796Y1553842I-1407J-2652D01*
G03X1021072Y1553297I1J-3002D01*
G02X1020957Y1553261I-115J164D01*
G01X996035D01*
G02X995920Y1553297I0J200D01*
G03X994196Y1553842I-1725J-2457D01*
G03X992790Y1553492I1J-3002D01*
G02X992602I-94J177D01*
G03X991196Y1553842I-1407J-2652D01*
G03X989472Y1553297I1J-3002D01*
G02X989357Y1553261I-115J164D01*
G01X964400D01*
G02X964287Y1553296I0J200D01*
G03X962584Y1553826I-1703J-2471D01*
G03X961178Y1553476I1J-3002D01*
G02X960990I-94J177D01*
G03X959584Y1553826I-1407J-2652D01*
G03X957881Y1553296I0J-3001D01*
G02X957768Y1553261I-113J165D01*
G01X941933D01*
G02X941733Y1553461I0J200D01*
G01Y1596024D01*
G03X941367Y1596908I-1251J0D01*
G01X940710Y1597565D01*
G03X939826Y1597931I-884J-885D01*
G01X923316D01*
G03X922432Y1597565I0J-1251D01*
G01X919669Y1594802D01*
G03X919303Y1593918I885J-884D01*
G01Y1590836D01*
G02X919244Y1590694I-200J0D01*
G01X918700Y1590150D01*
G03X918334Y1589266I885J-884D01*
G01Y1575813D01*
G02X918275Y1575671I-200J0D01*
G01X918252Y1575648D01*
G02X918110Y1575589I-142J141D01*
G01X905114D01*
G02X904972Y1575648I0J200D01*
G01X904916Y1575704D01*
G02X904857Y1575846I141J142D01*
G01Y1588912D01*
G03X904491Y1589796I-1251J0D01*
G01X904190Y1590097D01*
G02X904131Y1590239I141J142D01*
G01Y1599185D01*
G03X903765Y1600069I-1251J0D01*
G01X895446Y1608388D01*
G03X894562Y1608754I-884J-885D01*
G01X888356D01*
G02X888218Y1608809I0J200D01*
G03X886150Y1609635I-2068J-2176D01*
G03X883149Y1606710I0J-3002D01*
G01X883148Y1606671D01*
X883118Y1606601D01*
X877459Y1600942D01*
G03X877093Y1600058I885J-884D01*
G01Y1590368D01*
G02X877034Y1590226I-200J0D01*
G01X876699Y1589891D01*
G03X876333Y1589007I885J-884D01*
G01Y1575708D01*
X876303Y1575635D01*
X876290Y1575622D01*
X862984D01*
G02X862842Y1575681I0J200D01*
G01X862824Y1575699D01*
Y1588911D01*
G03X862458Y1589795I-1251J0D01*
G01X862205Y1590048D01*
G02X862146Y1590190I141J142D01*
G01Y1599281D01*
G03X861780Y1600165I-1251J0D01*
G01X853410Y1608535D01*
G03X852526Y1608901I-884J-885D01*
G01X846190D01*
G02X846063Y1608947I1J200D01*
G03X844150Y1609635I-1912J-2314D01*
G03X841151Y1606758I0J-3002D01*
G01X841149Y1606720D01*
X841119Y1606652D01*
X835393Y1600926D01*
G03X835027Y1600042I885J-884D01*
G01Y1590223D01*
G02X834968Y1590081I-200J0D01*
G01X834876Y1589989D01*
G03X834510Y1589105I885J-884D01*
G01Y1575975D01*
G02X834451Y1575833I-200J0D01*
G01X834073Y1575455D01*
G02X833931Y1575396I-142J141D01*
G01X821176D01*
G02X821034Y1575455I0J200D01*
G01X820914Y1575575D01*
G02X820855Y1575717I141J142D01*
G01Y1588717D01*
G03X820489Y1589601I-1251J0D01*
G01X820172Y1589918D01*
G02X820113Y1590060I141J142D01*
G01Y1599508D01*
G03X819747Y1600392I-1251J0D01*
G01X811703Y1608436D01*
G03X810819Y1608802I-884J-885D01*
G01X804304D01*
G02X804170Y1608854I0J200D01*
G03X802150Y1609635I-2020J-2222D01*
G03X799323Y1607642I0J-3001D01*
G01X799307Y1607599D01*
X793650Y1601942D01*
G03X793284Y1601058I885J-884D01*
G01Y1590319D01*
G02X793225Y1590177I-200J0D01*
G01X792811Y1589763D01*
G03X792445Y1588879I885J-884D01*
G01Y1575846D01*
G02X792386Y1575704I-200J0D01*
G01X792211Y1575529D01*
G02X792069Y1575470I-142J141D01*
G01X779200D01*
G02X779058Y1575529I0J200D01*
G01X778914Y1575673D01*
G02X778855Y1575815I141J142D01*
G01Y1588910D01*
G03X778489Y1589794I-1251J0D01*
G01X770250Y1598033D01*
G03X769366Y1598399I-884J-885D01*
G01X752259D01*
G03X751375Y1598033I0J-1251D01*
G01X740470Y1587128D01*
G03X740104Y1586244I885J-884D01*
G01Y1575821D01*
G02X739904Y1575621I-200J0D01*
G01X726837D01*
G02X726695Y1575680I0J200D01*
G01X726677Y1575698D01*
Y1597760D01*
X726767Y1597870D01*
X726839Y1597884D01*
G03Y1600832I-289J1474D01*
G01X726767Y1600846D01*
X726677Y1600956D01*
Y1616361D01*
G02X726736Y1616503I200J0D01*
G01X728059Y1617826D01*
G02X728201Y1617885I142J-141D01*
G01X740021D01*
G03X740905Y1618251I0J1251D01*
G01X743452Y1620798D01*
G02X743594Y1620857I142J-141D01*
G01X768783D01*
G03X769667Y1621223I0J1251D01*
G01X774240Y1625796D01*
G03X774606Y1626680I-885J884D01*
G01Y1659679D01*
G02X774665Y1659821I200J0D01*
G01X810874Y1696030D01*
G03X811240Y1696914I-885J884D01*
G01Y1712907D01*
G02X811299Y1713049I200J0D01*
G01X816611Y1718361D01*
G02X816753Y1718420I142J-141D01*
G37*
G36*
G01X1075557Y1548281D02*
G03X1075558Y1548280I884J883D01*
G01X1077438Y1546400D01*
G03X1077439Y1546399I884J883D01*
G02X1077498Y1546257I-141J-142D01*
G01Y1512423D01*
G02X1077439Y1512281I-200J0D01*
G03X1077438Y1512280I883J-884D01*
G01X1076566Y1511408D01*
G02X1076564Y1511406I-142J140D01*
G03X1076557Y1511399I881J-887D01*
G02X1076415Y1511340I-142J141D01*
G01X943081D01*
G02X942939Y1511399I0J200D01*
G03X942938Y1511400I-884J-883D01*
G01X941065Y1513273D01*
X941064Y1513274D01*
G03X941057Y1513281I-887J-881D01*
G02X940998Y1513423I141J142D01*
G01Y1547257D01*
G02X941057Y1547399I200J0D01*
G03X941058Y1547400I-883J884D01*
G01X941938Y1548280D01*
G03X941939Y1548281I-883J884D01*
G02X942081Y1548340I142J-141D01*
G01X1075415D01*
G02X1075557Y1548281I0J-200D01*
G37*
G36*
G01X1081757Y1543874D02*
X1082064Y1544181D01*
G02X1082206Y1544240I142J-141D01*
G01X1099402D01*
G02X1099602Y1544040I0J-200D01*
G01Y1511540D01*
G02X1099402Y1511340I-200J0D01*
G01X1082781D01*
G02X1082639Y1511399I0J200D01*
G01X1081757Y1512281D01*
G02X1081698Y1512423I141J142D01*
G01Y1543732D01*
G02X1081757Y1543874I200J0D01*
G37*
G36*
G01X1362694Y1069512D02*
G02I-800J0D01*
G37*
G36*
G01Y1063134D02*
G02I-800J0D01*
G37*
G36*
G01Y1075890D02*
G02I-800J0D01*
G37*
G36*
G01Y1088646D02*
G02I-800J0D01*
G37*
G36*
G01Y1082268D02*
G02I-800J0D01*
G37*
G36*
G01Y1095024D02*
G02I-800J0D01*
G37*
G36*
G01X1373796Y1069512D02*
G02I-800J0D01*
G37*
G36*
G01Y1063134D02*
G02I-800J0D01*
G37*
G36*
G01X1366395Y1069512D02*
G02I-800J0D01*
G37*
G36*
G01Y1063134D02*
G02I-800J0D01*
G37*
G36*
G01X1377497Y1069512D02*
G02I-800J0D01*
G37*
G36*
G01Y1063134D02*
G02I-800J0D01*
G37*
G36*
G01X1373796Y1075890D02*
G02I-800J0D01*
G37*
G36*
G01X1366395D02*
G02I-800J0D01*
G37*
G36*
G01X1377497D02*
G02I-800J0D01*
G37*
G36*
G01X1373796Y1088646D02*
G02I-800J0D01*
G37*
G36*
G01Y1082268D02*
G02I-800J0D01*
G37*
G36*
G01X1366395Y1088646D02*
G02I-800J0D01*
G37*
G36*
G01Y1082268D02*
G02I-800J0D01*
G37*
G36*
G01X1377497Y1088646D02*
G02I-800J0D01*
G37*
G36*
G01Y1082268D02*
G02I-800J0D01*
G37*
G36*
G01X1373796Y1095024D02*
G02I-800J0D01*
G37*
G36*
G01X1366395D02*
G02I-800J0D01*
G37*
G36*
G01X1377497D02*
G02I-800J0D01*
G37*
G36*
G01X1384899Y1069512D02*
G02I-800J0D01*
G37*
G36*
G01Y1063134D02*
G02I-800J0D01*
G37*
G36*
G01X1388600Y1069512D02*
G02I-800J0D01*
G37*
G36*
G01Y1063134D02*
G02I-800J0D01*
G37*
G36*
G01X1384899Y1075890D02*
G02I-800J0D01*
G37*
G36*
G01X1388600D02*
G02I-800J0D01*
G37*
G36*
G01X1384899Y1088646D02*
G02I-800J0D01*
G37*
G36*
G01Y1082268D02*
G02I-800J0D01*
G37*
G36*
G01X1388600Y1088646D02*
G02I-800J0D01*
G37*
G36*
G01Y1082268D02*
G02I-800J0D01*
G37*
G36*
G01X1384899Y1095024D02*
G02I-800J0D01*
G37*
G36*
G01X1388600D02*
G02I-800J0D01*
G37*
G36*
G01X1405253Y1059945D02*
G02I-800J0D01*
G37*
G36*
G01X1408954D02*
G02I-800J0D01*
G37*
G36*
G01X1396001Y1063134D02*
G02I-800J0D01*
G37*
G36*
G01X1405253Y1072701D02*
G02I-800J0D01*
G37*
G36*
G01Y1066323D02*
G02I-800J0D01*
G37*
G36*
G01X1396001Y1069512D02*
G02I-800J0D01*
G37*
G36*
G01X1399702Y1063134D02*
G02I-800J0D01*
G37*
G36*
G01X1408954Y1072701D02*
G02I-800J0D01*
G37*
G36*
G01Y1066323D02*
G02I-800J0D01*
G37*
G36*
G01X1399702Y1069512D02*
G02I-800J0D01*
G37*
G36*
G01X1396001Y1075890D02*
G02I-800J0D01*
G37*
G36*
G01X1405253Y1079079D02*
G02I-800J0D01*
G37*
G36*
G01X1399702Y1075890D02*
G02I-800J0D01*
G37*
G36*
G01X1408954Y1079079D02*
G02I-800J0D01*
G37*
G36*
G01X1396001Y1082268D02*
G02I-800J0D01*
G37*
G36*
G01X1405253Y1085457D02*
G02I-800J0D01*
G37*
G36*
G01X1396001Y1088646D02*
G02I-800J0D01*
G37*
G36*
G01X1399702Y1082268D02*
G02I-800J0D01*
G37*
G36*
G01X1408954Y1085457D02*
G02I-800J0D01*
G37*
G36*
G01X1399702Y1088646D02*
G02I-800J0D01*
G37*
G36*
G01X1396001Y1095024D02*
G02I-800J0D01*
G37*
G36*
G01Y1101402D02*
G02I-800J0D01*
G37*
G36*
G01X1405253Y1098213D02*
G02I-800J0D01*
G37*
G36*
G01Y1091835D02*
G02I-800J0D01*
G37*
G36*
G01X1399702Y1095024D02*
G02I-800J0D01*
G37*
G36*
G01Y1101402D02*
G02I-800J0D01*
G37*
G36*
G01X1408954Y1098213D02*
G02I-800J0D01*
G37*
G36*
G01Y1091835D02*
G02I-800J0D01*
G37*
G36*
G01X1431134Y1059945D02*
G02I-800J0D01*
G37*
G36*
G01X1427433D02*
G02I-800J0D01*
G37*
G36*
G01X1431134Y1066323D02*
G02I-800J0D01*
G37*
G36*
G01Y1072701D02*
G02I-800J0D01*
G37*
G36*
G01X1427433Y1066323D02*
G02I-800J0D01*
G37*
G36*
G01Y1072701D02*
G02I-800J0D01*
G37*
G36*
G01X1436685Y1063134D02*
G02I-800J0D01*
G37*
G36*
G01Y1069512D02*
G02I-800J0D01*
G37*
G36*
G01X1431134Y1079079D02*
G02I-800J0D01*
G37*
G36*
G01X1427433D02*
G02I-800J0D01*
G37*
G36*
G01X1436685Y1075890D02*
G02I-800J0D01*
G37*
G36*
G01Y1088646D02*
G02I-800J0D01*
G37*
G36*
G01X1431134Y1085457D02*
G02I-800J0D01*
G37*
G36*
G01X1427433D02*
G02I-800J0D01*
G37*
G36*
G01X1436685Y1082268D02*
G02I-800J0D01*
G37*
G36*
G01Y1101402D02*
G02I-800J0D01*
G37*
G36*
G01Y1095024D02*
G02I-800J0D01*
G37*
G36*
G01X1431134Y1091835D02*
G02I-800J0D01*
G37*
G36*
G01Y1098213D02*
G02I-800J0D01*
G37*
G36*
G01X1427433Y1091835D02*
G02I-800J0D01*
G37*
G36*
G01Y1098213D02*
G02I-800J0D01*
G37*
G36*
G01X1440386Y1063134D02*
G02I-800J0D01*
G37*
G36*
G01Y1069512D02*
G02I-800J0D01*
G37*
G36*
G01X1451488Y1063134D02*
G02I-800J0D01*
G37*
G36*
G01Y1069512D02*
G02I-800J0D01*
G37*
G36*
G01X1447787Y1063134D02*
G02I-800J0D01*
G37*
G36*
G01Y1069512D02*
G02I-800J0D01*
G37*
G36*
G01X1440386Y1075890D02*
G02I-800J0D01*
G37*
G36*
G01X1451488D02*
G02I-800J0D01*
G37*
G36*
G01X1447787D02*
G02I-800J0D01*
G37*
G36*
G01X1440386Y1088646D02*
G02I-800J0D01*
G37*
G36*
G01X1451488Y1082268D02*
G02I-800J0D01*
G37*
G36*
G01X1447787D02*
G02I-800J0D01*
G37*
G36*
G01X1440386D02*
G02I-800J0D01*
G37*
G36*
G01X1451488Y1088646D02*
G02I-800J0D01*
G37*
G36*
G01X1447787D02*
G02I-800J0D01*
G37*
G36*
G01X1440386Y1101402D02*
G02I-800J0D01*
G37*
G36*
G01Y1095024D02*
G02I-800J0D01*
G37*
G36*
G01X1451488D02*
G02I-800J0D01*
G37*
G36*
G01X1447787D02*
G02I-800J0D01*
G37*
G36*
G01X1462591Y1063134D02*
G02I-800J0D01*
G37*
G36*
G01Y1069512D02*
G02I-800J0D01*
G37*
G36*
G01X1458890Y1063134D02*
G02I-800J0D01*
G37*
G36*
G01Y1069512D02*
G02I-800J0D01*
G37*
G36*
G01X1462591Y1075890D02*
G02I-800J0D01*
G37*
G36*
G01X1458890D02*
G02I-800J0D01*
G37*
G36*
G01X1462591Y1082268D02*
G02I-800J0D01*
G37*
G36*
G01Y1088646D02*
G02I-800J0D01*
G37*
G36*
G01X1458890Y1082268D02*
G02I-800J0D01*
G37*
G36*
G01Y1088646D02*
G02I-800J0D01*
G37*
G36*
G01X1462591Y1095024D02*
G02I-800J0D01*
G37*
G36*
G01X1458890D02*
G02I-800J0D01*
G37*
G36*
G01X1473693Y1063134D02*
G02I-800J0D01*
G37*
G36*
G01Y1069512D02*
G02I-800J0D01*
G37*
G36*
G01X1469992Y1063134D02*
G02I-800J0D01*
G37*
G36*
G01Y1069512D02*
G02I-800J0D01*
G37*
G36*
G01X1473693Y1075890D02*
G02I-800J0D01*
G37*
G36*
G01X1469992D02*
G02I-800J0D01*
G37*
G36*
G01X1473693Y1082268D02*
G02I-800J0D01*
G37*
G36*
G01Y1088646D02*
G02I-800J0D01*
G37*
G36*
G01X1469992Y1082268D02*
G02I-800J0D01*
G37*
G36*
G01Y1088646D02*
G02I-800J0D01*
G37*
G36*
G01X1473693Y1095024D02*
G02I-800J0D01*
G37*
G36*
G01X1469992D02*
G02I-800J0D01*
G37*
%LPD*%
G75*
G54D14*
X11782Y167036D03*
X18691Y167208D03*
X22409Y230021D03*
X19684Y237154D03*
X19230Y1446459D03*
X34281Y277798D03*
Y282916D03*
X35689Y298207D03*
X34281Y312916D03*
Y307798D03*
X35740Y363337D03*
X39320Y392269D03*
X28562Y517025D03*
X39967Y526709D03*
X30562Y533055D03*
X35952Y551605D03*
X35852Y670445D03*
Y667045D03*
Y681410D03*
Y678010D03*
Y692316D03*
Y703222D03*
Y688916D03*
Y699822D03*
X35010Y1289485D03*
X35040Y1292433D03*
X35080Y1298360D03*
X35040Y1295380D03*
X34584Y1307744D03*
Y1310244D03*
Y1312744D03*
Y1315244D03*
X33822Y1477075D03*
Y1486075D03*
Y1483075D03*
Y1480075D03*
X27205Y1501630D03*
Y1498230D03*
X38058Y1591405D03*
X35167Y1598896D03*
Y1626896D03*
Y1629405D03*
X32927Y1668587D03*
X42449Y282916D03*
Y277798D03*
X41492Y292892D03*
Y298207D03*
X47892Y295452D03*
X40500Y288500D03*
X55254Y292892D03*
X42449Y312916D03*
Y307798D03*
X51114Y360862D03*
X43020Y382942D03*
X40940Y387302D03*
X41933Y395652D03*
X47619Y419084D03*
X47618Y415184D03*
X49360Y428806D03*
X45960D03*
X49212Y451602D03*
X45812D03*
X47812Y517635D03*
X42810Y528070D03*
X39952Y551605D03*
X55099Y1298676D03*
Y1292676D03*
X51000Y1339200D03*
X42822Y1477075D03*
Y1483075D03*
Y1486075D03*
Y1480075D03*
X49265Y1490950D03*
Y1493450D03*
X49188Y1499181D03*
X41360Y1498971D03*
X41309Y1496173D03*
X38650Y1499326D03*
X49177Y1496272D03*
X48383Y1532395D03*
X48157Y1536296D03*
X49196Y1551294D03*
X48324Y1545961D03*
X48758Y1559295D03*
X48907Y1554972D03*
X47735Y1584885D03*
X47973Y1589981D03*
X43633Y1606896D03*
X46833Y1612596D03*
X43933Y1613818D03*
X47633Y1600896D03*
X53633Y1629896D03*
X41208Y1619896D03*
X42491Y1638656D03*
X40167Y1632405D03*
X40922Y1654869D03*
Y1658269D03*
X45052Y1684283D03*
X41679Y1673323D03*
Y1676723D03*
X65933Y28406D03*
Y48720D03*
X61157Y69340D03*
X64557D03*
X66650Y265316D03*
X57271Y272357D03*
X59780Y282866D03*
X62567Y295103D03*
X66289Y298207D03*
X59780Y312866D03*
X59322Y360702D03*
X63429D03*
X67681D03*
X53406Y402862D03*
X62812Y412100D03*
X62813Y416000D03*
X64821Y430806D03*
X60921D03*
X63540Y438802D03*
X64442Y510667D03*
X55682Y517595D03*
X62142Y539495D03*
X56192Y537795D03*
X63633Y528229D03*
X58365Y552365D03*
X53299D03*
X56627Y585818D03*
X59259Y737422D03*
X58751Y777718D03*
X61251D03*
Y775218D03*
X58751D03*
X61620Y768510D03*
X56440Y766180D03*
X58751Y790218D03*
Y792718D03*
Y780218D03*
X61251D03*
X56057Y792750D03*
X61251Y792718D03*
Y790218D03*
X56057Y790250D03*
Y787750D03*
X61251Y787718D03*
X56057Y785250D03*
X61251Y785218D03*
Y782718D03*
X56057Y782750D03*
X58751Y782718D03*
Y785218D03*
Y787718D03*
X57752Y808020D03*
X60547Y1276036D03*
X57747Y1270470D03*
X55099Y1289676D03*
X55043Y1295676D03*
X53700Y1342300D03*
X67010Y1476292D03*
X57822Y1477075D03*
X57777Y1490580D03*
X66710Y1485324D03*
Y1482324D03*
X66785Y1479175D03*
X57822Y1482791D03*
Y1485294D03*
Y1480075D03*
X64030Y1491595D03*
X57770Y1488047D03*
X66696Y1488010D03*
X64030Y1499095D03*
Y1501595D03*
Y1494095D03*
Y1496595D03*
X55370Y1551351D03*
X66229Y1549536D03*
X61605Y1546833D03*
X64275Y1546296D03*
X57811Y1598061D03*
X58633Y1587481D03*
X63633D03*
X61110Y1598146D03*
X58633Y1629896D03*
X64133Y1627896D03*
X64633Y1632896D03*
X64427Y1643496D03*
X64462Y1655624D03*
X61927Y1643496D03*
X65257Y1652941D03*
X56815Y1643431D03*
X62202Y1684579D03*
X66127Y1687362D03*
X72153Y75343D03*
X75553D03*
X79726Y145191D03*
X82026Y143491D03*
X71659Y149191D03*
X71779Y165194D03*
X71775Y153194D03*
X72462Y268223D03*
X77680Y378395D03*
Y380895D03*
X68020Y395222D03*
X80948Y525513D03*
Y521613D03*
X80318Y543313D03*
Y539413D03*
X80915Y767400D03*
X80784Y771366D03*
X68354Y1314097D03*
X80378Y1406676D03*
X83441Y1430500D03*
X81052Y1427410D03*
X81132Y1424195D03*
X79055Y1434000D03*
X73820Y1442893D03*
X81401Y1436105D03*
X73820Y1445945D03*
X73757Y1448500D03*
X81822Y1477075D03*
X77883Y1491440D03*
X80932D03*
X80852Y1488638D03*
X75245Y1491440D03*
X81822Y1480075D03*
Y1483075D03*
Y1486075D03*
X72396Y1491290D03*
X72390Y1499211D03*
X77883Y1499240D03*
X80833D03*
X77883Y1494040D03*
Y1496640D03*
X80932Y1494040D03*
Y1496640D03*
X75245Y1499240D03*
Y1494040D03*
Y1496640D03*
X72396Y1493890D03*
Y1496490D03*
X77920Y1538245D03*
X75796Y1545669D03*
X75396Y1542369D03*
X78796Y1545669D03*
X78096Y1542444D03*
X78372Y1556416D03*
Y1558916D03*
X78522Y1562641D03*
Y1565141D03*
Y1567888D03*
X78403Y1580311D03*
X81103D03*
X78522Y1570388D03*
X81468Y1570285D03*
X68133Y1587896D03*
X81006Y1593265D03*
X72660Y1587365D03*
X72375Y1604365D03*
X74133Y1610896D03*
X70567Y1625603D03*
X72255Y1616730D03*
X74134Y1621396D03*
X75380Y1627622D03*
X75764Y1636993D03*
X79164Y1636992D03*
X77427Y1644410D03*
X82127Y1687362D03*
X82500Y1698511D03*
Y1706511D03*
X82000Y1716331D03*
X82500Y1720331D03*
X82000Y1724331D03*
X94157Y75340D03*
X83157Y69340D03*
X97557Y75340D03*
X86557Y69340D03*
X92197Y143853D03*
X87137Y143663D03*
X93775Y197241D03*
Y212241D03*
Y207241D03*
Y202241D03*
X87520Y382219D03*
Y391391D03*
Y395865D03*
X90225Y610351D03*
X84057Y599372D03*
X84038Y602233D03*
X90225Y614351D03*
Y618351D03*
Y622351D03*
X94474Y766871D03*
X95790Y1278014D03*
X82953Y1307607D03*
X83023Y1311607D03*
X97546Y1385912D03*
X85736Y1391597D03*
X86827Y1404080D03*
X93000Y1417000D03*
Y1408000D03*
X93069Y1412500D03*
X85103Y1433051D03*
X93000Y1426000D03*
X97800Y1433000D03*
X93000Y1421500D03*
Y1444500D03*
Y1448500D03*
X84500Y1444500D03*
Y1448500D03*
X88722Y1476741D03*
X89092Y1491106D03*
X89042Y1488506D03*
X83991Y1491440D03*
X83892Y1488840D03*
X88722Y1479741D03*
Y1482741D03*
Y1485741D03*
X83892Y1499140D03*
X83991Y1494040D03*
Y1496540D03*
X84051Y1501690D03*
X83796Y1533746D03*
X83811Y1537296D03*
X91511Y1552296D03*
X93296Y1549142D03*
X97018Y1546331D03*
X88511Y1552296D03*
X83121Y1542294D03*
X94786Y1574205D03*
Y1576705D03*
X97486Y1574205D03*
Y1576705D03*
X83603Y1580311D03*
X84093Y1570285D03*
X90675Y1590783D03*
X96124Y1593458D03*
Y1595958D03*
X93424Y1593458D03*
X90675Y1593283D03*
X93424Y1595958D03*
X90675Y1595783D03*
X93537Y1598506D03*
X96237D03*
X90649Y1598507D03*
X84833Y1611896D03*
X90892Y1654749D03*
X85836Y1655143D03*
Y1658543D03*
X87891Y1671121D03*
Y1674521D03*
X90127Y1687362D03*
X96101Y1696469D03*
X82945Y1702511D03*
X95342Y1713741D03*
X96555Y1705508D03*
X95400Y1719741D03*
X95460Y1725241D03*
X105157Y69340D03*
X108557D03*
X101679Y151191D03*
X101675Y160694D03*
X100818Y165506D03*
Y168906D03*
X110616Y767400D03*
X110485Y771366D03*
X105165Y1300380D03*
Y1302880D03*
X107665D03*
Y1300380D03*
X102665Y1302880D03*
Y1300380D03*
X105165Y1305380D03*
X107665D03*
X102665D03*
Y1307880D03*
Y1310380D03*
Y1312880D03*
X105165Y1307880D03*
Y1310380D03*
Y1312880D03*
X107665D03*
Y1310380D03*
Y1307880D03*
X105165Y1315380D03*
X107665D03*
X105165Y1317880D03*
X107665D03*
X102665D03*
Y1315380D03*
X98101Y1369018D03*
Y1371559D03*
X104863Y1382593D03*
X99594Y1379933D03*
X104863Y1380085D03*
X112305Y1382130D03*
X108817Y1380530D03*
X111555Y1379562D03*
X101874Y1376408D03*
X111600Y1403100D03*
X113500Y1398600D03*
X110000Y1407425D03*
X110075Y1410500D03*
X101637Y1432938D03*
X102076Y1427833D03*
X101955Y1448660D03*
X101500Y1436000D03*
X102398Y1440000D03*
X113500Y1455600D03*
X112481Y1452424D03*
X112100Y1467500D03*
X103571Y1476485D03*
X103555Y1485128D03*
Y1479128D03*
Y1482128D03*
X109733Y1491367D03*
X110605Y1487896D03*
X104184Y1491292D03*
X106784D03*
X105453Y1487893D03*
X108053D03*
X102931Y1488097D03*
X101584Y1491292D03*
X106396Y1485113D03*
X108996D03*
X106371Y1482181D03*
X108971D03*
X107197Y1501756D03*
X109712Y1499196D03*
X104616Y1501811D03*
X107112Y1499196D03*
X109733Y1493967D03*
Y1496567D03*
X106784Y1493892D03*
Y1496492D03*
X101634D03*
X104512Y1499196D03*
X104184Y1496492D03*
Y1493892D03*
X101534Y1499244D03*
X101634Y1493992D03*
X101835Y1501863D03*
X109878Y1501879D03*
X102011Y1550242D03*
X99818Y1546296D03*
X111196Y1542569D03*
X111901Y1545543D03*
X112418Y1555680D03*
X112339Y1565015D03*
Y1562515D03*
X112418Y1558180D03*
X99986Y1574205D03*
Y1576705D03*
X108555Y1574657D03*
Y1577462D03*
X98824Y1593558D03*
X101524D03*
X98824Y1596058D03*
X101524D03*
X101637Y1598606D03*
X98937D03*
X112353Y1646612D03*
X110378Y1670313D03*
X99443Y1661931D03*
Y1658531D03*
X110378Y1674313D03*
X100443Y1684063D03*
Y1687463D03*
X107500Y1707450D03*
X116157Y75340D03*
X127153Y69343D03*
X119557Y75340D03*
X115016Y300281D03*
Y320715D03*
X118407Y526766D03*
X113042Y686285D03*
X113980Y717480D03*
X116480D03*
X118980D03*
X121480D03*
X123980D03*
X113980Y714980D03*
X116480D03*
X118980D03*
X121480D03*
X123980D03*
X116480Y722480D03*
X118980D03*
X121480D03*
X123980D03*
X113980Y719980D03*
X116480D03*
X118980D03*
X121480D03*
X123980D03*
X113980Y722480D03*
X124174Y766871D03*
X120965Y1307880D03*
Y1310380D03*
Y1312880D03*
X118465D03*
Y1310380D03*
Y1307880D03*
Y1300380D03*
X123465Y1302880D03*
Y1300380D03*
X120965Y1305380D03*
X118465D03*
X123465D03*
Y1307880D03*
Y1310380D03*
Y1312880D03*
X120965Y1300380D03*
Y1302880D03*
X118465D03*
X120965Y1315380D03*
X118465D03*
X120965Y1317880D03*
X118465D03*
X123465D03*
Y1315380D03*
X121207Y1363643D03*
X115321Y1372872D03*
X120181D03*
X117751D03*
X121241Y1367047D03*
Y1369947D03*
X127211Y1373177D03*
Y1378977D03*
X125111Y1377577D03*
X122945Y1379207D03*
X127211Y1376077D03*
X125011Y1374577D03*
X122945Y1376307D03*
X122050Y1403750D03*
X129200Y1401000D03*
X124700D03*
X126000Y1414000D03*
Y1418000D03*
X116700Y1415700D03*
Y1410500D03*
X120700Y1408100D03*
X116900Y1449000D03*
X113600Y1449100D03*
X116122Y1458000D03*
X119100Y1460300D03*
X124600Y1465100D03*
X121500Y1467400D03*
X113100Y1537346D03*
X114030Y1542419D03*
X114610Y1545543D03*
X121705Y1619460D03*
X114618Y1624541D03*
X117655Y1621766D03*
X118956Y1635244D03*
X124312Y1633488D03*
X126717Y1635893D03*
X126428Y1658587D03*
X126760Y1682383D03*
X123353Y1695941D03*
X127353Y1696062D03*
X127710Y1700166D03*
X127290Y1705666D03*
X125183Y1716741D03*
X127168Y1721695D03*
X129020Y1726741D03*
X138157Y75340D03*
X141557D03*
X130553Y69343D03*
X140360Y430160D03*
X141642Y488684D03*
Y494147D03*
X139980Y507420D03*
X139890Y503440D03*
X140471Y670445D03*
X131752Y668506D03*
X134902D03*
X140600Y683029D03*
X131752Y686074D03*
X134902D03*
X131960Y679290D03*
X140317Y767400D03*
Y771200D03*
X140265Y1307880D03*
Y1310380D03*
Y1312880D03*
X137765D03*
Y1310380D03*
Y1307880D03*
X135265Y1312880D03*
Y1310380D03*
Y1307880D03*
Y1305380D03*
X140265D03*
X137765D03*
X135265Y1300380D03*
Y1302880D03*
X140265Y1300380D03*
Y1302880D03*
X137765D03*
Y1300380D03*
X140265Y1315380D03*
X137765D03*
X135265D03*
Y1317880D03*
X140265D03*
X137765D03*
X130701Y1369018D03*
Y1371559D03*
X137463Y1382593D03*
X132194Y1379933D03*
X137463Y1380085D03*
X141417Y1380530D03*
X134474Y1376408D03*
X138000Y1400600D03*
X134800Y1408100D03*
X142000Y1414500D03*
X136000Y1432000D03*
X141500Y1433500D03*
Y1429500D03*
X139500Y1446000D03*
X133100Y1444100D03*
X138013Y1440487D03*
X141514Y1436500D03*
X128661Y1464000D03*
X139802Y1556133D03*
X129070Y1608338D03*
X137386Y1626412D03*
X135543Y1637055D03*
X132353Y1646612D03*
X136353D03*
X142465Y1662493D03*
X143000Y1701011D03*
X142293Y1705166D03*
X129493Y1711846D03*
X143000Y1709166D03*
X135722Y1715672D03*
X147920Y28261D03*
X148780Y48720D03*
X149153Y69343D03*
X152553D03*
X149231Y224204D03*
X148228Y216118D03*
X158380Y419760D03*
X147450Y423860D03*
X154770Y441830D03*
X147810Y475710D03*
X146982Y521997D03*
Y530997D03*
X159513Y674855D03*
X152822Y665500D03*
X153875Y766871D03*
X151065Y1307880D03*
Y1310380D03*
Y1312880D03*
X153565D03*
Y1310380D03*
Y1307880D03*
X156065Y1312880D03*
Y1310380D03*
Y1307880D03*
Y1305380D03*
X151065D03*
X153565D03*
X156065Y1300380D03*
Y1302880D03*
X151065Y1300380D03*
Y1302880D03*
X153565D03*
Y1300380D03*
X151065Y1315380D03*
X153565D03*
X156065D03*
Y1317880D03*
X151065D03*
X153565D03*
X152781Y1372872D03*
X150351D03*
X147921D03*
X153741Y1369977D03*
Y1367077D03*
X144905Y1382130D03*
X144155Y1379562D03*
X155545Y1379207D03*
Y1376307D03*
X145000Y1414425D03*
X150900Y1425500D03*
X154443Y1441195D03*
X156174Y1435396D03*
X156477Y1447733D03*
X154083Y1456007D03*
X148340Y1454674D03*
X154671Y1450019D03*
X154305Y1453101D03*
X159000Y1525480D03*
X155618Y1549331D03*
X155071Y1543604D03*
X152843Y1559146D03*
Y1562666D03*
X154945Y1624350D03*
X146453Y1614879D03*
X149171Y1616759D03*
X154945Y1627750D03*
X142576Y1640163D03*
X152353Y1646612D03*
X142576Y1643563D03*
X154111Y1663933D03*
X154010Y1676811D03*
X157410D03*
X143778Y1685087D03*
X147253Y1696343D03*
X155353Y1687843D03*
X159427Y1696652D03*
X152605Y1715941D03*
X149338Y1705603D03*
X156825Y1705510D03*
X146000Y1718241D03*
X146086Y1705603D03*
X145267Y1722241D03*
X152496Y1722941D03*
X146483Y1725636D03*
X155260Y1723682D03*
X161361Y75340D03*
X164761D03*
X162830Y396930D03*
X172120Y412350D03*
X172010Y474900D03*
X166760Y506880D03*
X166670Y502900D03*
X163372Y670863D03*
X172725Y667898D03*
X162482Y679319D03*
X161735Y684456D03*
X172725Y679230D03*
X169987Y767666D03*
Y771266D03*
X170265Y1312880D03*
Y1310380D03*
Y1307880D03*
X167765Y1312880D03*
Y1310380D03*
Y1307880D03*
Y1305380D03*
X170265D03*
X167765Y1300380D03*
Y1302880D03*
X170265D03*
Y1300380D03*
Y1315380D03*
X167765D03*
Y1317880D03*
X170265D03*
X163401Y1369018D03*
Y1371559D03*
X159811Y1373177D03*
X170163Y1382593D03*
X164894Y1379933D03*
X170163Y1380085D03*
X167174Y1376408D03*
X159811Y1378977D03*
Y1376077D03*
X157711Y1377577D03*
X157611Y1374577D03*
X163099Y1414400D03*
X162873Y1411611D03*
X163061Y1409048D03*
Y1406548D03*
X160684Y1441046D03*
X158704Y1439411D03*
X161210Y1443542D03*
X163271Y1441588D03*
X163148Y1474504D03*
X172180Y1490210D03*
X172070Y1495550D03*
X163460Y1491010D03*
X163320Y1494340D03*
X161188Y1510800D03*
X162188Y1518040D03*
X162531Y1523331D03*
Y1526731D03*
X167666Y1550751D03*
X165166D03*
X162666D03*
X170166D03*
X170230Y1542960D03*
X160150Y1553251D03*
Y1555751D03*
X162666D03*
X165166D03*
X167666D03*
X170166D03*
Y1553251D03*
X167666D03*
X165166D03*
X162666D03*
X170166Y1567621D03*
X167666D03*
X165166D03*
X162666D03*
X170166Y1565121D03*
X167666D03*
X165166D03*
X162666D03*
Y1562621D03*
X165166D03*
X167666D03*
X170166D03*
X162466Y1570121D03*
X164966D03*
X167466D03*
X169966D03*
X163735Y1635369D03*
Y1631969D03*
X157511Y1663933D03*
X165491Y1665582D03*
Y1662182D03*
X165336Y1675077D03*
Y1678477D03*
X162740Y1713172D03*
Y1704885D03*
X166467Y1720973D03*
X171925Y1717984D03*
X171945Y1730693D03*
X162740Y1723886D03*
X183357Y75343D03*
X172361Y69340D03*
X186757Y75343D03*
X175761Y69340D03*
X184930Y125502D03*
X181025Y159123D03*
X183890Y388180D03*
X174320Y395040D03*
X189290Y396730D03*
X177675Y419260D03*
X185160Y419220D03*
X181550Y441290D03*
X182500Y672500D03*
X172500Y684799D03*
X183576Y766871D03*
X183565Y1310380D03*
Y1312880D03*
X186065D03*
Y1310380D03*
Y1307880D03*
X172765D03*
Y1310380D03*
Y1312880D03*
X183565Y1307880D03*
Y1305380D03*
X186065D03*
X183565Y1300380D03*
Y1302880D03*
X186065D03*
Y1300380D03*
X172765Y1305380D03*
Y1300380D03*
Y1302880D03*
Y1315380D03*
X183565D03*
X186065D03*
X183565Y1317880D03*
X186065D03*
X172765D03*
X185481Y1372872D03*
X183051D03*
X180621D03*
X186481Y1370147D03*
Y1367247D03*
X177605Y1382130D03*
X174117Y1380530D03*
X176855Y1379562D03*
X185558Y1418560D03*
Y1416060D03*
X183058Y1418560D03*
Y1416060D03*
X173164Y1406397D03*
Y1408897D03*
X172976Y1411460D03*
X173202Y1414249D03*
X185558Y1421060D03*
Y1423560D03*
Y1426060D03*
X183058Y1421060D03*
Y1426060D03*
Y1423560D03*
Y1428560D03*
X185558D03*
X173490Y1542540D03*
X173050Y1555751D03*
Y1553251D03*
X178582Y1575390D03*
X181087Y1576135D03*
X178582Y1572490D03*
Y1569590D03*
X180292Y1582589D03*
X177792D03*
X177509Y1653825D03*
X177666Y1649223D03*
X183974Y1656804D03*
X183920Y1653973D03*
X184139Y1651088D03*
X180103Y1668921D03*
X177672Y1657538D03*
X183986Y1659548D03*
X182533Y1676854D03*
X185124Y1701851D03*
X185084Y1691988D03*
X179999Y1699156D03*
X185173Y1695138D03*
X178385Y1715441D03*
X183813Y1705404D03*
X178376Y1720559D03*
X185760Y1731666D03*
X194361Y69340D03*
X197761D03*
X204088Y138912D03*
X200577Y125502D03*
X190000Y143000D03*
X191264Y147768D03*
X193610Y153951D03*
X192592Y353072D03*
X188055Y731734D03*
X199718Y767400D03*
X197651Y769241D03*
X200365Y1312880D03*
Y1310380D03*
Y1307880D03*
Y1305380D03*
Y1300380D03*
Y1302880D03*
X188565Y1312880D03*
Y1310380D03*
Y1307880D03*
Y1305380D03*
Y1300380D03*
Y1302880D03*
X200365Y1315380D03*
Y1317880D03*
X188565Y1315380D03*
Y1317880D03*
X196301Y1369018D03*
Y1371559D03*
X192511Y1373177D03*
X197794Y1379933D03*
X200074Y1376408D03*
X188245Y1379207D03*
X190411Y1377577D03*
X192511Y1378977D03*
X190311Y1374577D03*
X188245Y1376307D03*
X192511Y1376077D03*
X200408Y1416249D03*
Y1418749D03*
X192983Y1417568D03*
X188058Y1416060D03*
Y1418560D03*
X190483Y1417568D03*
X197983D03*
X195483D03*
X188695Y1404813D03*
Y1407313D03*
X191995Y1404813D03*
Y1407313D03*
X194495Y1404813D03*
Y1407313D03*
X196995Y1404813D03*
Y1407313D03*
X199495Y1404813D03*
Y1407313D03*
X188507Y1409876D03*
X191807D03*
X194307D03*
X196807D03*
X199307D03*
X200558Y1421551D03*
X195483Y1420068D03*
X192983D03*
X195483Y1422568D03*
X197983D03*
X192983D03*
X188058Y1421060D03*
Y1423560D03*
X190483Y1420068D03*
Y1422568D03*
X197983Y1420068D03*
X188058Y1426060D03*
X193679Y1640052D03*
Y1643452D03*
X198698Y1662215D03*
X199747Y1675603D03*
X200424Y1686870D03*
X197780Y1696973D03*
X200478Y1701758D03*
X200448Y1690771D03*
X202076Y1717845D03*
X189760Y1713061D03*
X193274Y1709769D03*
X199843Y1709837D03*
X203510Y1712441D03*
X196763Y1710444D03*
X189760Y1723041D03*
Y1731564D03*
X194000Y1720551D03*
X203655Y1723000D03*
X198760Y1719991D03*
X216491Y69343D03*
X205495Y75340D03*
X208895D03*
X217687Y522453D03*
X214999Y585668D03*
X211254Y595145D03*
X208254D03*
X211009Y610001D03*
X208009D03*
X214202Y606943D03*
X208254Y603245D03*
X211254D03*
X214202Y609681D03*
X208326Y606918D03*
X211326D03*
X210199Y714074D03*
X206199D03*
X206254Y732537D03*
X206933Y737277D03*
X208818Y766871D03*
X205365Y1307880D03*
Y1310380D03*
Y1312880D03*
X202865D03*
Y1310380D03*
Y1307880D03*
X216165D03*
Y1310380D03*
Y1312880D03*
Y1305380D03*
Y1300380D03*
Y1302880D03*
X205365Y1305380D03*
X202865D03*
X205365Y1300380D03*
Y1302880D03*
X202865D03*
Y1300380D03*
X205365Y1315380D03*
X202865D03*
X216165D03*
Y1317880D03*
X205365D03*
X202865D03*
X213521Y1372872D03*
X215951D03*
X203063Y1382593D03*
Y1380085D03*
X210505Y1382130D03*
X207017Y1380530D03*
X209755Y1379562D03*
X205558Y1418560D03*
Y1416060D03*
X202945Y1415910D03*
Y1418410D03*
X208058Y1416060D03*
X208061Y1418605D03*
X205479Y1652130D03*
Y1648730D03*
X206788Y1660960D03*
X210833Y1660867D03*
X210217Y1668603D03*
X207807Y1681302D03*
Y1696409D03*
X211862Y1701100D03*
X212365Y1705403D03*
X211000Y1717675D03*
X229131Y26477D03*
X225731D03*
X229127Y50649D03*
X225727D03*
X227495Y75340D03*
X230895D03*
X219891Y69343D03*
X233284Y137195D03*
X221051Y153167D03*
X223687Y522453D03*
X229687D03*
X226599Y570970D03*
X217999Y585668D03*
X223999D03*
X220999D03*
X217202Y606943D03*
X220202D03*
X223202D03*
X223111Y603782D03*
X225895Y609691D03*
X228895D03*
X220111Y603782D03*
X217202Y609681D03*
X220202D03*
X223202D03*
X218024Y622385D03*
X221024D03*
X224024D03*
X227024D03*
X221024Y632385D03*
X218024D03*
X224024D03*
X227024D03*
X224157Y715915D03*
Y712915D03*
X229263Y765863D03*
X229275Y769292D03*
X218665Y1312880D03*
Y1310380D03*
Y1307880D03*
X221165Y1312880D03*
Y1310380D03*
Y1307880D03*
Y1305380D03*
X218665D03*
X221165Y1300380D03*
Y1302880D03*
X218665D03*
Y1300380D03*
Y1315380D03*
X221165D03*
Y1317880D03*
X218665D03*
X229101Y1369018D03*
Y1371559D03*
X218381Y1372872D03*
X219401Y1370067D03*
Y1367167D03*
X225411Y1373177D03*
X230594Y1379933D03*
X225411Y1378977D03*
Y1376077D03*
X221145Y1379207D03*
X223311Y1377577D03*
X223211Y1374577D03*
X221145Y1376307D03*
X238059Y26235D03*
X233335Y17665D03*
X235697Y21585D03*
X241306Y20325D03*
X246356Y26855D03*
X246506Y20365D03*
X242216Y39365D03*
X246216D03*
X238059Y37165D03*
X235697Y39755D03*
X248816Y48965D03*
X239816Y54365D03*
X248487Y68690D03*
X242920Y67915D03*
X238846Y72977D03*
X235186Y98067D03*
X234331Y103286D03*
X232529Y114830D03*
X238297Y121555D03*
X244818Y111546D03*
Y115546D03*
X235460Y115790D03*
X235186Y112022D03*
X238600Y130400D03*
X235147Y124435D03*
X243813Y132383D03*
X241271Y130719D03*
X234000Y148000D03*
X239988Y141986D03*
X236104Y151996D03*
X245486Y159705D03*
X234628Y166735D03*
X240413Y360867D03*
X233413D03*
X235913D03*
X243845Y656940D03*
X246045Y655540D03*
X243845Y651140D03*
Y654040D03*
X245945Y652540D03*
X232981Y743983D03*
X240200Y766300D03*
X246371Y772388D03*
X232965Y1297880D03*
X237965D03*
X235465D03*
Y1300380D03*
Y1302880D03*
X237965D03*
Y1300380D03*
X235465Y1305380D03*
X237965D03*
X232965Y1302880D03*
Y1300380D03*
Y1305380D03*
Y1307880D03*
Y1310380D03*
Y1312880D03*
X237965Y1307880D03*
Y1310380D03*
Y1312880D03*
X235465D03*
Y1310380D03*
Y1307880D03*
X237965Y1315380D03*
X235465D03*
X232965D03*
X246321Y1372872D03*
X235863Y1380085D03*
X243305Y1382130D03*
X239817Y1380530D03*
X242555Y1379562D03*
X235863Y1382593D03*
X232874Y1376408D03*
X255106Y16615D03*
X251106Y12615D03*
X250216Y39365D03*
X254046Y39425D03*
X259316Y48965D03*
X261016Y51565D03*
X252316Y48965D03*
X255816D03*
X254016Y51565D03*
X250516D03*
X257516D03*
X247893Y100546D03*
X248093Y92146D03*
X261416Y100665D03*
X253874Y111774D03*
X252800Y114800D03*
X256586Y138373D03*
X260596Y151065D03*
X248350Y165700D03*
X257252Y156730D03*
X258439Y214000D03*
X247859Y375389D03*
X250359D03*
X254859D03*
X247694Y378523D03*
X250194D03*
X254694D03*
X258751Y647987D03*
X262239Y649587D03*
X259501Y650555D03*
X255735Y657245D03*
X253305D03*
X250875D03*
X248111Y653810D03*
Y650910D03*
X250312Y663080D03*
Y660180D03*
X247587Y714760D03*
Y717260D03*
X252591Y714737D03*
Y717237D03*
X250091D03*
Y714737D03*
X247587Y712237D03*
X250087D03*
X252587D03*
X247587Y719760D03*
X252591Y719737D03*
X250091D03*
X247587Y724760D03*
X252587D03*
X250087D03*
X247587Y722260D03*
Y727260D03*
X250087Y729760D03*
X247587D03*
X250087Y727260D03*
X252587D03*
Y729760D03*
X252591Y722237D03*
X250091D03*
X254671Y776388D03*
X257071Y772770D03*
X260971Y777988D03*
X248765Y1297880D03*
X251265D03*
X248765Y1292880D03*
Y1295380D03*
X251265D03*
Y1292880D03*
X248765Y1307880D03*
Y1310380D03*
Y1312880D03*
X251265D03*
Y1310380D03*
Y1307880D03*
X248765Y1305380D03*
X251265D03*
X248765Y1300380D03*
Y1302880D03*
X251265D03*
Y1300380D03*
X248765Y1315380D03*
X251265D03*
Y1317880D03*
X248765D03*
X248751Y1372872D03*
X251181D03*
X252211Y1370232D03*
Y1367332D03*
X258211Y1373177D03*
X256111Y1377577D03*
X258211Y1378977D03*
X256011Y1374577D03*
X258211Y1376077D03*
X253945Y1379207D03*
Y1376307D03*
X261530Y1550300D03*
X275116Y28565D03*
X275896Y48875D03*
X266420Y39120D03*
X265365Y49171D03*
X263516Y51565D03*
X261816Y48965D03*
X263182Y73396D03*
X269860Y72741D03*
X262893Y77529D03*
Y80029D03*
X263316Y87665D03*
X275238Y83024D03*
X264916Y100665D03*
X268416D03*
X262916Y97965D03*
X266416D03*
X269916D03*
X273616Y96665D03*
X264293Y120972D03*
X269487Y121095D03*
X275793Y120248D03*
X266000Y125800D03*
X275793Y129595D03*
X266971Y140110D03*
X264574Y151206D03*
X276821Y140465D03*
X270178Y140322D03*
X262500Y161100D03*
X273500Y207500D03*
X266360Y203070D03*
X269925Y217700D03*
X274993Y522052D03*
X269568Y522366D03*
X266327Y522456D03*
X274096Y574698D03*
X273208Y588237D03*
X267601Y608378D03*
X271462Y650184D03*
X266193Y650032D03*
X272955Y658558D03*
X266193Y647524D03*
X269182Y653709D03*
X272955Y661099D03*
X276575Y685381D03*
Y688281D03*
Y691181D03*
X265891Y714737D03*
Y717237D03*
X263391D03*
Y714737D03*
X263387Y712237D03*
X265887D03*
X265891Y719737D03*
X263391D03*
X265787Y724760D03*
X263287D03*
X265787Y727260D03*
X263287D03*
X265787Y729760D03*
X263287D03*
X265787Y732260D03*
X263287D03*
X265891Y722237D03*
X263391D03*
X265787Y737260D03*
X263287D03*
X265787Y734760D03*
X263287D03*
X271161Y780588D03*
X268991Y783248D03*
X271245Y785474D03*
X274282Y786741D03*
X272054Y801112D03*
X270850Y797605D03*
X272165Y1256716D03*
X269665Y1259216D03*
X272165D03*
X269765Y1269234D03*
X272265D03*
X269765Y1261734D03*
Y1264234D03*
Y1266734D03*
X272265D03*
Y1264234D03*
Y1261734D03*
X267179Y1269273D03*
Y1266773D03*
Y1264273D03*
Y1261773D03*
Y1271773D03*
X269679D03*
X272179D03*
X262701Y1322872D03*
Y1325413D03*
X264194Y1333787D03*
X269463Y1333939D03*
X273417Y1334384D03*
X276155Y1333416D03*
X269463Y1336447D03*
X266474Y1330262D03*
X269829Y1521436D03*
X273597Y1519845D03*
X269144Y1511953D03*
X273474Y1516120D03*
Y1512220D03*
X269144Y1514453D03*
Y1516953D03*
X267322Y1519250D03*
X276624Y1516120D03*
Y1512220D03*
X276637Y1521436D03*
X274546Y1549295D03*
Y1546795D03*
X267297Y1546119D03*
X286996Y20365D03*
X290795Y28365D03*
X284228Y25935D03*
X280828D03*
X282716Y40020D03*
X290716D03*
X287988Y54893D03*
X291379Y55746D03*
X293157Y50525D03*
X284226Y50649D03*
X280826D03*
X278638Y83024D03*
X288553Y105006D03*
X285353D03*
X280853Y109906D03*
X282853Y115606D03*
X285853D03*
X280853Y107306D03*
X286996Y139865D03*
X283049Y139731D03*
X288000Y209000D03*
X290000Y222575D03*
X289163Y212503D03*
X278425Y230925D03*
X289393Y498960D03*
X278547Y523041D03*
X284018Y522300D03*
X287723Y548499D03*
X289421Y575098D03*
X291481Y682228D03*
X280841Y688051D03*
X278675Y686781D03*
X280841Y685151D03*
X288465Y691493D03*
X283605D03*
X286035D03*
X278775Y689781D03*
X283042Y697280D03*
Y694380D03*
X285317Y746478D03*
X282817D03*
X280317D03*
Y759110D03*
X285317D03*
X282817D03*
X285317Y761610D03*
X285321Y748978D03*
Y751478D03*
Y753978D03*
X282821D03*
Y751478D03*
Y748978D03*
X285321Y756478D03*
X282821D03*
X280317Y756610D03*
Y751610D03*
Y754110D03*
Y749110D03*
Y761610D03*
X282817D03*
X284035Y796850D03*
X285258Y799314D03*
X282323Y794867D03*
X281449Y809609D03*
X283987Y811342D03*
X285565Y1246716D03*
X288065D03*
X283065D03*
X288065Y1251716D03*
X285565D03*
X283065D03*
X288065Y1249216D03*
X285565D03*
X283065D03*
Y1254216D03*
X288065D03*
X285565D03*
X283065Y1269234D03*
X285565D03*
X283065Y1261734D03*
Y1264234D03*
Y1266734D03*
X285565D03*
Y1264234D03*
Y1261734D03*
X283065Y1256716D03*
X285565D03*
X288065D03*
X283065Y1259216D03*
X285565D03*
X288065D03*
Y1266716D03*
Y1264216D03*
Y1261716D03*
Y1269216D03*
X285479Y1271773D03*
X282979D03*
X287979D03*
X284781Y1326726D03*
X282351D03*
X279921D03*
X285891Y1320942D03*
Y1323842D03*
X289611Y1328431D03*
X276905Y1335984D03*
X289711Y1331431D03*
X287545Y1330161D03*
Y1333061D03*
X280088Y1509469D03*
X282588D03*
X279774Y1512220D03*
Y1516120D03*
X284024Y1514576D03*
X279499Y1519845D03*
X284024Y1512076D03*
X290593Y1523331D03*
Y1526731D03*
X291416Y1541795D03*
Y1549295D03*
Y1546795D03*
Y1544295D03*
X285586Y1551844D03*
X288004Y1551099D03*
X290509Y1551844D03*
X288004Y1548199D03*
X284014Y1538682D03*
X286514D03*
X284546Y1549295D03*
Y1546795D03*
Y1541795D03*
Y1544295D03*
X287046D03*
Y1541795D03*
X277046Y1546795D03*
Y1549295D03*
X282046D03*
Y1546795D03*
Y1544295D03*
X279546Y1549295D03*
Y1546795D03*
X282046Y1541795D03*
X300230Y14820D03*
X302606Y26365D03*
X292056Y24475D03*
X295516Y26365D03*
X300244Y28365D03*
X299496Y22865D03*
X304923Y24657D03*
X304968Y28365D03*
X303252Y38199D03*
X298716Y40020D03*
X296337Y55855D03*
X301306Y52485D03*
X298542Y51088D03*
X303711Y50860D03*
X295755Y72800D03*
X301107Y75676D03*
X305820Y73693D03*
X303852Y65042D03*
X306470Y65160D03*
X301780Y82900D03*
X299002Y88700D03*
X307816Y95727D03*
X301179Y112806D03*
Y110006D03*
Y107106D03*
X296478Y149203D03*
X296474Y158706D03*
X292811Y213242D03*
X296283Y242391D03*
X306528Y256528D03*
X297815Y580384D03*
X294299Y577188D03*
X302130Y584160D03*
X304192Y684425D03*
X298923Y684273D03*
X294969Y683828D03*
X292231Y684796D03*
X298923Y681765D03*
X301912Y687950D03*
X305685Y695340D03*
Y692799D03*
X298617Y746478D03*
X296117D03*
X301117D03*
X298621Y753978D03*
X296121D03*
Y751478D03*
Y748978D03*
X298621Y756478D03*
X296121D03*
X301121Y748996D03*
Y751496D03*
Y753996D03*
Y756496D03*
X296117Y759110D03*
Y761610D03*
X301117Y759110D03*
X298617D03*
X301117Y761610D03*
X298617D03*
X298621Y748978D03*
Y751478D03*
X301117Y766610D03*
X296117D03*
Y764110D03*
X301117Y771610D03*
X298617D03*
Y769110D03*
X301117D03*
X296117Y771610D03*
Y769110D03*
X298617Y766610D03*
Y764110D03*
X301117D03*
X305061Y1254131D03*
X300061D03*
X302561D03*
X305061Y1249131D03*
Y1251631D03*
X300061D03*
X302561D03*
X300061Y1249131D03*
X302561D03*
X305061Y1246631D03*
X300061D03*
X302561D03*
X302661Y1269149D03*
X305161D03*
X302661Y1261649D03*
Y1264149D03*
Y1266649D03*
X305161D03*
Y1264149D03*
Y1261649D03*
X300061Y1269131D03*
Y1266631D03*
X305061Y1259131D03*
Y1256631D03*
X300061D03*
Y1259131D03*
Y1261631D03*
Y1264131D03*
X302561Y1256631D03*
Y1259131D03*
X305075Y1271688D03*
X302575D03*
X300075D03*
X295597Y1322844D03*
Y1325385D03*
X291811Y1327031D03*
X297090Y1333759D03*
X302359Y1333911D03*
X306313Y1334356D03*
X302359Y1336419D03*
X299370Y1330234D03*
X291811Y1332831D03*
Y1329931D03*
X294725Y1381612D03*
X294533Y1384401D03*
X305204Y1381461D03*
X305012Y1384250D03*
X294684Y1387040D03*
X305163Y1386889D03*
X294683Y1390281D03*
X305163Y1389678D03*
X295042Y1530596D03*
X296416Y1549295D03*
X293916D03*
Y1546795D03*
X296416D03*
Y1544295D03*
X293916D03*
X296416Y1541795D03*
X293916D03*
X298916D03*
Y1549295D03*
Y1546795D03*
Y1544295D03*
X303041Y1544299D03*
X297323Y1657172D03*
Y1653772D03*
X310396Y50365D03*
X306566Y50225D03*
X323036Y73125D03*
X310455Y75895D03*
X320190Y77648D03*
X314653Y71806D03*
Y68906D03*
X312410Y89060D03*
X322871Y84321D03*
X316982Y89003D03*
X311053Y112806D03*
Y110006D03*
Y107106D03*
X323646Y147120D03*
Y152120D03*
X308240Y148100D03*
X317472Y222262D03*
Y225217D03*
X319970Y228167D03*
X320095Y231810D03*
X319075Y260075D03*
X311749Y440921D03*
X314780Y545716D03*
X322955Y556148D03*
X310445Y700931D03*
X312611Y702301D03*
X321235Y711636D03*
X316375D03*
X318805D03*
X311545Y709931D03*
X310445Y703931D03*
X311445Y706931D03*
X313611Y708201D03*
Y705301D03*
X315912Y717400D03*
Y714500D03*
X313087Y769160D03*
Y771660D03*
Y774160D03*
Y776660D03*
X318091Y769128D03*
Y771628D03*
Y774128D03*
X315591D03*
Y771628D03*
Y769128D03*
X318091Y776628D03*
X315591D03*
X313087Y766628D03*
X315587D03*
X318087D03*
Y791660D03*
X313087D03*
X315587D03*
X318087Y789160D03*
X313087D03*
X315587D03*
Y779160D03*
X313087Y784160D03*
X315587D03*
X313087Y786660D03*
X315587D03*
X313087Y781660D03*
X315587D03*
X313087Y779160D03*
X318087Y786660D03*
Y784160D03*
Y779160D03*
Y781660D03*
X313284Y1218522D03*
Y1215122D03*
X318461Y1254131D03*
X320961D03*
X315961D03*
Y1249131D03*
X318461D03*
X320961D03*
X315961Y1251631D03*
X318461D03*
X320961D03*
X315961Y1246631D03*
X318461D03*
X320961D03*
X315961Y1269149D03*
X318461D03*
X315961Y1261649D03*
Y1264149D03*
Y1266649D03*
X318461D03*
Y1264149D03*
Y1261649D03*
X320961Y1269131D03*
Y1256631D03*
Y1259131D03*
Y1261631D03*
X318461Y1256631D03*
Y1259131D03*
X320961Y1264131D03*
Y1266631D03*
X315961Y1256631D03*
Y1259131D03*
X320875Y1271688D03*
X315875D03*
X318375D03*
X312817Y1326698D03*
X315247D03*
X317677D03*
X318811Y1320902D03*
Y1323802D03*
X309801Y1335956D03*
X309051Y1333388D03*
X320441Y1330133D03*
Y1333033D03*
X307255Y1643750D03*
Y1647150D03*
X323113Y76941D03*
X334339Y162580D03*
X323646Y160120D03*
Y156120D03*
X331780Y182900D03*
X336000Y284000D03*
X324406Y367744D03*
X325816Y543012D03*
X324647Y566086D03*
X334031Y613498D03*
Y610498D03*
X331391D03*
Y613498D03*
X333502Y600019D03*
Y603019D03*
X330109Y602883D03*
Y605883D03*
X334031Y619398D03*
Y616498D03*
X331391D03*
Y619398D03*
X324251Y702378D03*
X331693Y701915D03*
Y704423D03*
X327739Y703978D03*
X325001Y704946D03*
X334682Y708100D03*
X331391Y769128D03*
Y771628D03*
Y774128D03*
X328891D03*
Y771628D03*
Y769128D03*
X331391Y776628D03*
X328891D03*
X333887Y766628D03*
X328887D03*
X331387D03*
X333891Y776646D03*
Y774146D03*
Y771646D03*
Y769146D03*
X333887Y791660D03*
X328887D03*
X331387D03*
X333887Y789160D03*
X328887D03*
X331387D03*
X333887Y779160D03*
Y781660D03*
X331387Y779160D03*
X328887D03*
Y781660D03*
X331387D03*
X333887Y786660D03*
X328887D03*
X331387D03*
X333887Y784160D03*
X328887D03*
X331387D03*
X335465Y1246631D03*
X332965D03*
X335465Y1249131D03*
X332965D03*
X335465Y1251631D03*
X332965D03*
X335465Y1254131D03*
X332965D03*
X335465Y1259131D03*
Y1256631D03*
X332965Y1259131D03*
Y1256631D03*
X335565Y1269149D03*
Y1261649D03*
Y1264149D03*
Y1266649D03*
X332961Y1269188D03*
Y1266688D03*
Y1261688D03*
Y1264188D03*
Y1271688D03*
X335461D03*
X328501Y1322787D03*
Y1325328D03*
X324707Y1327003D03*
X322507Y1328403D03*
X329994Y1333702D03*
X335263Y1333854D03*
Y1336362D03*
X332274Y1330177D03*
X324707Y1332803D03*
X322607Y1331403D03*
X324707Y1329903D03*
X334038Y1373469D03*
X334230Y1370680D03*
X323559Y1373620D03*
X323751Y1370831D03*
X334189Y1376108D03*
X323710Y1376259D03*
X334189Y1378897D03*
X323709Y1379500D03*
X341082Y56308D03*
X340436Y120555D03*
X343446Y131170D03*
X338244Y192264D03*
X344984Y199299D03*
X344106Y222659D03*
X348107Y220420D03*
X341895Y233980D03*
X348645Y229180D03*
X352000Y230643D03*
Y235643D03*
X344034Y282609D03*
X348890Y409120D03*
Y411620D03*
X340337Y496462D03*
X346751Y515376D03*
X351157Y550415D03*
X350566Y541882D03*
X351018Y554896D03*
X351157Y566936D03*
X345521Y564388D03*
X349397Y564459D03*
X351157Y570415D03*
X341500Y574500D03*
X342500Y582500D03*
Y578500D03*
X338420Y574500D03*
X351157Y590415D03*
Y586415D03*
X337031Y607498D03*
Y613498D03*
Y610498D03*
X346031Y607498D03*
X343031D03*
X349031D03*
X346031Y610498D03*
X343031D03*
X349031D03*
X340031Y607498D03*
Y610498D03*
Y613498D03*
X346031Y604498D03*
X343031D03*
X349031D03*
X340031D03*
X343691Y614018D03*
X346191D03*
X348691D03*
X343721Y618348D03*
X346221D03*
X348721D03*
X351191Y614018D03*
X351221Y618348D03*
X340031Y619398D03*
Y616498D03*
X337031Y619398D03*
Y616498D03*
X342675Y640994D03*
X345175D03*
X347675D03*
X350175D03*
X342675Y643494D03*
X345175D03*
X347675D03*
X350175D03*
X342595Y646054D03*
X345095D03*
X347595D03*
X350095D03*
X336962Y704575D03*
X338455Y715490D03*
Y712949D03*
X349435Y711368D03*
X346671Y705033D03*
X344505Y706663D03*
X346671Y707933D03*
X344605Y709663D03*
X342405Y705263D03*
Y708163D03*
Y711063D03*
X348395Y717060D03*
Y714160D03*
X346051Y769058D03*
Y771558D03*
Y774058D03*
Y776558D03*
X351151Y769040D03*
Y771540D03*
Y774040D03*
X348651D03*
Y771540D03*
Y769040D03*
X351151Y776540D03*
X348651D03*
X351147Y766540D03*
X348647D03*
X346147D03*
X346051Y791558D03*
X348551D03*
X351051D03*
X346051Y789058D03*
X348551D03*
X346051Y784058D03*
X348551D03*
X346051Y786558D03*
X348551D03*
X346051Y779058D03*
X348551D03*
X346051Y781558D03*
X348551D03*
X351051Y789058D03*
Y784058D03*
Y786558D03*
Y779058D03*
Y781558D03*
X347107Y1174343D03*
X339278Y1192112D03*
X336778D03*
X347885Y1206426D03*
X339532Y1218605D03*
X349938Y1214563D03*
X337965Y1251631D03*
Y1249131D03*
Y1254131D03*
X348865Y1246631D03*
Y1251631D03*
Y1249131D03*
Y1254131D03*
X337965Y1246631D03*
X348865Y1269149D03*
Y1261649D03*
Y1264149D03*
Y1266649D03*
X338065Y1269149D03*
Y1266649D03*
Y1264149D03*
Y1261649D03*
X337965Y1256631D03*
Y1259131D03*
X348865D03*
Y1256631D03*
X337961Y1271688D03*
X348861D03*
X348151Y1326641D03*
X350581D03*
X345721D03*
X342705Y1335899D03*
X339217Y1334299D03*
X341955Y1333331D03*
X346464Y1380102D03*
X343964D03*
X348964D03*
Y1387602D03*
Y1385102D03*
Y1382602D03*
X343964Y1385102D03*
Y1387602D03*
X346464Y1385102D03*
Y1387602D03*
X343964Y1382602D03*
X346464D03*
X348964Y1390102D03*
X343964D03*
Y1392602D03*
X346464D03*
Y1390102D03*
X343777Y1395166D03*
X346302Y1395242D03*
X348828Y1395392D03*
X349032Y1392675D03*
X361744Y120713D03*
X363621Y127665D03*
X361171Y223114D03*
X358618Y223129D03*
X361171Y220614D03*
X358671D03*
X355910Y223847D03*
X365739Y221871D03*
X365559Y238896D03*
X357925Y304082D03*
X351390Y409120D03*
X353890D03*
Y411620D03*
X351390D03*
X365852Y516466D03*
X365071Y551038D03*
X355100Y544390D03*
X362200Y566750D03*
X364047Y556773D03*
X359200Y566990D03*
X360261Y561044D03*
X359657Y570702D03*
X359157Y574415D03*
X365158Y597546D03*
Y593580D03*
X352031Y607498D03*
Y610498D03*
X355031Y607498D03*
Y613498D03*
Y610498D03*
X352031Y604498D03*
X355031D03*
X361031Y607498D03*
Y613498D03*
Y610498D03*
X358031Y607498D03*
Y613498D03*
Y610498D03*
Y604498D03*
Y619398D03*
Y616498D03*
X355031Y619398D03*
Y616498D03*
X361031Y619398D03*
Y616498D03*
X352675Y640994D03*
Y643494D03*
X355275Y641034D03*
Y643534D03*
X355195Y646094D03*
X352595Y646054D03*
X357311Y702110D03*
X364753Y701647D03*
Y704155D03*
X360799Y703710D03*
X358061Y704678D03*
X351865Y711368D03*
X354295D03*
X364451Y769040D03*
Y771540D03*
Y774040D03*
X361951D03*
Y771540D03*
Y769040D03*
X364451Y776540D03*
X361951D03*
X364447Y766540D03*
X361947D03*
X364451Y791558D03*
X361951D03*
X364451Y786558D03*
Y789058D03*
X361951D03*
Y786558D03*
X364451Y784058D03*
X361951Y781558D03*
X364451Y779058D03*
Y781558D03*
X361951Y779058D03*
Y784058D03*
X361671Y803588D03*
X356671D03*
X351671D03*
X363313Y812088D03*
X359813Y812188D03*
X356313D03*
X352813D03*
X356535Y849708D03*
X364897Y852564D03*
X364821Y861852D03*
X357400Y855982D03*
X356895Y859791D03*
X353281Y859620D03*
X363236Y1199632D03*
X361922Y1206891D03*
X357271Y1208988D03*
X351413Y1210052D03*
X365461Y1254188D03*
Y1251688D03*
Y1249188D03*
Y1246688D03*
X351365Y1246631D03*
X353865D03*
Y1251631D03*
X351365D03*
X353865Y1249131D03*
X351365D03*
X353865Y1254131D03*
X351365D03*
Y1269149D03*
Y1266649D03*
Y1264149D03*
Y1261649D03*
X365461Y1256688D03*
Y1259188D03*
X353865Y1266631D03*
Y1264131D03*
Y1261631D03*
Y1269131D03*
X351365Y1259131D03*
Y1256631D03*
X353865Y1259131D03*
Y1256631D03*
X365561Y1269288D03*
Y1264288D03*
Y1266788D03*
Y1261788D03*
Y1271788D03*
X351361Y1271688D03*
X353861D03*
X361301Y1322987D03*
Y1325528D03*
X351651Y1320942D03*
Y1323842D03*
X357611Y1326946D03*
X355411Y1328346D03*
X362794Y1333902D03*
X365074Y1330377D03*
X353345Y1332976D03*
X357611Y1329846D03*
X353345Y1330076D03*
X355511Y1331346D03*
X357611Y1332746D03*
X356764Y1359296D03*
X354264D03*
X364764D03*
X362264D03*
X359764D03*
X351632Y1359203D03*
X351923Y1364724D03*
X354423D03*
X356923D03*
X359423D03*
X362223D03*
X364723D03*
X351772Y1362085D03*
X354272D03*
X356772D03*
X359272D03*
X362072D03*
X364572D03*
X363964Y1385102D03*
X356464Y1380102D03*
X358964D03*
X361464D03*
X353964D03*
X351464D03*
X363964D03*
Y1382602D03*
X351464Y1385102D03*
X353964D03*
X361464D03*
X356464D03*
X358964D03*
X351464Y1382602D03*
X361464D03*
X358964D03*
X356464D03*
X353964D03*
X352067Y1387665D03*
X354567D03*
X357067D03*
X359567D03*
X363190Y1387527D03*
X365979Y1387641D03*
X352332Y1391886D03*
X354832D03*
X357332D03*
X359832D03*
X363191Y1390292D03*
Y1392792D03*
X365980Y1392906D03*
Y1390406D03*
X363003Y1395393D03*
X365792Y1395507D03*
X352313Y1395223D03*
X359859D03*
X357208D03*
X365493Y1655107D03*
X370888Y155250D03*
X377118Y222229D03*
X380012Y239615D03*
X370327Y228951D03*
X370352Y235455D03*
X366671Y297114D03*
X369171D03*
X369671Y292114D03*
Y294614D03*
X380935Y443386D03*
X375935D03*
X378435D03*
X382184Y466351D03*
X378976Y479226D03*
X379633Y493942D03*
X371962Y524954D03*
X368371Y553038D03*
X371971Y553138D03*
X375410Y552254D03*
X377502Y554193D03*
X380157Y553090D03*
X375271Y542191D03*
X379114Y544866D03*
X368647Y550422D03*
X370271Y555038D03*
X379689Y586040D03*
X368798Y587938D03*
X369271Y600138D03*
X373477Y593338D03*
X378577Y593026D03*
X377577Y590126D03*
X370022Y704307D03*
X371515Y715222D03*
Y712681D03*
X367742Y707832D03*
X379711Y708001D03*
Y705101D03*
X375445Y708231D03*
X377545Y706731D03*
X375445Y705331D03*
X377645Y709731D03*
X375445Y711131D03*
X366951Y769058D03*
Y771558D03*
Y774058D03*
Y776558D03*
X379187Y766428D03*
Y768960D03*
Y771460D03*
Y773960D03*
Y776460D03*
X366947Y766540D03*
X366951Y781558D03*
Y786558D03*
Y789058D03*
Y784058D03*
X379187Y786460D03*
Y783960D03*
Y788960D03*
Y778960D03*
Y781460D03*
X366951Y791558D03*
X379187Y791460D03*
X366951Y779058D03*
X376671Y803588D03*
X371671D03*
X366671D03*
X366864Y857274D03*
X369626Y860717D03*
X370316Y1204673D03*
X367931Y1196981D03*
X376271Y1207488D03*
X380718Y1221906D03*
X379223Y1219527D03*
X372126Y1214455D03*
X368726D03*
X367961Y1254188D03*
Y1251688D03*
Y1249188D03*
Y1246688D03*
X370461Y1254188D03*
Y1249188D03*
Y1251688D03*
Y1246688D03*
X367961Y1256688D03*
Y1259188D03*
X370461D03*
Y1256688D03*
X368061Y1269206D03*
X370561D03*
X368061Y1261706D03*
Y1264206D03*
Y1266706D03*
X370561D03*
Y1264206D03*
Y1261706D03*
Y1271788D03*
X368061D03*
X380951Y1326841D03*
X378521D03*
X368063Y1334054D03*
X375505Y1336099D03*
X372017Y1334499D03*
X374755Y1333531D03*
X368063Y1336562D03*
X368964Y1382602D03*
Y1385102D03*
X366464D03*
X368964Y1380102D03*
X366464D03*
Y1382602D03*
X368542Y1387639D03*
X368543Y1390404D03*
Y1392904D03*
X368355Y1395505D03*
X374432Y1582600D03*
X375050Y1639400D03*
X371823Y1644516D03*
X370533Y1658605D03*
X374962Y1648511D03*
X372953Y1653197D03*
X373330Y1668539D03*
X370369Y1661817D03*
X372449Y1680520D03*
X372395Y1677449D03*
X395048Y121178D03*
X384375Y147365D03*
X386350Y138980D03*
X395590Y147010D03*
X391310Y227871D03*
X389912Y280345D03*
X390881Y284156D03*
X395053Y318125D03*
X383525Y443386D03*
X389784Y476070D03*
X384827Y507057D03*
X397184Y507101D03*
X382184D03*
X388985Y554870D03*
X383071Y553738D03*
X382705Y546433D03*
X395171Y559463D03*
X395669Y563328D03*
X385318Y555238D03*
X394168Y568482D03*
X395157Y573815D03*
X393481Y571239D03*
X387103Y584506D03*
X392471Y596988D03*
X391021Y588788D03*
X390351Y702178D03*
X393839Y703778D03*
X391101Y704746D03*
X382475Y711436D03*
X387335D03*
X384905D03*
X381812Y717060D03*
Y714160D03*
X394987Y766428D03*
X381687D03*
X384187D03*
X394991Y773928D03*
Y771428D03*
Y768928D03*
Y776428D03*
X384191Y768928D03*
Y771428D03*
Y773928D03*
X381691D03*
Y771428D03*
Y768928D03*
X384191Y776428D03*
X381691D03*
X381687Y791460D03*
X384187D03*
X394987Y784060D03*
Y779060D03*
Y781560D03*
Y789060D03*
Y786560D03*
X381687Y778960D03*
Y786460D03*
Y783960D03*
Y788960D03*
Y781460D03*
X384187Y788960D03*
Y786460D03*
Y783960D03*
Y778960D03*
Y781460D03*
X386381Y1015474D03*
X393861D03*
X386381Y1022560D03*
Y1019017D03*
X393861Y1022560D03*
Y1019017D03*
X390974Y1222849D03*
Y1219449D03*
X388630Y1236747D03*
X381361Y1254188D03*
Y1249188D03*
Y1251688D03*
Y1246688D03*
X383861Y1254188D03*
X386361D03*
X383861Y1249188D03*
X386361D03*
X383861Y1251688D03*
X386361D03*
X383861Y1246688D03*
X386361D03*
X388630Y1240147D03*
X381361Y1269206D03*
X383861D03*
X381361Y1261706D03*
Y1264206D03*
Y1266706D03*
X383861D03*
Y1264206D03*
Y1261706D03*
X381361Y1256688D03*
Y1259188D03*
X386361Y1256688D03*
Y1259188D03*
X383861Y1256688D03*
Y1259188D03*
X386361Y1269288D03*
Y1261788D03*
Y1266788D03*
Y1264288D03*
X381361Y1271788D03*
X386361D03*
X383861D03*
X383381Y1326841D03*
X384481Y1321192D03*
Y1324092D03*
X388211Y1328546D03*
X393883Y1342318D03*
X388311Y1331546D03*
X386145Y1333176D03*
Y1330276D03*
X386611Y1336056D03*
X388771Y1337546D03*
Y1334546D03*
X395376Y1353233D03*
X393883Y1344859D03*
X395384Y1519250D03*
X395359Y1546519D03*
X389290Y1561250D03*
X387939Y1565534D03*
X389276Y1568413D03*
X391526Y1582373D03*
X394521Y1575891D03*
X388784Y1581801D03*
X393005Y1592304D03*
X381711Y1593842D03*
X381607Y1590393D03*
X388445Y1585898D03*
X389333Y1598816D03*
X387805Y1617302D03*
Y1614802D03*
X394824Y1629713D03*
X394000Y1621500D03*
X389824Y1629713D03*
X389000Y1621500D03*
X384824Y1629713D03*
X381350Y1649000D03*
Y1642900D03*
Y1645800D03*
X382115Y1661545D03*
X387324Y1680495D03*
X392324D03*
X382642Y1680979D03*
X385068Y1683502D03*
X410500Y104883D03*
X410400Y107383D03*
X399264Y121144D03*
X403141Y148300D03*
X410678Y159140D03*
X408603Y152278D03*
X411299Y212096D03*
X400000Y220300D03*
X411940Y240501D03*
X410000Y304000D03*
X402184Y466469D03*
X410984Y496649D03*
X406184Y507900D03*
X403657Y546915D03*
X408550Y557850D03*
X404871Y567338D03*
X403381Y573516D03*
X410111Y572608D03*
X407543Y577415D03*
Y580490D03*
X408445Y687531D03*
X397793Y701715D03*
X410645Y691931D03*
X410545Y688931D03*
X408445Y690431D03*
Y693331D03*
X403062Y704375D03*
X397793Y704223D03*
X404555Y715290D03*
Y712749D03*
X400782Y707900D03*
X399991Y776560D03*
X397491Y768928D03*
Y771428D03*
Y773928D03*
Y776428D03*
X397487Y766428D03*
X399991Y771560D03*
Y769060D03*
X399987Y766428D03*
X399991Y774060D03*
X397487Y779060D03*
Y781560D03*
Y786560D03*
Y784060D03*
X399991D03*
Y779060D03*
Y781560D03*
X401341Y1015474D03*
Y1019017D03*
Y1022560D03*
X403347Y1266162D03*
Y1268662D03*
X400847Y1266162D03*
X398347D03*
X400847Y1268662D03*
X398347D03*
X403347Y1271162D03*
Y1273662D03*
X400847Y1271162D03*
X398347D03*
X400847Y1273662D03*
X398347D03*
X403347Y1276162D03*
Y1278662D03*
X400847D03*
Y1276162D03*
X398347Y1278662D03*
Y1276162D03*
X398447Y1281262D03*
Y1283762D03*
X400947Y1281180D03*
Y1283680D03*
X403447D03*
Y1281180D03*
X400947Y1288680D03*
X403447D03*
X400947Y1286180D03*
X403447D03*
X398447Y1286262D03*
Y1288762D03*
X398461Y1291319D03*
X403461D03*
X400961D03*
X400645Y1353385D03*
X408087Y1355430D03*
X404599Y1353830D03*
X407337Y1352862D03*
X400645Y1355893D03*
X397656Y1349708D03*
X401536Y1516120D03*
Y1512220D03*
X397206Y1516953D03*
Y1511953D03*
Y1514453D03*
X397891Y1521436D03*
X401659Y1519845D03*
X404686Y1516120D03*
Y1512220D03*
X410650Y1509469D03*
X408150D03*
X407836Y1512220D03*
Y1516120D03*
X407561Y1519845D03*
X404699Y1521436D03*
X410108Y1535680D03*
X408895Y1553644D03*
X405331Y1548928D03*
X410851Y1557434D03*
X407198Y1564990D03*
X401249Y1564422D03*
X405758Y1557900D03*
X402912Y1558011D03*
X396452Y1577738D03*
X403163Y1579357D03*
X403004Y1582457D03*
X408925Y1573805D03*
Y1576805D03*
X404669Y1594317D03*
X403837Y1609056D03*
Y1612456D03*
X399447Y1612609D03*
X399801Y1606376D03*
X406697Y1604207D03*
X408856Y1623435D03*
X400380Y1621500D03*
X405436Y1620268D03*
X406343Y1613847D03*
X405747Y1623350D03*
X404640Y1637425D03*
X397822Y1629615D03*
X409552Y1633606D03*
X405342Y1628611D03*
X404661Y1634139D03*
X412000Y1647177D03*
X403844Y1665769D03*
X405000Y1675000D03*
X397324Y1680495D03*
X409000Y1683500D03*
X424975Y54762D03*
X417025D03*
X416549Y66365D03*
Y71665D03*
X427300Y71300D03*
X419900Y96620D03*
X414100D03*
X424084Y110839D03*
X417486Y124179D03*
Y127579D03*
X424086Y123023D03*
X422890Y136700D03*
X424086Y133265D03*
X412370Y188210D03*
X411610Y223140D03*
X424815Y217646D03*
X422936Y223501D03*
X419299Y212096D03*
X423299D03*
X420115Y230323D03*
Y240501D03*
Y235442D03*
Y226323D03*
X411940Y235442D03*
X412715Y251165D03*
Y258165D03*
Y266165D03*
X419617Y308000D03*
X424151Y453174D03*
X415984Y466392D03*
X424784Y496572D03*
X419984Y508000D03*
X411500Y510800D03*
X412771Y524820D03*
X414402Y544690D03*
X423351Y684378D03*
X424101Y686946D03*
X412711Y687301D03*
X420335Y693636D03*
X415475D03*
X417905D03*
X412711Y690201D03*
X414712Y699440D03*
Y696540D03*
X420158Y748643D03*
X415158Y756175D03*
Y751175D03*
Y753675D03*
X417658Y748643D03*
X415158D03*
Y761175D03*
X420158D03*
X417658D03*
X415158Y758675D03*
X420162Y751143D03*
Y753643D03*
Y756143D03*
X417662D03*
Y753643D03*
Y751143D03*
X420162Y758643D03*
X417662D03*
X415158Y771175D03*
X420158Y763675D03*
Y766175D03*
X417658Y768675D03*
X415158D03*
X417658Y763675D03*
Y766175D03*
X415158Y763675D03*
Y766175D03*
X415318Y1009765D03*
Y1006025D03*
X424873Y1014745D03*
X423811Y1005800D03*
X415318Y1013505D03*
X424873Y1023013D03*
Y1018879D03*
X415318Y1028466D03*
Y1020986D03*
Y1024726D03*
Y1017245D03*
X418918Y1032206D03*
X423811Y1032431D03*
X424024Y1267144D03*
X414247Y1268662D03*
X416747D03*
X419247D03*
X424024Y1269644D03*
Y1272144D03*
X414247Y1281180D03*
Y1283680D03*
X416747D03*
Y1281180D03*
Y1271162D03*
X414247D03*
X416747Y1278662D03*
Y1276162D03*
X419247Y1278662D03*
Y1276162D03*
Y1273662D03*
X416747D03*
X414247Y1278662D03*
Y1276162D03*
Y1273662D03*
X419361Y1283719D03*
Y1281219D03*
X419247Y1271162D03*
X424024Y1274644D03*
X414247Y1288680D03*
X416747D03*
X414247Y1286180D03*
X416747D03*
X419361Y1288719D03*
Y1291219D03*
X414361D03*
X416861D03*
X419361Y1286219D03*
X417063Y1340523D03*
Y1343423D03*
X415963Y1346172D03*
X413533D03*
X411103D03*
X421315Y1354276D03*
Y1351376D03*
X421205Y1348586D03*
Y1345686D03*
X418675Y1352166D03*
Y1349266D03*
X425631Y1517138D03*
X425087Y1510708D03*
X422587D03*
X423131Y1517138D03*
X412086Y1512076D03*
Y1514576D03*
X422557Y1537595D03*
X420057D03*
X417098Y1536411D03*
X418157Y1549295D03*
X423157Y1541795D03*
Y1544295D03*
X415657Y1541795D03*
X418157Y1546795D03*
Y1544295D03*
Y1541795D03*
X415657Y1549295D03*
Y1546795D03*
Y1544295D03*
X420657Y1541795D03*
Y1544295D03*
Y1546795D03*
Y1549295D03*
X417098Y1538911D03*
X424115Y1548199D03*
Y1551099D03*
X421697Y1551844D03*
X421683Y1565312D03*
X421108Y1560235D03*
X424488Y1565400D03*
X413540Y1556646D03*
X424616Y1560086D03*
X414202Y1559396D03*
X421294Y1557729D03*
X419254Y1566828D03*
X427081Y1581620D03*
X421277Y1571923D03*
X413396Y1594597D03*
X410991Y1597002D03*
X425469Y1595433D03*
X422069D03*
X419277Y1600725D03*
X414500Y1639075D03*
X417365Y1627695D03*
X420765D03*
X423500Y1652500D03*
X411448Y1650598D03*
X420000Y1664925D03*
X411500Y1657500D03*
X417000Y1675000D03*
X413000Y1683500D03*
X415500Y1672500D03*
X433673Y73960D03*
X428149Y65016D03*
X431359Y82589D03*
X433997Y166400D03*
X437997D03*
X436103Y158594D03*
X437997Y170701D03*
X433997D03*
X438200Y212096D03*
X431299Y212095D03*
X437440Y237270D03*
X442710Y237990D03*
X435710Y250340D03*
X440710D03*
X426947Y320749D03*
X433277Y471970D03*
X429784Y466315D03*
X426208Y468977D03*
X436226Y475526D03*
X437084Y501865D03*
X429784Y506947D03*
X442084Y511870D03*
X427500Y510553D03*
X426011Y524888D03*
X436062Y686575D03*
X430793Y686423D03*
X426839Y685978D03*
X430793Y683915D03*
X437555Y697490D03*
Y694949D03*
X433782Y690100D03*
X430958Y748643D03*
X433458D03*
X433462Y751143D03*
Y753643D03*
Y756143D03*
X430962D03*
Y753643D03*
Y751143D03*
Y758643D03*
X440159Y970341D03*
Y977841D03*
Y985341D03*
X438359Y993766D03*
X438434Y989766D03*
X438359Y997766D03*
X427551Y1005800D03*
X434716Y1014745D03*
X431291Y1005800D03*
X435031D03*
X438771D03*
X438359Y1001766D03*
X434716Y1018879D03*
Y1023013D03*
X431291Y1032431D03*
X435031D03*
X438771D03*
X427551D03*
X427615Y1282917D03*
Y1275417D03*
Y1280417D03*
Y1277917D03*
X436903Y1285694D03*
Y1289694D03*
X436924Y1462595D03*
X433524D03*
X440224Y1452895D03*
X427286Y1483590D03*
Y1480190D03*
Y1501990D03*
Y1505390D03*
X426704Y1523331D03*
Y1526731D03*
X439935Y1532600D03*
X430027Y1546795D03*
Y1544295D03*
X432527Y1541795D03*
Y1549295D03*
Y1546795D03*
Y1544295D03*
X430027Y1541795D03*
Y1549295D03*
X435027D03*
Y1546795D03*
Y1544295D03*
Y1541795D03*
X427527Y1549295D03*
Y1546795D03*
Y1544295D03*
Y1541795D03*
X426620Y1551844D03*
X437736Y1544392D03*
X431923Y1565790D03*
X432051Y1560635D03*
X437910Y1553910D03*
X433440Y1581700D03*
X429947Y1594398D03*
X436776Y1610394D03*
X430500Y1605835D03*
X431664Y1624342D03*
X436776Y1613794D03*
X433012Y1621612D03*
X430500Y1613709D03*
X434500Y1641500D03*
X431000Y1640500D03*
X432000Y1650000D03*
X436925Y1649500D03*
X441182Y77125D03*
X445267Y82124D03*
X452948Y104003D03*
X445997Y166400D03*
X453997D03*
X449997D03*
X448038Y158659D03*
X441997Y170701D03*
X449997D03*
X448499Y212036D03*
X443299Y212095D03*
X456231Y227764D03*
X443299Y220046D03*
X447299D03*
X456231Y232883D03*
X455422Y244103D03*
X444310Y243370D03*
X446710Y249340D03*
X454518Y280793D03*
X447840Y275970D03*
X441320Y295170D03*
Y301170D03*
Y307170D03*
Y313170D03*
Y316170D03*
X442297Y474442D03*
X453269Y478388D03*
X449496Y474009D03*
X446547Y480123D03*
X443683Y502256D03*
X448024Y505345D03*
X452084Y511870D03*
X447084D03*
X457084D03*
X453723Y526558D03*
X444441Y565549D03*
X450305Y669036D03*
X452735D03*
X447875D03*
X440845Y668731D03*
Y665831D03*
X445111Y662701D03*
X442945Y664331D03*
X440845Y662931D03*
X443045Y667331D03*
X445111Y665601D03*
X447212Y671640D03*
Y674540D03*
X446686Y726660D03*
Y729160D03*
Y731660D03*
X449190Y726528D03*
Y729028D03*
Y731528D03*
X451690D03*
Y729028D03*
Y726528D03*
X446686Y724028D03*
X449186D03*
X451686D03*
Y741660D03*
X449186D03*
Y739160D03*
Y736660D03*
X451686Y739160D03*
Y736660D03*
X446686Y741660D03*
Y736660D03*
Y739160D03*
Y734160D03*
X449190Y734028D03*
X451690D03*
X453810Y1014745D03*
X449992Y1005800D03*
X453732D03*
X443574Y1014745D03*
X446252Y1005800D03*
X442511D03*
X453810Y1023013D03*
X443574D03*
X453810Y1018879D03*
X443574D03*
X453732Y1032431D03*
X442884Y1038766D03*
X442511Y1032431D03*
X442884Y1042766D03*
X446252Y1032431D03*
X449992D03*
X441159Y1051541D03*
X443764Y1179395D03*
X443624Y1452895D03*
X453624Y1472295D03*
X446810Y1565020D03*
X446910Y1562098D03*
X446653Y1573264D03*
X441931Y1581662D03*
X443590Y1593880D03*
X441460Y1596020D03*
X450500Y1612450D03*
X446182Y1625555D03*
X450180Y1614950D03*
X445800Y1633200D03*
Y1636000D03*
X446000Y1650000D03*
X462653Y72525D03*
X462456Y95101D03*
X459056D03*
X470010Y141070D03*
X461997Y166400D03*
X471371Y227764D03*
X461931Y212703D03*
X468574Y213104D03*
X471371Y222764D03*
X464440Y218253D03*
X460567Y225205D03*
Y235442D03*
X460624Y240953D03*
Y230323D03*
X463240Y244980D03*
X456720Y285158D03*
X457248Y280143D03*
Y282643D03*
X470243Y285693D03*
X467545Y356864D03*
X460441Y499842D03*
X457424Y497978D03*
X468638Y514096D03*
X465766Y524991D03*
X458725Y524480D03*
X470331Y566632D03*
X465331D03*
X467831D03*
X462831D03*
X467831Y569132D03*
X470331D03*
X459931Y566632D03*
X457431D03*
X462831Y569132D03*
X457431D03*
X459931D03*
X465331D03*
X470331Y576132D03*
X467831Y571632D03*
X465331D03*
X467831Y576132D03*
X465331D03*
X470331Y571632D03*
X462831D03*
Y576132D03*
X457431Y571632D03*
Y574132D03*
X459931Y571632D03*
Y574132D03*
X457431Y576632D03*
X459931D03*
X462831Y598514D03*
X467831D03*
X470331D03*
X465331D03*
X457711D03*
X460211D03*
X462831Y601014D03*
X467831D03*
X470331D03*
X465331D03*
X457711D03*
X460211D03*
X469955Y672890D03*
X463193Y659315D03*
X468462Y661975D03*
X463193Y661823D03*
X455751Y659778D03*
X459239Y661378D03*
X469955Y670349D03*
X456501Y662346D03*
X466182Y665500D03*
X462490Y731528D03*
Y726528D03*
Y729028D03*
X464990D03*
Y726528D03*
X467486Y724028D03*
X464986D03*
X462486D03*
X467490Y726660D03*
X457472Y1005800D03*
X465965Y1009765D03*
Y1006025D03*
Y1013505D03*
Y1020986D03*
Y1024726D03*
Y1028466D03*
Y1017245D03*
Y1032206D03*
X457472Y1032431D03*
X463724Y1462595D03*
X470424Y1452895D03*
X460324Y1462595D03*
X467024Y1452895D03*
X457024Y1472295D03*
X462215Y1581510D03*
X462753Y1641289D03*
X459500Y1659000D03*
X467500Y1651500D03*
X457000Y1650000D03*
X468075Y1662500D03*
X470463Y1670038D03*
X464925Y1662500D03*
X467500Y1678500D03*
X468575Y1704000D03*
X462500Y1697000D03*
X466000Y1714575D03*
X468575Y1731000D03*
X479400Y90574D03*
Y94574D03*
Y97574D03*
Y110930D03*
X479465Y119644D03*
Y115644D03*
X482255Y133222D03*
Y129822D03*
X479465Y123644D03*
X482380Y141942D03*
X483800Y189400D03*
X480200Y191900D03*
X480700Y208200D03*
X480715Y211099D03*
X471371Y235764D03*
X483227Y233000D03*
X487620Y270400D03*
X479870D03*
X483823Y285893D03*
X474808Y291492D03*
X482893Y291293D03*
X479148Y315502D03*
X484063Y305669D03*
X480773Y307153D03*
X471015Y527283D03*
X475731Y566632D03*
X473231D03*
Y569132D03*
X475731D03*
Y574132D03*
Y571632D03*
X473231Y574132D03*
Y571632D03*
X475731Y576632D03*
X473231D03*
X485335Y642536D03*
X480475D03*
X482905D03*
X473445Y642231D03*
X477711Y639101D03*
X475645Y640831D03*
X473445Y639331D03*
X475545Y637831D03*
X473445Y636431D03*
X477711Y636201D03*
X479812Y645240D03*
Y648140D03*
X479058Y702660D03*
Y700160D03*
X484062Y700028D03*
Y702528D03*
X481562D03*
Y700028D03*
X479058Y697528D03*
X481558D03*
X484058D03*
X479058Y717660D03*
Y707660D03*
Y712660D03*
Y710160D03*
Y715160D03*
X484058Y710160D03*
Y712660D03*
X481558Y710160D03*
Y712660D03*
X484058Y715160D03*
X481558D03*
X484062Y707528D03*
X481562D03*
X479058Y705160D03*
X484062Y705028D03*
X481562D03*
X480803Y1015474D03*
Y1022560D03*
Y1019017D03*
X483824Y1472295D03*
X480424D03*
X483500Y1658500D03*
X479500Y1666500D03*
X473500Y1662500D03*
X477538Y1661463D03*
X474000Y1704000D03*
X478500Y1697000D03*
Y1710500D03*
Y1733500D03*
X491849Y55095D03*
Y60105D03*
X497885Y51315D03*
X491849Y64965D03*
X500674Y116261D03*
X490380Y131442D03*
X493780D03*
X485780Y141942D03*
X500136Y141058D03*
X495500Y161386D03*
X497700Y157200D03*
X492685Y160994D03*
X486682Y193516D03*
X495232D03*
Y185516D03*
X486682Y189516D03*
X496831Y205030D03*
X499380Y222510D03*
X491635Y225970D03*
X494144Y221370D03*
X487442Y223377D03*
X500209Y227881D03*
X491635Y215652D03*
X500209Y233000D03*
X491859D03*
X500119Y243173D03*
X500209Y238119D03*
X491577Y238120D03*
Y243240D03*
X485962Y290679D03*
X487827Y354017D03*
X490419Y362138D03*
X498500Y419425D03*
X495793Y632815D03*
X495839Y635323D03*
X488351Y633278D03*
X491839Y634878D03*
X489101Y635846D03*
X498782Y639000D03*
X497362Y700028D03*
Y702528D03*
X494862D03*
Y700028D03*
X499858Y697528D03*
X497358D03*
X494858D03*
X499862Y700160D03*
Y702660D03*
X494862Y705028D03*
X497362D03*
X499862Y705160D03*
X488384Y1015474D03*
X495884D03*
X488384Y1022560D03*
Y1019017D03*
X495884Y1022560D03*
Y1019017D03*
X490524Y1462595D03*
X497224Y1452895D03*
X487124Y1462595D03*
X493824Y1452895D03*
X512658Y46613D03*
X504796Y86320D03*
X516020Y105370D03*
Y109270D03*
X513772Y121220D03*
X502750Y111276D03*
X503000Y135600D03*
X509346Y125842D03*
X507945Y160919D03*
X503161Y154620D03*
X500600Y157100D03*
X505315Y196944D03*
X503507Y185516D03*
X504351Y202776D03*
X508238Y199506D03*
X512076Y206404D03*
X511684Y221219D03*
X504351Y215901D03*
X508001Y220166D03*
X515223Y289035D03*
Y313200D03*
Y305145D03*
X513775Y608436D03*
X506745Y608131D03*
X508945Y606731D03*
X506745Y602331D03*
Y605231D03*
X508845Y603731D03*
X511011Y602101D03*
Y605001D03*
X513012Y611040D03*
Y613940D03*
X501062Y635475D03*
X502555Y646390D03*
Y643849D03*
X514162Y673428D03*
Y665928D03*
Y668428D03*
Y670928D03*
X514158Y663428D03*
Y678460D03*
Y683460D03*
Y680960D03*
Y675960D03*
X509572Y865327D03*
X513572D03*
X513924Y1462595D03*
X510624Y1472295D03*
X507224D03*
X524713Y33346D03*
X529713D03*
X516058Y46613D03*
X519765Y40328D03*
X523165D03*
X519743Y71436D03*
X523143D03*
X524993Y125914D03*
X521618Y165428D03*
X519268Y167428D03*
X519601Y196117D03*
X518691Y191846D03*
X517314Y200449D03*
X519248Y280721D03*
X516723D03*
X521773D03*
X520273Y289035D03*
X517748D03*
X522798D03*
X520273Y313200D03*
X517748D03*
X520273Y305145D03*
X517748D03*
X515523Y335613D03*
X529317Y403784D03*
X524680Y417602D03*
X529095Y452049D03*
X529153Y598735D03*
X529235Y601543D03*
X521651Y599178D03*
X525139Y600778D03*
X522401Y601746D03*
X516205Y608436D03*
X518635D03*
X529962Y673428D03*
Y670928D03*
Y668428D03*
Y665928D03*
X516662Y673428D03*
Y670928D03*
Y668428D03*
Y665928D03*
X527462Y673428D03*
Y665928D03*
Y668428D03*
Y670928D03*
X516658Y663428D03*
X527458D03*
X529958D03*
X516658Y678460D03*
Y683460D03*
Y680960D03*
X527458Y678460D03*
X516658Y675960D03*
X527458D03*
X529958D03*
Y678460D03*
X526474Y851934D03*
Y849434D03*
X517009Y856494D03*
X523074Y853439D03*
Y855939D03*
X528220Y1167366D03*
X517118D03*
X520818D03*
X517324Y1462595D03*
X524024Y1452895D03*
X520624D03*
X539120Y31340D03*
X535117D03*
X544721Y42892D03*
X539721Y42862D03*
X533918Y47067D03*
X537318D03*
X541003Y71436D03*
X544403D03*
X538210Y90618D03*
X540615Y88213D03*
X535170Y111230D03*
Y115130D03*
X530567Y125914D03*
X543408Y133912D03*
X538166Y130698D03*
X541675Y146874D03*
Y151470D03*
Y142021D03*
Y137169D03*
Y156195D03*
X533442Y164428D03*
X532222Y207849D03*
X540695Y217874D03*
X534277Y224930D03*
X538613Y227882D03*
X537051Y211959D03*
X538613Y238119D03*
X534277Y230441D03*
Y235560D03*
X538613Y233000D03*
X539217Y245270D03*
X543780Y294168D03*
X541808Y289743D03*
X544628Y291633D03*
Y289133D03*
X542983Y334531D03*
X533211Y350838D03*
X533543Y404130D03*
X530729Y398634D03*
X543170Y434737D03*
X534455Y428561D03*
X531753Y453232D03*
X540616Y463486D03*
X538067Y592652D03*
X542071Y593089D03*
X535855Y612290D03*
X539657Y607658D03*
X534362Y601375D03*
X535855Y609749D03*
X532082Y604900D03*
X534962Y670960D03*
Y665960D03*
Y668460D03*
X532462D03*
Y665960D03*
Y670960D03*
Y673460D03*
Y663460D03*
X534962D03*
Y673460D03*
Y675960D03*
X532462D03*
X531921Y1167366D03*
X537424Y1452895D03*
X534024D03*
X544794Y1480682D03*
Y1484082D03*
Y1497482D03*
Y1494082D03*
X543947Y1516120D03*
Y1512220D03*
X543672Y1519845D03*
X540810Y1521436D03*
X533317Y1511953D03*
Y1514453D03*
Y1516953D03*
X531495Y1519250D03*
X537770Y1519845D03*
X537647Y1516120D03*
Y1512220D03*
X534002Y1521436D03*
X540797Y1516120D03*
Y1512220D03*
X543719Y1549295D03*
Y1546795D03*
X541219D03*
Y1549295D03*
X538719D03*
Y1546795D03*
X531339Y1546481D03*
X553620Y31048D03*
X549919D03*
X554984Y45312D03*
X553651Y48842D03*
X546350Y39562D03*
X550972Y42902D03*
X561721Y41024D03*
X556351Y41538D03*
X548610Y48082D03*
X547821Y79372D03*
X551721D03*
X555176Y71436D03*
X558576D03*
X552105Y112203D03*
X555505D03*
X553780Y121240D03*
Y124640D03*
X559484Y156667D03*
X553757Y160075D03*
X547196Y190256D03*
X550196D03*
X554196D03*
X553578Y193541D03*
X547196Y199256D03*
X550553Y200304D03*
Y197778D03*
X548963Y218441D03*
X549248Y237652D03*
Y230441D03*
X555567Y236970D03*
X549248Y234152D03*
X559774Y243176D03*
X557243Y294693D03*
X561808Y300492D03*
X562030Y372872D03*
X551044Y373085D03*
X562208Y383668D03*
Y404717D03*
X550573Y399586D03*
Y403586D03*
X562208Y397599D03*
X550573Y414274D03*
X549854Y406298D03*
X547529Y425411D03*
X551591Y443665D03*
X552510Y446490D03*
X547751Y472678D03*
X550925Y475178D03*
X553360Y477822D03*
X555727Y479968D03*
X558379Y482096D03*
X549957Y658478D03*
Y661478D03*
X558690Y1226149D03*
X558876Y1454905D03*
Y1458305D03*
X546253Y1454107D03*
Y1457507D03*
X555348Y1483590D03*
Y1480190D03*
Y1501990D03*
Y1505390D03*
X548197Y1514641D03*
X550471Y1513584D03*
Y1511031D03*
X548197Y1512088D03*
X554766Y1523331D03*
Y1526731D03*
X550939Y1536646D03*
X559215Y1530596D03*
X546219Y1549295D03*
Y1541795D03*
Y1546795D03*
Y1544295D03*
X548719Y1549295D03*
Y1546795D03*
Y1541795D03*
Y1544295D03*
X551219D03*
Y1541795D03*
X549674Y1538890D03*
X558089Y1541795D03*
Y1544295D03*
Y1546795D03*
Y1549295D03*
X555589Y1541795D03*
Y1549295D03*
Y1546795D03*
Y1544295D03*
X549759Y1551844D03*
X552177Y1551099D03*
X554682Y1551844D03*
X552177Y1548199D03*
X565185Y47982D03*
X575331Y47672D03*
X573191Y42912D03*
X570209Y47982D03*
X566771Y41133D03*
X564794Y58911D03*
X567997Y58992D03*
X573763Y58688D03*
X562331Y48438D03*
X570860Y121310D03*
Y124710D03*
X563951Y153640D03*
Y148640D03*
Y157494D03*
X572003Y164356D03*
Y169415D03*
X568804Y221926D03*
X571427Y217771D03*
X569004Y225496D03*
X568736Y235821D03*
X565093Y242640D03*
X570823Y294893D03*
X572447Y299470D03*
X569893Y300293D03*
X571063Y314669D03*
X566148Y324502D03*
X567773Y316153D03*
X575913Y413287D03*
X570863Y410728D03*
X572121Y437038D03*
X564407Y431638D03*
X568709Y434227D03*
X563763Y486350D03*
X567297Y487551D03*
X560890Y484664D03*
X569923Y490726D03*
X561346Y1228547D03*
X564669Y1238907D03*
X564283Y1231192D03*
X565537Y1235456D03*
X574200Y1229900D03*
X567127Y1249536D03*
X570775Y1263008D03*
X564986Y1462595D03*
X571686Y1452895D03*
X561586Y1462595D03*
X568286Y1452895D03*
X560589Y1541795D03*
Y1544295D03*
Y1546795D03*
Y1549295D03*
X563089Y1541795D03*
Y1549295D03*
Y1546795D03*
Y1544295D03*
X567214Y1544299D03*
X591938Y46308D03*
X576478Y58563D03*
X591070Y60201D03*
X586953Y63441D03*
X583685Y70678D03*
X586390Y69291D03*
X579561Y73090D03*
X585000Y82500D03*
X584752Y86248D03*
X590501Y86909D03*
X578454Y88926D03*
X586394Y95948D03*
X591811Y97421D03*
X580485Y133056D03*
Y130530D03*
X583485D03*
Y133056D03*
X589203Y164356D03*
X581203D03*
X589203Y169415D03*
X585685Y174975D03*
X581203Y169415D03*
X575425Y189835D03*
X582124Y194150D03*
X588244Y208991D03*
X575440Y200785D03*
X582002Y197481D03*
X582766Y225496D03*
Y221421D03*
X588554Y217277D03*
Y225277D03*
X580343Y217771D03*
X588215Y214079D03*
X588968Y240112D03*
X582816Y228696D03*
X581099Y263680D03*
X586157Y366827D03*
X585585Y372052D03*
X577482Y383668D03*
X581985Y387227D03*
Y376427D03*
X587710Y399287D03*
X581985Y401158D03*
X587710Y404287D03*
X588723Y415846D03*
X588798Y435949D03*
X588723Y427949D03*
X588742Y431976D03*
X577845Y437151D03*
X587829Y445138D03*
X575345Y437151D03*
X580523Y435949D03*
X575075Y451263D03*
X582390Y464701D03*
X589507Y462559D03*
X583116Y476745D03*
X587500Y470308D03*
X587795Y479631D03*
X581335Y472100D03*
X581421Y813078D03*
X588500Y812093D03*
X584271Y1263988D03*
X588386Y1462595D03*
X585086Y1472295D03*
X581686D03*
X602837Y32910D03*
X603064Y48023D03*
X599284Y42481D03*
X597956Y48047D03*
X606585Y43529D03*
X601073Y60301D03*
X603350Y73642D03*
X599295Y100747D03*
X606183Y95873D03*
X597275Y94922D03*
X596068Y106798D03*
X591385Y109165D03*
X602328Y109062D03*
X597769Y153640D03*
Y148640D03*
X603344Y139131D03*
X598552Y159066D03*
X600161Y188776D03*
X593661D03*
X604293Y193185D03*
X597293Y193186D03*
X602294Y203786D03*
X598968Y238878D03*
X603526Y229995D03*
X597050Y281950D03*
X602223Y298035D03*
X603723Y289721D03*
X602223Y314145D03*
Y322200D03*
X598414Y372357D03*
X598208Y383668D03*
X599884Y412000D03*
X593758Y415850D03*
X603326Y429530D03*
X590326Y445015D03*
X592529Y461563D03*
X598496Y451421D03*
X597500Y483500D03*
X602833Y791746D03*
X590710Y804192D03*
X603743Y794963D03*
X595619Y806084D03*
X600337Y800649D03*
X596821Y802688D03*
X592572Y809088D03*
X596621Y1240366D03*
X595253Y1266668D03*
X596944Y1270115D03*
X595532Y1262668D03*
X605771Y1263098D03*
X598112Y1264365D03*
X594991Y1285582D03*
Y1289582D03*
X591786Y1462595D03*
X598486Y1452895D03*
X595086D03*
X613025Y42725D03*
X612608Y35961D03*
X618732Y39913D03*
X619563Y49193D03*
X615587Y45611D03*
X606263Y60301D03*
X616815Y60277D03*
X611579D03*
X615190Y74533D03*
X615772Y106645D03*
X618182Y100786D03*
X610009Y100748D03*
X614282Y95873D03*
X617420Y119640D03*
X619240Y123232D03*
X605853Y149640D03*
Y145640D03*
Y152140D03*
Y155131D03*
X618801Y165356D03*
Y175534D03*
Y170415D03*
X616357Y182229D03*
X608794Y203786D03*
X607868Y257562D03*
X618705Y285305D03*
X608773Y289721D03*
X609798Y298035D03*
X607273D03*
X606248Y289721D03*
X604748Y298035D03*
X609798Y314145D03*
X607273D03*
X604748D03*
X621585Y331358D03*
X609798Y322200D03*
X607273D03*
X604748D03*
X611118Y359462D03*
X613565Y350819D03*
X619035Y369542D03*
X613482Y383668D03*
X617985Y387227D03*
Y376427D03*
Y401728D03*
X606032Y418968D03*
X617985Y407346D03*
X617998Y415546D03*
X606811Y429528D03*
X611925Y437000D03*
X605769Y442593D03*
X615903Y493474D03*
X608886Y494400D03*
X618680Y511302D03*
X618957Y502306D03*
X616457D03*
X611896Y535178D03*
Y538178D03*
X607091Y528168D03*
X618645Y783582D03*
X609402Y788678D03*
X615571Y788448D03*
X608940Y1265991D03*
X610551Y1262988D03*
X618761Y1266988D03*
X615591Y1282038D03*
X618761Y1278668D03*
X606619Y1278302D03*
X610551Y1269888D03*
X616037Y1367166D03*
X608148Y1373890D03*
X616615Y1386232D03*
X616629Y1375082D03*
X618586Y1462595D03*
X615186D03*
X611886Y1472295D03*
X608486D03*
X613948Y1641600D03*
X624634Y48104D03*
X628410Y45381D03*
X624689Y58262D03*
X627881Y57120D03*
X622207Y60573D03*
X627496Y74977D03*
X626642Y71365D03*
X622156Y95948D03*
X626208Y100861D03*
X628885Y127057D03*
X630810Y122089D03*
X625532Y146982D03*
X625553Y152683D03*
X625755Y168917D03*
X626372Y193431D03*
X626824Y182080D03*
X620455Y219277D03*
Y228777D03*
X631505Y284355D03*
X626705Y285305D03*
X622705D03*
X626473Y305338D03*
X626388Y330536D03*
X631694Y341300D03*
X626555Y343929D03*
X624133Y346520D03*
X626596Y360196D03*
X636500Y360362D03*
X634105Y404652D03*
X635058Y399700D03*
X627925Y421966D03*
X631075Y429888D03*
X632281Y441904D03*
X622174Y438925D03*
X622197Y436116D03*
X622800Y461348D03*
X627880Y455310D03*
X620800Y474700D03*
X627364Y478823D03*
X632984Y471462D03*
X630758Y505874D03*
X633406Y497964D03*
X624381Y503765D03*
X631510Y510613D03*
X624718Y553428D03*
X634794Y590504D03*
X635567Y671774D03*
X631557Y773359D03*
X631741Y770318D03*
X633406Y1358576D03*
X634776Y1353739D03*
X630477Y1350109D03*
Y1353109D03*
X624795Y1373257D03*
X624976Y1378313D03*
X630195Y1384263D03*
X625195Y1383457D03*
X622352Y1393285D03*
X630523Y1392554D03*
X635849Y1393376D03*
X625286Y1452895D03*
X621886D03*
X629808Y1668863D03*
X633422Y1673488D03*
X631643Y1670946D03*
X635491Y1696845D03*
X635472Y1711808D03*
X644963Y29143D03*
X638490Y33340D03*
X642157Y44695D03*
X639876Y49193D03*
X651042Y41545D03*
X647987Y47606D03*
X646042Y41545D03*
X640653Y58274D03*
X640670Y74369D03*
X650846Y74074D03*
X647938Y83795D03*
X644202Y84604D03*
X642607Y94116D03*
X645752Y134988D03*
X643800Y166053D03*
X641111Y158300D03*
X641006Y161829D03*
X643800Y161862D03*
X640923Y169388D03*
X649871Y181942D03*
X641276Y187557D03*
X637804Y235371D03*
X640804D03*
X637804Y239371D03*
X640804D03*
X640084Y227113D03*
X637804Y243371D03*
X640804D03*
X642171Y311280D03*
X641013Y324459D03*
X640922Y360342D03*
X639000Y364862D03*
X642128Y363279D03*
X636579Y366941D03*
X642617Y389299D03*
X637314Y393680D03*
X640784Y395957D03*
X651279Y404458D03*
X637160Y405449D03*
X635243Y433518D03*
X637432Y428935D03*
X642406Y427614D03*
X639211Y433862D03*
Y438191D03*
X635449Y449797D03*
X639002Y449862D03*
X639500Y442362D03*
X639313Y452361D03*
X635690Y461441D03*
X648500Y453862D03*
X635640Y464257D03*
X644849Y495582D03*
X647576Y497964D03*
X643053Y502891D03*
X640076Y497964D03*
X635906D03*
X642310Y535773D03*
X649592Y540078D03*
X639757Y533440D03*
X636055Y528605D03*
X646151Y535227D03*
X648314Y571169D03*
X644414D03*
X638694Y590504D03*
X650258Y590316D03*
X646358D03*
X650228Y674761D03*
X638967Y671774D03*
X646446Y674643D03*
X640271Y763488D03*
X636551Y767900D03*
X642804Y766871D03*
X636247Y771179D03*
X635092Y1277102D03*
X634995Y1384457D03*
X638053Y1384491D03*
X647401Y1384160D03*
X645386Y1462595D03*
X641986D03*
X648686Y1452895D03*
X638686Y1472295D03*
X635286D03*
X639907Y1570443D03*
X639132Y1573127D03*
X645180Y1597800D03*
X645190Y1595050D03*
X649153Y1625726D03*
X649297Y1623185D03*
X640242Y1639951D03*
X647630Y1641522D03*
X643128Y1639803D03*
X642716Y1653939D03*
X637218Y1654131D03*
X644905Y1646491D03*
X639800Y1646650D03*
X643074Y1668505D03*
X647574D03*
X647460Y1662952D03*
X640846Y1665189D03*
X650158Y1687189D03*
X643041Y1682883D03*
X647500Y1674805D03*
X640600D03*
X643300D03*
X639391Y1700695D03*
X640690Y1703547D03*
X651143Y1706162D03*
X644975Y1725236D03*
X635210Y1718395D03*
X641825Y1730516D03*
X640865Y1719684D03*
X657921Y30864D03*
X654117Y29099D03*
X654582Y45448D03*
X660928Y60707D03*
X651014Y60820D03*
X656600Y60537D03*
X661601Y75562D03*
X656501Y69662D03*
X657166Y79131D03*
X656427Y75431D03*
X661588Y69662D03*
X658228Y88447D03*
X666200Y84862D03*
X654037Y93241D03*
Y96041D03*
X651950Y99890D03*
X658949Y139840D03*
X662881Y149912D03*
Y146912D03*
X654326Y174437D03*
X653700Y179962D03*
X659881Y208262D03*
Y205762D03*
Y210762D03*
X662781Y207862D03*
Y205362D03*
Y210362D03*
X663915Y234476D03*
X659918Y326503D03*
X658905Y341885D03*
X661019Y344831D03*
X663551Y346035D03*
X649500Y373500D03*
X652425Y385924D03*
X659095Y381020D03*
X649495Y385118D03*
X659354Y393938D03*
X653523Y399987D03*
X652954Y394284D03*
X661297Y409857D03*
X662016Y417897D03*
X652027Y415930D03*
X654273Y419251D03*
X662000Y433862D03*
X654248Y422500D03*
X657535Y422694D03*
X666000Y429844D03*
X651432Y433532D03*
X662000Y429844D03*
X652763Y427866D03*
X651384Y445252D03*
X661546Y444497D03*
X662000Y449862D03*
X654441Y449618D03*
X662000Y437844D03*
X657622Y437819D03*
X651853Y439518D03*
X653449Y458542D03*
X662570Y461547D03*
Y457755D03*
X662000Y473862D03*
X666000Y473844D03*
X651072Y465939D03*
X654000Y465824D03*
X654014Y473862D03*
X662000Y465862D03*
X651114Y473884D03*
X662000Y469862D03*
X653266Y479106D03*
X663374Y484295D03*
X652380Y482390D03*
X657520Y486330D03*
X649500Y490260D03*
X660215Y483109D03*
X658758Y497964D03*
X655917D03*
X661718Y498056D03*
X651406Y501178D03*
X650404Y496102D03*
X652576Y497964D03*
X659425Y521075D03*
X665689Y550294D03*
X649922Y545610D03*
X655967Y544375D03*
X658642Y573893D03*
X661718Y579932D03*
X653368Y581468D03*
X655572Y572603D03*
X656832Y577205D03*
X662992Y598660D03*
X658613Y599534D03*
X662628Y674761D03*
X660175Y679517D03*
X657428Y674761D03*
X663580Y731509D03*
X658947Y767300D03*
Y771100D03*
X662600Y1311502D03*
Y1308502D03*
X653376Y1365793D03*
X661719Y1363394D03*
X651973Y1363038D03*
X653149Y1372500D03*
X653101Y1369862D03*
X652651Y1375308D03*
X661813Y1370081D03*
X653117Y1378037D03*
X651877Y1391074D03*
X652086Y1452895D03*
X662086D03*
X663160Y1511734D03*
Y1516734D03*
Y1519234D03*
Y1521734D03*
X660660Y1519234D03*
X661710Y1514148D03*
X663160Y1524234D03*
X666092Y1553650D03*
X660953Y1539998D03*
X663133Y1543744D03*
Y1541244D03*
Y1538744D03*
X660953Y1542498D03*
X657430Y1555228D03*
X659532Y1546519D03*
X664246Y1561009D03*
X661731Y1561083D03*
X661156Y1626532D03*
X650966Y1618934D03*
X651870Y1612986D03*
X650753Y1615912D03*
X653542Y1649059D03*
X660058Y1648889D03*
X660389Y1654481D03*
X663431Y1645780D03*
X654712Y1653813D03*
X664315Y1654484D03*
X650074Y1668505D03*
X658648Y1664169D03*
X655683Y1664212D03*
X653154Y1683265D03*
X664159Y1674844D03*
X661528Y1674865D03*
X650200Y1674805D03*
X658491Y1688965D03*
X649464Y1691180D03*
X659837Y1698400D03*
X659557Y1714672D03*
X658759Y1707147D03*
X659028Y1710047D03*
X660930Y1730277D03*
X662120Y1720404D03*
X670613Y42464D03*
X674013D03*
X677476Y33317D03*
X680864Y38190D03*
X666506Y32750D03*
X674647Y38190D03*
X677305Y57947D03*
X665469Y58525D03*
X674036Y74522D03*
X675509Y88173D03*
X667941Y80142D03*
X677561Y118409D03*
X677738Y115428D03*
X665651Y147692D03*
X673011Y169021D03*
X679035Y204181D03*
X678226Y215771D03*
X674348Y218580D03*
X666552Y346115D03*
X677111Y345662D03*
X672111D03*
X674611D03*
X676800Y369362D03*
X672800D03*
X680800Y380280D03*
X672800Y382362D03*
X676000Y378100D03*
X667090Y385150D03*
X671500Y390862D03*
X679940Y400933D03*
X675500Y398862D03*
Y390862D03*
X670018Y418690D03*
X669929Y407999D03*
X666000Y433862D03*
Y425862D03*
X670000Y429864D03*
Y433844D03*
Y425894D03*
X666000Y437844D03*
X670000Y442362D03*
Y437844D03*
X666000Y442362D03*
X670000Y446362D03*
X679062Y455140D03*
X666000Y453844D03*
Y457862D03*
X670000Y453844D03*
X666000Y461862D03*
X670000Y469824D03*
Y477862D03*
X678000D03*
X670000Y482862D03*
X678000D03*
X681213Y495658D03*
X672699Y506907D03*
X664741Y506865D03*
X680488Y504784D03*
X665425Y537000D03*
X664454Y574896D03*
X665774Y571762D03*
X666192Y598660D03*
X679047Y678733D03*
X673287Y733156D03*
X674123Y736083D03*
X667101Y736071D03*
X672505Y766871D03*
X674552Y1342488D03*
Y1344988D03*
X665167Y1380836D03*
Y1376836D03*
X673671Y1431922D03*
X675272Y1434525D03*
X665486Y1452895D03*
X672856Y1484082D03*
Y1480682D03*
Y1497482D03*
Y1494082D03*
X678386Y1507965D03*
X677871Y1522079D03*
X678345Y1516994D03*
X677871Y1519579D03*
X673174Y1515806D03*
X675505Y1512606D03*
X678339Y1510960D03*
X677871Y1524579D03*
X678121Y1528516D03*
X665832Y1527425D03*
X672715Y1526626D03*
Y1530526D03*
X678350Y1567400D03*
X669524Y1560850D03*
X672163Y1560899D03*
X673729Y1556768D03*
X666978Y1560945D03*
X672810Y1571560D03*
X666610Y1571580D03*
X668133Y1625828D03*
X670839Y1620863D03*
X673960Y1633042D03*
X669648Y1640917D03*
X670803Y1654606D03*
X671068Y1650818D03*
X674908Y1644481D03*
X667971Y1654404D03*
X669178Y1646627D03*
X673548Y1669550D03*
X678117Y1662787D03*
X675497Y1687253D03*
X673359Y1674409D03*
X671001Y1696017D03*
X671798Y1704542D03*
X673113Y1716599D03*
X667701Y1705043D03*
X668058Y1720092D03*
X673113Y1727261D03*
X684611Y41857D03*
X682291Y46822D03*
X690476Y32684D03*
X692390Y46939D03*
X692466Y35950D03*
X687835Y37850D03*
X687345Y46940D03*
X687018Y58357D03*
X683369Y58157D03*
X692390Y72692D03*
X690028Y70142D03*
X687665Y73202D03*
X685781Y70022D03*
X680580Y79230D03*
X681054Y104668D03*
X686891Y115868D03*
X687000Y119500D03*
X685500Y124000D03*
X679316Y209861D03*
X680576Y207105D03*
X681333Y212326D03*
X679737Y217763D03*
X693621Y346169D03*
X680828Y363500D03*
X684800Y369362D03*
X680800D03*
X691484Y360643D03*
X691500Y382462D03*
X685200Y377820D03*
X690105Y401775D03*
X687500Y390680D03*
X684794Y402268D03*
X683500Y390862D03*
X679500D03*
X692996Y418358D03*
X694299Y413108D03*
X689269Y410420D03*
X687612Y471850D03*
X691572Y465214D03*
X684800Y477862D03*
X687472Y486994D03*
X684680Y485942D03*
X684800Y481862D03*
X680187Y491243D03*
X690452Y486984D03*
X687310Y500453D03*
X682915Y500568D03*
X683000Y521500D03*
X687310Y522141D03*
X694111Y537881D03*
X690718Y578913D03*
X694996Y575081D03*
X689574Y572866D03*
X681352Y681305D03*
X691417Y680382D03*
X685786Y680936D03*
X686509Y677440D03*
X688648Y767300D03*
Y771100D03*
X687961Y1314308D03*
Y1320308D03*
Y1323308D03*
Y1317308D03*
X684868Y1327117D03*
X682348D03*
Y1339617D03*
X683052Y1342548D03*
X684868Y1329617D03*
X682348D03*
X684868Y1332117D03*
X682348D03*
X684868Y1334617D03*
X682348D03*
X684868Y1337117D03*
Y1339617D03*
X682348Y1337117D03*
X683052Y1345048D03*
X681289Y1418291D03*
X683391Y1420531D03*
X685448Y1423137D03*
X691587Y1429515D03*
X689538Y1427467D03*
X684350Y1448911D03*
X692376Y1438326D03*
X691943Y1441626D03*
X687040Y1452300D03*
X684280Y1452260D03*
X684603Y1507851D03*
X681517Y1508034D03*
X687529Y1508173D03*
X690683Y1508058D03*
X693395D03*
X693532Y1510755D03*
X690820D03*
X687666Y1510870D03*
X687711Y1513612D03*
X690751Y1513750D03*
X693655Y1513818D03*
X693587Y1516470D03*
X690752Y1516516D03*
X683666Y1515189D03*
X680717Y1513292D03*
X684557Y1510685D03*
X681563Y1510708D03*
X693495Y1519305D03*
X679854Y1551492D03*
X679413Y1548843D03*
X680107Y1554330D03*
X681780Y1574280D03*
X684080Y1576500D03*
X686949Y1625144D03*
X689897Y1621781D03*
X692209Y1620037D03*
X691036Y1625508D03*
X686994Y1629077D03*
X693451Y1628733D03*
X686808Y1643500D03*
X685578Y1637479D03*
X683067Y1641758D03*
X686075Y1657082D03*
X679413Y1653251D03*
X685719Y1672391D03*
X685747Y1669303D03*
X693608Y1671081D03*
X685635Y1675310D03*
X691560Y1682047D03*
X693480Y1673940D03*
X692390Y1687594D03*
X705666Y48010D03*
X697678Y47132D03*
X697893Y35950D03*
X702481Y48327D03*
X698462Y60683D03*
X695220Y60455D03*
X704201Y72112D03*
X699476Y69982D03*
X701081Y72450D03*
X694752Y70212D03*
X696701Y72462D03*
X698711Y86035D03*
X696371Y78512D03*
X696728Y81552D03*
Y84052D03*
X706721Y100462D03*
X702721Y102162D03*
X701221Y104862D03*
X697721D03*
X695721Y102162D03*
X694221Y104862D03*
X699221Y102162D03*
X699398Y123668D03*
X704709Y125586D03*
X704771Y171188D03*
Y167788D03*
X703486Y345507D03*
X699813Y344798D03*
X706139Y345597D03*
X695500Y374362D03*
X699500D03*
X703500D03*
X707500D03*
X707943Y360643D03*
X707500Y368862D03*
X696391Y368617D03*
X703477Y369409D03*
X695500Y382362D03*
X700300Y382502D03*
X707500Y382362D03*
X700000Y386790D03*
X707500Y386862D03*
X703700Y386832D03*
X695500Y386862D03*
X699500Y390862D03*
X695500D03*
X707500D03*
X703500Y401290D03*
Y390862D03*
X708584Y404868D03*
X699431Y513344D03*
X703774Y513463D03*
X707664Y513375D03*
X703788Y521817D03*
X696020Y521844D03*
X699800Y521760D03*
X708500Y517362D03*
X708210Y537816D03*
X708500Y529862D03*
X704500D03*
X700790Y537732D03*
X704500Y537862D03*
X708500Y533862D03*
X696829Y533604D03*
X702657Y533695D03*
X697018Y537577D03*
X704500Y545862D03*
X696283Y546530D03*
X710429Y545752D03*
X708500Y555451D03*
X698996Y575081D03*
X704056D03*
X708056D03*
X704056Y583081D03*
X698996D03*
X702806Y613264D03*
X696928Y613207D03*
X706387Y621686D03*
X705158Y645357D03*
X703781Y641805D03*
X704965Y638767D03*
X707833Y655325D03*
X704549Y655238D03*
X701233Y655355D03*
X708418Y650389D03*
X694812Y680188D03*
X698756Y676388D03*
X694837Y676412D03*
X701386Y679683D03*
X703584Y676544D03*
X708012Y676836D03*
X705697Y679533D03*
X697571Y730453D03*
X704598Y732288D03*
X700205Y733211D03*
X702553Y735811D03*
X702206Y766871D03*
X697461Y1314008D03*
Y1320008D03*
Y1323008D03*
X702388Y1327127D03*
X699868D03*
X697461Y1317008D03*
X701771Y1342488D03*
X702388Y1337127D03*
Y1339627D03*
X699868Y1337127D03*
Y1339627D03*
X702388Y1329627D03*
X699868D03*
X702388Y1332127D03*
X699868D03*
X702388Y1334627D03*
X699868D03*
X701771Y1344988D03*
X705657Y1387027D03*
X701689Y1399545D03*
X697731Y1397513D03*
X706351Y1397588D03*
X705657Y1389568D03*
X695162Y1441350D03*
X696237Y1508149D03*
X699247Y1508062D03*
X699049Y1510892D03*
X696374Y1510846D03*
X696329Y1513818D03*
X696330Y1516584D03*
X699140Y1513772D03*
X707050Y1531700D03*
X709150Y1536250D03*
X703290Y1551700D03*
X707050Y1548400D03*
Y1541800D03*
X703290Y1545100D03*
X708500Y1560500D03*
X708994Y1568507D03*
X699500Y1559000D03*
X699610Y1568523D03*
Y1572523D03*
Y1576523D03*
X708600Y1572523D03*
X710420Y1585173D03*
X710550Y1576523D03*
X710080Y1581683D03*
X699610Y1584523D03*
X699500Y1596500D03*
Y1588500D03*
X709836Y1594721D03*
X710360Y1589296D03*
X699000Y1604500D03*
X699500Y1599500D03*
X709382Y1601210D03*
X699500Y1608500D03*
X709020Y1609101D03*
X699424Y1616627D03*
X695933Y1623460D03*
X709260Y1617903D03*
X701114Y1640345D03*
X702683Y1633715D03*
X703563Y1644116D03*
X702402Y1650469D03*
X700528Y1661468D03*
X697503Y1661331D03*
X703102Y1665554D03*
X714471Y46670D03*
X724621Y40062D03*
X719821Y45862D03*
X714322Y56286D03*
X721163Y58588D03*
X714096Y73686D03*
X712717Y68541D03*
X719416Y68738D03*
Y74036D03*
X725016Y86952D03*
X720016D03*
X715745Y86300D03*
X712725Y84714D03*
X712291Y106722D03*
X715934Y117488D03*
Y114588D03*
X712734Y117488D03*
Y114588D03*
X720434Y135088D03*
X717434D03*
X719934Y124488D03*
X723134D03*
X712341Y128093D03*
X710284Y169826D03*
X717021Y220862D03*
X714867Y344943D03*
X717712Y346103D03*
X715500Y374362D03*
X719500D03*
X723531Y368862D03*
X723500Y360862D03*
X711500Y374362D03*
X715500Y360862D03*
X719500Y368862D03*
X715500D03*
X711363Y369274D03*
X711500Y382362D03*
X719640Y386862D03*
X723632D03*
X711500D03*
X715500D03*
X722500Y383162D03*
X723500Y390862D03*
X719500D03*
X715500D03*
X711500D03*
X716500Y521862D03*
X711617Y513531D03*
X724500Y517362D03*
X716500D03*
X720400Y517440D03*
X720452Y513362D03*
X716716Y513368D03*
X720499Y533474D03*
X719841Y537348D03*
X712113Y537797D03*
X720500Y555862D03*
Y546211D03*
X712115Y541872D03*
X712409Y555413D03*
X710464Y557036D03*
X722201Y579306D03*
X723483Y574890D03*
X714583Y590792D03*
X716181Y585562D03*
X715037Y606428D03*
X716313Y610134D03*
X719710Y612831D03*
X720787Y627907D03*
X716721D03*
X713343Y633842D03*
X724000Y633906D03*
X725812Y654713D03*
X715371Y654726D03*
X711702Y646533D03*
X711295Y665117D03*
X718129Y666725D03*
X722129D03*
X712164Y676912D03*
X712120Y680287D03*
X717515Y679833D03*
X720563Y679886D03*
X720613Y677040D03*
X723814Y736782D03*
X718349Y767300D03*
Y771100D03*
X721339Y1314048D03*
X711839Y1314348D03*
X721339Y1323048D03*
Y1320048D03*
Y1317048D03*
X715828Y1327277D03*
X710488Y1327177D03*
X713008D03*
X711839Y1323348D03*
Y1320348D03*
Y1317348D03*
X713008Y1329877D03*
Y1332377D03*
Y1334877D03*
X715828Y1332877D03*
Y1330377D03*
X713008Y1337377D03*
Y1339877D03*
X715828Y1335377D03*
X710288Y1339677D03*
Y1337177D03*
X710221Y1342488D03*
X710288Y1334677D03*
Y1332177D03*
Y1329677D03*
X710221Y1344988D03*
X712419Y1398094D03*
X719861Y1400139D03*
X716373Y1398539D03*
X719111Y1397571D03*
X712419Y1400602D03*
X709430Y1394417D03*
X722877Y1390881D03*
X712099Y1416973D03*
X714599D03*
X717099D03*
X712099Y1414473D03*
X714599D03*
X717099D03*
X709599Y1416973D03*
Y1414473D03*
X717099Y1432773D03*
X712099D03*
X714599D03*
X717099Y1430273D03*
X712099D03*
X714599D03*
X709599Y1432773D03*
Y1427373D03*
Y1424873D03*
Y1430273D03*
Y1419873D03*
Y1422373D03*
X714259Y1447483D03*
X719471Y1467422D03*
X711671D03*
X714271D03*
X716871D03*
X720217Y1472287D03*
X717617D03*
X715017D03*
X720926Y1469814D03*
X718326D03*
X715726D03*
X713126D03*
X716067Y1474792D03*
X718667D03*
X721267D03*
X717358Y1477038D03*
X719958D03*
X714474Y1566333D03*
X724110Y1561825D03*
X714110Y1581475D03*
X714900Y1571273D03*
X721963Y1576932D03*
X719963Y1578932D03*
X721440Y1570963D03*
X719963Y1585790D03*
X721963Y1587790D03*
X723590Y1595323D03*
X718892Y1597152D03*
X714372Y1594679D03*
X723408Y1608740D03*
X720106Y1609542D03*
X717798Y1607335D03*
X713718Y1610235D03*
X717229Y1612376D03*
X718129Y1624330D03*
X722104Y1626253D03*
X715744Y1622842D03*
X722889Y1622491D03*
X711298Y1632534D03*
X718122Y1636332D03*
X718116Y1639129D03*
X713771Y1654927D03*
X722480Y1657616D03*
X719117Y1682722D03*
X723181Y1688825D03*
X740101Y41162D03*
X736621Y45262D03*
X733315Y40862D03*
X728721Y43562D03*
X726789Y60562D03*
X738590Y59868D03*
X730785Y58068D03*
X728285Y58135D03*
X724645Y58362D03*
X734769Y60757D03*
X725769Y69737D03*
X736864Y74943D03*
X731864D03*
X727200Y73210D03*
X729918Y90998D03*
X739824Y91052D03*
X734380Y80518D03*
X729380D03*
X736650Y102350D03*
X735771Y94988D03*
X730660Y108484D03*
X728734Y132088D03*
Y129288D03*
Y126388D03*
X735500Y143000D03*
X724147Y345291D03*
X729211Y346379D03*
X726431Y346384D03*
X738773Y346716D03*
X734463Y346712D03*
X735500Y368862D03*
X734166Y360782D03*
X739500Y368862D03*
X727564D03*
X731500Y360862D03*
X731406Y374331D03*
X731500Y368862D03*
Y386862D03*
X739553Y388270D03*
X735500Y386862D03*
X727500D03*
X735500Y390862D03*
X727500D03*
X735500Y399330D03*
X738672Y494444D03*
X728938Y517520D03*
X724500Y513362D03*
X732500D03*
X739185Y521394D03*
X728500Y521862D03*
X724500D03*
X728500Y513362D03*
X736609Y518426D03*
X728500Y529862D03*
X728576Y537476D03*
X736500Y537862D03*
X724336Y537527D03*
X724433Y530870D03*
X732500Y529862D03*
X736647Y529772D03*
X732580Y537193D03*
X724697Y535053D03*
X728652Y545862D03*
X728695Y550943D03*
X736670Y545864D03*
X740500Y545862D03*
X724684Y545864D03*
X724281Y553438D03*
X728714Y554190D03*
X732520Y545988D03*
X736528Y576480D03*
Y579615D03*
X727253Y610689D03*
X724246Y627939D03*
X736362Y636854D03*
X730770Y644218D03*
X733382Y633574D03*
X729489Y666547D03*
X734442Y675695D03*
X730837Y678940D03*
X738486Y679139D03*
X724931Y678364D03*
X735316Y736742D03*
X725712Y734135D03*
X729391D03*
X727576Y736756D03*
X727448Y766871D03*
X735739Y1314048D03*
Y1320048D03*
Y1317048D03*
X724788Y1327277D03*
X727501Y1327230D03*
X730021D03*
X735739Y1323048D03*
X727401Y1332430D03*
Y1329930D03*
Y1334930D03*
X724788Y1330377D03*
Y1332877D03*
X727401Y1339930D03*
Y1337430D03*
X724788Y1335377D03*
X730021Y1337230D03*
Y1339730D03*
Y1334730D03*
Y1329730D03*
Y1332230D03*
X730795Y1342444D03*
Y1344944D03*
X738439Y1387127D03*
X728198Y1388026D03*
Y1385126D03*
X738439Y1389668D03*
X727737Y1390881D03*
X725307D03*
X734767Y1396986D03*
Y1394086D03*
X732567Y1392586D03*
X732667Y1395586D03*
X730501Y1397216D03*
Y1394316D03*
X734767Y1391186D03*
X735418Y1426122D03*
Y1423122D03*
Y1420122D03*
X732418Y1426122D03*
Y1423122D03*
Y1420122D03*
X735453Y1525368D03*
X737551Y1524008D03*
X727325Y1563400D03*
X727571Y1558353D03*
X736782Y1555496D03*
X730782D03*
X733782D03*
X727571Y1555353D03*
X733782Y1567496D03*
X736782D03*
X730782D03*
X733782Y1558496D03*
Y1561496D03*
X736782Y1558496D03*
Y1561496D03*
X733782Y1564496D03*
X736782D03*
X730782Y1558496D03*
Y1561496D03*
Y1564496D03*
X726475Y1571293D03*
X723963Y1578932D03*
X730782Y1570496D03*
X736782D03*
X733782D03*
X723963Y1585790D03*
X726550Y1599358D03*
X730647Y1623629D03*
X727320Y1623698D03*
X736723Y1623938D03*
X731119Y1647997D03*
X735642Y1648537D03*
X730347Y1682902D03*
X725638Y1682890D03*
X732852Y1695701D03*
X738030Y1723903D03*
Y1726903D03*
X738108Y1721157D03*
X738075Y1718082D03*
X746101Y46262D03*
X745901Y40362D03*
X749478Y59902D03*
X746588Y59754D03*
X740817Y58503D03*
X747488Y71429D03*
X740537Y73564D03*
X750034Y89988D03*
X750701Y106642D03*
X754783Y96553D03*
X750034Y92888D03*
X741309Y108742D03*
X748034Y116288D03*
X748261Y112552D03*
X743050Y139182D03*
X751221Y137864D03*
X743547Y147703D03*
X748915Y158608D03*
X745031Y161463D03*
X748125Y170618D03*
X751575Y184252D03*
X746522Y308804D03*
X750717Y319907D03*
X747594Y319106D03*
X747696Y332772D03*
X751337Y343849D03*
X748752Y343582D03*
X745132Y344964D03*
X752926Y361021D03*
X747500Y368862D03*
X751500D03*
X743500D03*
Y374362D03*
X749389Y360816D03*
X755135Y368907D03*
X754813Y374362D03*
X739500D03*
X747500D03*
X747454Y386817D03*
X751652Y386862D03*
X743500Y386962D03*
X739652Y390862D03*
X743500D03*
X747500D03*
X751500D03*
X747629Y406163D03*
X753252Y495234D03*
X748381Y495244D03*
X752652Y504106D03*
X752500Y517362D03*
X744500Y513362D03*
X748661Y517060D03*
X740500Y513362D03*
X752500D03*
X748500D03*
X753951Y521801D03*
X748077Y521789D03*
X740500Y537862D03*
X752965Y537678D03*
X748143Y530269D03*
X744916Y530268D03*
X752500Y529862D03*
X748000Y537862D03*
X741851Y553544D03*
X745645Y545880D03*
X752500Y545862D03*
X745091Y553563D03*
X748500Y545862D03*
X752195Y554761D03*
X748482Y557085D03*
X751731Y557714D03*
X739128Y566639D03*
X741624Y580707D03*
X741200Y577470D03*
X749131Y570340D03*
X750062Y655415D03*
X753309Y655515D03*
X750074Y648739D03*
X753483Y648749D03*
X751885Y666724D03*
X753231Y678679D03*
X742579Y676093D03*
X746665Y678879D03*
X750168Y675833D03*
X748049Y767300D03*
Y771100D03*
X745439Y1314048D03*
X748188Y1327317D03*
X745491Y1327124D03*
X742971D03*
X745439Y1323048D03*
Y1320048D03*
Y1317048D03*
X745691Y1332424D03*
Y1329924D03*
Y1334924D03*
X748188Y1333017D03*
Y1330517D03*
X745691Y1339924D03*
Y1337424D03*
X748188Y1335517D03*
X742971Y1337124D03*
Y1339624D03*
Y1334624D03*
Y1329624D03*
Y1332124D03*
X739501Y1342244D03*
Y1344744D03*
X739932Y1398042D03*
X745201Y1398194D03*
X752643Y1400239D03*
X749155Y1398639D03*
X751893Y1397671D03*
X745201Y1400702D03*
X742212Y1394517D03*
X739611Y1458211D03*
X750418Y1468893D03*
X750968Y1482349D03*
X746111Y1504125D03*
X745984Y1501052D03*
X745001Y1516471D03*
X750205Y1512307D03*
X750155Y1516451D03*
X739900Y1523152D03*
X748782Y1555496D03*
X742782D03*
X739782D03*
X745782D03*
X739782Y1558496D03*
Y1561496D03*
Y1564496D03*
X745782Y1558496D03*
X742782D03*
X745782Y1561496D03*
X742782D03*
X745782Y1564496D03*
X742782D03*
X739782Y1567496D03*
X742782D03*
X748782Y1558496D03*
Y1561496D03*
Y1564496D03*
X747110Y1575863D03*
X747150Y1583247D03*
X747110Y1579863D03*
X739782Y1570496D03*
X742782D03*
X747160Y1587773D03*
X749167Y1591967D03*
X754635Y1592571D03*
X743664Y1626945D03*
X753770Y1636083D03*
X751521Y1656008D03*
X739880Y1648046D03*
X742792Y1647982D03*
X745075Y1665675D03*
X754030Y1669256D03*
X748254Y1674771D03*
X752187Y1682994D03*
X748413Y1679367D03*
X746766Y1696036D03*
X740328Y1698376D03*
X747289Y1693063D03*
X752187Y1691058D03*
X741030Y1723903D03*
Y1726903D03*
X741160Y1721150D03*
X741025Y1718195D03*
X757721Y62132D03*
X760221D03*
X762721D03*
X755621Y51602D03*
X758621D03*
X757721Y64632D03*
X760221D03*
X763221Y65132D03*
X757188Y91829D03*
X757694Y98108D03*
Y100653D03*
X760193Y106500D03*
X757576Y112575D03*
X756000Y145500D03*
X754825Y163397D03*
X756303Y158417D03*
X765950Y190669D03*
X765000Y186500D03*
X754737Y185469D03*
X757629Y239295D03*
X761067Y280355D03*
X763384Y279231D03*
X763508Y284404D03*
X763463Y281840D03*
X760614Y284100D03*
X754759Y281007D03*
X758510Y298620D03*
X760462Y295662D03*
X757937Y303908D03*
X768130Y335363D03*
X758245Y343763D03*
X764331Y374401D03*
X756347Y360851D03*
X764983Y368052D03*
X766304Y372862D03*
X768304Y374362D03*
X759652D03*
X755500Y386862D03*
X759500D03*
X763500D03*
X767500D03*
X759500Y390791D03*
X755500Y390862D03*
X759500Y402098D03*
X767500Y401470D03*
Y390862D03*
X763500D03*
X757258Y408763D03*
X765975Y414414D03*
X769648Y430511D03*
X770530Y423460D03*
X768301Y438223D03*
X770918Y442510D03*
X770042Y446829D03*
X770590Y470940D03*
X762800Y493654D03*
X764500Y521862D03*
X756500Y513340D03*
X764500D03*
X756800Y517050D03*
X760500Y521189D03*
X764600Y517022D03*
X756186Y529888D03*
X764500Y529862D03*
X760500Y529845D03*
X757860Y537859D03*
X760660Y537862D03*
X756500Y545862D03*
X764500D03*
X759568Y545867D03*
X768340Y563678D03*
X765809Y563410D03*
X758103Y556873D03*
X765041Y565867D03*
X762530Y565340D03*
X757745Y655353D03*
X755765Y666904D03*
X762656Y667835D03*
X756936Y676319D03*
X768565Y677573D03*
X760529Y677715D03*
X764401Y676968D03*
X762396Y732915D03*
X754532Y735859D03*
X760425Y736233D03*
X764568Y736183D03*
X761608Y766871D03*
X759839Y1313948D03*
Y1319948D03*
X760204Y1327314D03*
X762754D03*
X759839Y1316948D03*
X757638Y1327317D03*
X759839Y1322948D03*
X760204Y1332514D03*
Y1330014D03*
Y1335014D03*
X757638Y1333017D03*
Y1330517D03*
X760194Y1340024D03*
Y1337524D03*
X757638Y1335517D03*
X762844Y1337324D03*
Y1339824D03*
X762754Y1334814D03*
Y1329814D03*
Y1332314D03*
X762261Y1343424D03*
Y1345924D03*
X760980Y1385146D03*
Y1388046D03*
X758089Y1390981D03*
X760519D03*
X755659D03*
X767549Y1391286D03*
Y1397086D03*
Y1394186D03*
X765349Y1392686D03*
X765449Y1395686D03*
X763283Y1397316D03*
Y1394416D03*
X758163Y1490789D03*
Y1498663D03*
Y1494726D03*
Y1502600D03*
Y1506538D03*
Y1522286D03*
Y1510474D03*
X757826Y1514412D03*
X758056Y1518349D03*
X760650Y1570633D03*
Y1578733D03*
Y1574733D03*
X757610Y1576023D03*
X766212Y1568043D03*
X757650Y1580023D03*
X766950Y1581233D03*
X757610Y1584023D03*
X767750Y1584108D03*
X757610Y1589023D03*
X760650Y1587733D03*
X760521Y1595500D03*
X759723Y1626161D03*
X755261Y1628208D03*
X758030Y1668583D03*
X754839Y1678069D03*
X768463Y1687769D03*
X757161Y1696424D03*
X768733Y1694485D03*
X781441Y118637D03*
X782819Y149471D03*
X780159Y146961D03*
X772270Y153728D03*
X771427Y158026D03*
X782712Y260466D03*
X777408Y256648D03*
X777421Y277962D03*
X779884Y281705D03*
X769790Y296231D03*
X777468Y296315D03*
X769861Y302462D03*
X782641Y310888D03*
X779681Y313053D03*
X770190Y312563D03*
X779121Y303410D03*
Y308755D03*
X780046Y328268D03*
X772119Y333537D03*
X771964Y339716D03*
X781812Y341863D03*
X779118Y341749D03*
X769000Y364000D03*
X776500Y371000D03*
X784500Y367500D03*
X771512Y386862D03*
X775388Y390862D03*
X770000Y380787D03*
X777612Y403505D03*
X771512Y390862D03*
X780295Y403538D03*
X784498Y396353D03*
X782700Y415284D03*
X773181Y415197D03*
X773233Y409154D03*
X783256Y409340D03*
X770159Y410257D03*
X783770Y422454D03*
X772610Y434690D03*
X780877Y427344D03*
X771718Y426804D03*
X780877Y423344D03*
X783821Y431534D03*
X780877Y431368D03*
X772677Y451374D03*
X780577Y435564D03*
X780877Y443344D03*
Y447344D03*
X780977Y459524D03*
X780877Y463344D03*
Y455344D03*
X783377Y451344D03*
X780877Y475344D03*
X780759Y479344D03*
X783877Y475344D03*
X772427D03*
X783759Y479344D03*
X780877Y483344D03*
X772390Y491047D03*
X772427Y487344D03*
X783358Y495344D03*
X783351Y499221D03*
X771039Y511292D03*
X775100Y502504D03*
X772427Y495344D03*
X777166Y504477D03*
X774998Y511306D03*
X774964Y514204D03*
X772100Y532700D03*
X777200Y530250D03*
X772000Y529862D03*
X781699Y536425D03*
X772000Y545862D03*
X776345Y545733D03*
X777754Y558740D03*
X773463Y563455D03*
X778747Y572269D03*
X779448Y632498D03*
X772459Y655290D03*
X771553Y677963D03*
X777750Y767300D03*
Y771100D03*
X783280Y1296009D03*
X778030Y1296259D03*
X780530D03*
X783280Y1298509D03*
X785520Y1292160D03*
X769439Y1313948D03*
X783280Y1301009D03*
X769439Y1319948D03*
Y1322948D03*
Y1316948D03*
X770881Y1343344D03*
X782115Y1334173D03*
X770881Y1345844D03*
X774646Y1516441D03*
X772906Y1522901D03*
X774616Y1520361D03*
X778850Y1556133D03*
X781850D03*
Y1559133D03*
Y1562133D03*
Y1565133D03*
X778850Y1559133D03*
Y1562133D03*
Y1565133D03*
X771450Y1577333D03*
X781850Y1568133D03*
Y1571133D03*
X778850Y1568133D03*
Y1571133D03*
X771550Y1587133D03*
X774420Y1587284D03*
X785181Y120947D03*
X792681D03*
X790181D03*
X787681D03*
X783941Y118637D03*
X786441D03*
X788941D03*
X785529Y270459D03*
X798205Y279146D03*
X794058Y301569D03*
X793221Y296062D03*
X793897Y309026D03*
X793855Y305316D03*
X798493Y301377D03*
X795921Y312662D03*
X787500Y328362D03*
X799226Y328467D03*
X791726D03*
X783726D03*
X785674Y342279D03*
X788806Y342236D03*
X791403Y342262D03*
X793951Y342224D03*
X795685Y357498D03*
X792302Y357537D03*
X798312Y372571D03*
X796021Y395924D03*
X797000Y404000D03*
X786571Y403455D03*
X785923Y419194D03*
X787000Y407500D03*
X796283Y415344D03*
Y419344D03*
X786877Y427344D03*
X796283Y423344D03*
Y431344D03*
X783877Y427344D03*
X796283D03*
X786999Y435476D03*
X797252Y443344D03*
X786877D03*
X796333Y435344D03*
X786203Y447054D03*
X783877Y435444D03*
X797197Y447344D03*
X786887Y451344D03*
X797252D03*
X797322Y463344D03*
X786825Y459518D03*
X786755Y455524D03*
X797252Y455344D03*
X797326Y479344D03*
X786877Y471344D03*
X797463Y476159D03*
X786877Y475344D03*
X786440Y480769D03*
X797405Y487464D03*
X797326Y483344D03*
X787092Y490681D03*
X786358Y483566D03*
X786102Y507536D03*
X787446Y495344D03*
X787279Y499238D03*
X790503Y501826D03*
X799450Y511801D03*
X800674Y504130D03*
X789125Y529425D03*
X800500Y540500D03*
X794357Y559996D03*
X785919Y559660D03*
X792782Y565323D03*
X791723Y574946D03*
X799742Y628983D03*
X789135Y617097D03*
X783653Y631671D03*
X787591Y631785D03*
X788537Y734410D03*
X793131Y734310D03*
X784543Y734510D03*
X791308Y766871D03*
X789020Y1292160D03*
X792520D03*
X796020D03*
X794273Y1354600D03*
Y1357600D03*
Y1364500D03*
Y1361500D03*
X784669Y1462178D03*
X796955Y1487468D03*
X788710Y1488821D03*
X784277Y1504569D03*
Y1500632D03*
Y1508506D03*
Y1512443D03*
X791867Y1524254D03*
X784850Y1556133D03*
X796850D03*
X790850D03*
X787850D03*
X793850D03*
X784850Y1559133D03*
Y1562133D03*
Y1565133D03*
X796850Y1559133D03*
Y1562133D03*
Y1565133D03*
X787850Y1559133D03*
Y1562133D03*
Y1565133D03*
X793850Y1559133D03*
X790850D03*
X793850Y1562133D03*
X790850D03*
X793850Y1565133D03*
X790850D03*
X799150Y1581379D03*
X784850Y1568133D03*
Y1571133D03*
X787850Y1568133D03*
Y1571133D03*
X793850Y1568133D03*
X790850D03*
X793850Y1571133D03*
X790850D03*
X796650Y1583347D03*
X803302Y265848D03*
X812867Y278860D03*
X810139Y274098D03*
X804330Y281380D03*
X801341Y279141D03*
X799935Y286823D03*
X799113Y297733D03*
X803893Y301969D03*
X805871Y304812D03*
X806461Y310610D03*
X808617Y330102D03*
X806117D03*
X812070Y341590D03*
X803410Y341572D03*
X803500Y366000D03*
X802660Y381020D03*
X802462Y387756D03*
X807564Y403805D03*
X811224Y395974D03*
X803412Y403978D03*
X813148Y403908D03*
X805425Y395502D03*
X813252Y427060D03*
X802270Y435372D03*
X802459Y443218D03*
X813208Y435344D03*
X812895Y449802D03*
X813114Y443344D03*
X802533Y449802D03*
X812983Y463578D03*
X813114Y459344D03*
X801552Y463318D03*
X802752Y459344D03*
X813114Y455344D03*
X812983Y471344D03*
Y476159D03*
X801874Y471344D03*
X802752Y480159D03*
X812983D03*
X813000Y484862D03*
X801762Y495344D03*
X802752Y487344D03*
X801753Y491344D03*
X813187Y498362D03*
X813114Y495344D03*
X802250Y500504D03*
X801857Y508031D03*
X805940Y534500D03*
X805341Y578059D03*
X805199Y620347D03*
X804863Y626789D03*
X805150Y623843D03*
X807451Y767299D03*
X807127Y770958D03*
X799280Y1296009D03*
X802030Y1296259D03*
X804530D03*
X807601Y1299241D03*
X799280Y1298509D03*
Y1301009D03*
X801614Y1339062D03*
X811771Y1355488D03*
X799071Y1350088D03*
X807866Y1369177D03*
X805366Y1367093D03*
X802866D03*
X807866Y1366677D03*
X808714Y1490376D03*
Y1487376D03*
Y1506784D03*
Y1519784D03*
Y1509784D03*
Y1516784D03*
X802150Y1570633D03*
Y1578633D03*
Y1582833D03*
X810150Y1574633D03*
X813150Y1579410D03*
Y1570633D03*
X810050Y1584033D03*
X802150Y1594633D03*
X810850Y1587733D03*
X810150Y1590633D03*
X813049D03*
X802700Y1587183D03*
X810150Y1602633D03*
Y1598633D03*
X802150Y1606633D03*
X819321Y56961D03*
X823115Y115223D03*
X820901Y147112D03*
X814571Y145952D03*
X814532Y139851D03*
X822635Y165468D03*
X825332Y166862D03*
X813676Y266065D03*
X823067Y273225D03*
X823038Y276301D03*
X819828Y288063D03*
X827621Y302962D03*
X822689Y305148D03*
X826915Y311842D03*
X822252Y309973D03*
X816232Y341584D03*
X818677Y356405D03*
X826765Y356334D03*
X817780Y366905D03*
X823778Y376378D03*
X818157Y381020D03*
X816991Y395337D03*
X820018Y403710D03*
X816281Y403814D03*
X828286Y401567D03*
X824653Y405347D03*
X817497Y415344D03*
X827341Y419344D03*
X817497D03*
X827341Y415344D03*
X817497Y427060D03*
X826474Y431344D03*
X816239Y435344D03*
X817497Y431060D03*
X826474Y435344D03*
X816117Y443552D03*
X816236Y439279D03*
X816109Y449802D03*
X822878Y446425D03*
X816109Y455344D03*
X816000Y463578D03*
X816170Y458524D03*
X826912Y475989D03*
X816109Y471344D03*
X816409Y467568D03*
X817393Y491594D03*
X830212Y483892D03*
X826472Y483896D03*
X827000Y489055D03*
X817996Y496219D03*
X828259Y501027D03*
X824380Y517595D03*
X827237Y550771D03*
X817849Y550871D03*
X820620Y550846D03*
X824366Y552444D03*
X827832Y554269D03*
X814489Y558082D03*
X825200Y580300D03*
X815287Y580401D03*
X820617Y641273D03*
X816732Y629198D03*
X815753Y644219D03*
X817900Y649012D03*
X822579Y760169D03*
X822218Y756979D03*
X822794Y767511D03*
X825390Y770020D03*
X822794Y777511D03*
X816550Y766871D03*
X822625Y763529D03*
X822794Y772511D03*
Y775011D03*
X825061Y764884D03*
X822864Y783262D03*
X822772Y788359D03*
X822790Y785838D03*
X822883Y780334D03*
X822982Y791245D03*
X822555Y807409D03*
X822794Y797511D03*
Y800011D03*
Y795011D03*
X822494Y802941D03*
X823927Y907676D03*
X823958Y936140D03*
X826958D03*
X823958Y939140D03*
X826958D03*
X827088Y933387D03*
X824036Y933394D03*
X826953Y930432D03*
X824003Y930319D03*
X828109Y1234504D03*
X826728Y1246315D03*
X824444Y1249420D03*
X828246Y1266501D03*
X824714Y1490376D03*
Y1487376D03*
X816690Y1490376D03*
Y1487376D03*
X824714Y1500376D03*
Y1497376D03*
Y1506784D03*
X816717Y1500388D03*
X816729Y1497364D03*
X816693Y1506784D03*
X824714Y1519784D03*
Y1509784D03*
Y1516784D03*
X816706Y1519820D03*
X816693Y1516784D03*
X816694Y1509796D03*
X824714Y1529784D03*
Y1526784D03*
X816714Y1529784D03*
Y1526784D03*
X823850Y1556133D03*
X820850D03*
X826850D03*
X820850Y1565133D03*
Y1562133D03*
Y1559133D03*
X826850Y1565133D03*
X823850D03*
X826850Y1562133D03*
Y1559133D03*
X823850Y1562133D03*
Y1559133D03*
X820850Y1571133D03*
Y1568133D03*
X826850Y1571133D03*
Y1568133D03*
X823850Y1571133D03*
Y1568133D03*
X816150Y1587284D03*
X828601Y61752D03*
X836780Y68008D03*
X839899Y87248D03*
X841585Y94181D03*
X837251Y93221D03*
X839361Y114862D03*
X835115Y115223D03*
X845221Y135862D03*
Y129362D03*
X829115Y147123D03*
X838221Y163862D03*
X835221D03*
X842721Y181362D03*
X837161Y213207D03*
X844527Y204968D03*
X838821Y206872D03*
X837161Y218212D03*
X837501Y229642D03*
X836305Y268624D03*
X836181Y275686D03*
X830418Y311865D03*
X837754Y335345D03*
X829800Y331013D03*
X840457Y335368D03*
X842257Y350376D03*
X829344Y356224D03*
X833219Y375992D03*
X840357Y382813D03*
X833097Y393000D03*
X837912Y401545D03*
X834426Y401504D03*
X833000Y409500D03*
X838500D03*
X837847Y405347D03*
X833807Y423257D03*
X841809Y423219D03*
X838000Y423362D03*
X829106Y439279D03*
X842825Y448739D03*
X828979Y449802D03*
X834106Y439279D03*
X828714Y443552D03*
X833800Y444700D03*
X828751Y455344D03*
Y463578D03*
X834251Y455578D03*
X828751Y459344D03*
X832224Y450328D03*
X831381Y455167D03*
X833751Y463578D03*
X842825Y452739D03*
X828751Y471344D03*
Y467568D03*
X838575Y477554D03*
X839200Y467900D03*
X830046Y476031D03*
X838561Y484071D03*
X841854Y504972D03*
X833000Y503500D03*
X831798Y515314D03*
X838342Y514610D03*
X839061Y555808D03*
X841660Y558200D03*
X835519Y580056D03*
X831018Y583076D03*
X835059Y660940D03*
X837391Y659820D03*
X831505Y897291D03*
X831582Y905153D03*
X832347Y1251703D03*
X844250Y1266759D03*
X832274Y1277301D03*
X832342Y1274626D03*
X833756Y1330156D03*
X834017Y1336252D03*
X833963Y1339464D03*
X838963Y1345974D03*
X833853Y1345833D03*
X841039Y1358082D03*
X839244Y1352094D03*
X841472Y1365050D03*
X835850Y1556133D03*
X829850D03*
X832850D03*
X838850D03*
X832850Y1565133D03*
X835850D03*
X832850Y1562133D03*
X835850D03*
X832850Y1559133D03*
X835850D03*
X829850Y1565133D03*
Y1562133D03*
Y1559133D03*
X838850Y1565133D03*
Y1562133D03*
Y1559133D03*
X841150Y1581379D03*
X832850Y1571133D03*
X835850D03*
X832850Y1568133D03*
X835850D03*
X829850Y1571133D03*
Y1568133D03*
X838650Y1583347D03*
X850016Y87341D03*
X843856Y87711D03*
X847473Y94754D03*
X854221Y135862D03*
Y129362D03*
X854201Y143062D03*
X848745Y160137D03*
X845721Y181362D03*
X856213Y191545D03*
X855859Y212425D03*
X855934Y215375D03*
X847581Y232222D03*
X853621Y269057D03*
X853829Y262057D03*
X846189Y281419D03*
X856244Y286447D03*
X843504Y287602D03*
X855481Y299692D03*
X860071Y304850D03*
X843308Y335550D03*
X857187Y342210D03*
X848030Y338461D03*
X850155Y335042D03*
X852303Y337488D03*
X852177Y341882D03*
X848425Y378089D03*
X854552Y381000D03*
X854190Y404035D03*
X855722Y416606D03*
X846000Y418862D03*
X854239Y412911D03*
X851517Y411745D03*
X846000Y423362D03*
X845986Y429413D03*
X857942Y448575D03*
X845100Y440100D03*
X857887Y459847D03*
X848500Y452128D03*
X847686Y475915D03*
X847303Y485788D03*
X846104Y494661D03*
X847518Y490905D03*
X846411Y482128D03*
X849772Y494585D03*
X852209Y507211D03*
X855497Y507205D03*
X849351Y499070D03*
X848097Y503315D03*
X855837Y519713D03*
X847941Y538325D03*
X845094Y535110D03*
X844741Y543864D03*
X843655Y555683D03*
X847435Y555496D03*
X856647Y616786D03*
X854484Y647436D03*
X848999Y644995D03*
X846931Y1291468D03*
X846895Y1295981D03*
X845801Y1287776D03*
X851500Y1302000D03*
X851400Y1305499D03*
X852811Y1313450D03*
X850684Y1310000D03*
X852955Y1320320D03*
X856500Y1321500D03*
X853100Y1331688D03*
X856500Y1330500D03*
X852780Y1338365D03*
X856500Y1339500D03*
Y1348500D03*
X844150Y1578633D03*
Y1570633D03*
Y1582833D03*
X852150Y1574633D03*
X855150Y1579410D03*
Y1570633D03*
X852050Y1584033D03*
X844150Y1594633D03*
X852850Y1587733D03*
X852150Y1590633D03*
X855049D03*
X844700Y1587183D03*
X852150Y1602633D03*
Y1598633D03*
X844150Y1606633D03*
X858630Y60293D03*
X863343Y90021D03*
X865912Y89252D03*
X870892Y131868D03*
X871145Y163862D03*
X875170Y185113D03*
X867529Y231788D03*
X863104Y273103D03*
X868104D03*
X867701Y267537D03*
X863230Y280001D03*
X866619Y286801D03*
X870672Y295485D03*
X870008Y302273D03*
X872508D03*
X871099Y323000D03*
X864342Y330858D03*
X860942D03*
X860587Y342210D03*
X860372Y375195D03*
X866168Y374774D03*
X871190Y382230D03*
X858925Y398537D03*
X864826Y411557D03*
X870220Y430424D03*
X870826Y423423D03*
X870064Y427703D03*
X859500Y429362D03*
X863420D03*
X859469Y425293D03*
X860541Y446089D03*
X860328Y475162D03*
X858288Y467048D03*
X860280Y488636D03*
X860299Y491620D03*
X864361Y493001D03*
X860508Y497772D03*
X862987Y507305D03*
X860341Y503154D03*
X860658Y515961D03*
X867356Y558714D03*
X867733Y575522D03*
X864590Y642420D03*
X870590D03*
X866727Y650739D03*
X866549Y748027D03*
X869275Y750472D03*
X873175D03*
X868496Y776516D03*
X868539Y790882D03*
X870591Y785437D03*
X865466Y790581D03*
Y785581D03*
Y788081D03*
Y783081D03*
X865394Y801244D03*
X865466Y793081D03*
Y795581D03*
Y798081D03*
X865569Y806045D03*
Y808545D03*
X863369Y827461D03*
X863344Y824713D03*
X863372Y833469D03*
Y830718D03*
X867651Y836820D03*
X867646Y833388D03*
X863671Y839062D03*
X865601Y841219D03*
X865109Y850795D03*
X864768Y844815D03*
X864140Y856052D03*
X864020Y859972D03*
X864106Y863534D03*
X864003Y866609D03*
X866005Y941554D03*
X863055Y941441D03*
X863010Y947262D03*
X866010D03*
X863010Y950262D03*
X866010D03*
X866140Y944509D03*
X863088Y944516D03*
X862044Y1249687D03*
X866294Y1255903D03*
X874989Y1410441D03*
X863745Y1444560D03*
X871214Y1466542D03*
X865850Y1556133D03*
X871850D03*
X862850D03*
X868850D03*
X865850Y1565133D03*
Y1562133D03*
Y1559133D03*
X862850Y1565133D03*
Y1562133D03*
Y1559133D03*
X868850Y1565133D03*
X871850D03*
X868850Y1562133D03*
X871850D03*
X868850Y1559133D03*
X871850D03*
X865850Y1571133D03*
Y1568133D03*
X862850Y1571133D03*
Y1568133D03*
X868850Y1571133D03*
X871850D03*
X868850Y1568133D03*
X871850D03*
X858150Y1587284D03*
X876696Y176862D03*
Y171362D03*
X887521D03*
Y176862D03*
X889351Y195489D03*
X878328Y183169D03*
X878221Y187449D03*
X887130Y183169D03*
X884986Y198829D03*
X881354Y267407D03*
X884004Y278712D03*
Y274482D03*
X885764Y284361D03*
X877448Y284825D03*
X884004Y271332D03*
X874244Y287047D03*
X873172Y295485D03*
X888000Y293000D03*
X877640Y315789D03*
X873884Y447991D03*
Y450491D03*
X885916Y653912D03*
X883731Y651690D03*
X884410Y794332D03*
X883633Y790336D03*
X883776Y786814D03*
X877459Y802356D03*
X875412Y797350D03*
X882582Y1075083D03*
X879582D03*
X876582D03*
X873582D03*
X882582Y1061983D03*
X879582D03*
X876582D03*
Y1071533D03*
Y1068533D03*
Y1065533D03*
X873582D03*
Y1068533D03*
Y1071533D03*
Y1061983D03*
X886707Y1229920D03*
Y1232920D03*
X881807Y1238920D03*
X876923Y1239520D03*
X886707Y1235920D03*
X881694Y1229763D03*
Y1232763D03*
Y1235763D03*
X876907Y1235586D03*
Y1232586D03*
Y1229586D03*
X881807Y1241920D03*
X877936Y1312336D03*
X883379Y1417881D03*
X875039Y1407246D03*
X886362Y1428973D03*
X884399Y1431507D03*
X879424Y1425001D03*
X883279Y1421726D03*
X883562Y1440356D03*
X881987Y1449608D03*
X887519Y1444625D03*
X877226Y1441585D03*
X887117Y1436735D03*
X877850Y1556133D03*
X874850D03*
X880850D03*
X874850Y1565133D03*
X877850D03*
X880850D03*
X874850Y1562133D03*
X877850D03*
X880850D03*
X874850Y1559133D03*
X877850D03*
X880850D03*
X886150Y1578633D03*
Y1570633D03*
Y1582833D03*
X883150Y1581379D03*
X874850Y1571133D03*
X877850D03*
X874850Y1568133D03*
X877850D03*
X886150Y1594633D03*
X880650Y1583347D03*
X886700Y1587183D03*
X886150Y1606633D03*
X891621Y207162D03*
X888930Y206823D03*
X891621Y209662D03*
X888930Y209323D03*
X896621Y207162D03*
X894121D03*
Y209662D03*
X896621D03*
X892376Y466430D03*
X899000Y481038D03*
X888372Y547518D03*
X902376Y590172D03*
X900323Y604377D03*
X900301Y828248D03*
Y831221D03*
X899500Y853000D03*
X901000Y909000D03*
X901842Y936863D03*
X903925Y948500D03*
X889273Y1134470D03*
X902382Y1137558D03*
X891996Y1149707D03*
X900280Y1150769D03*
X902482Y1140558D03*
X888247Y1219520D03*
Y1222520D03*
X891247D03*
Y1219520D03*
X888247Y1225520D03*
X896974Y1232869D03*
Y1235869D03*
X896907Y1238920D03*
X896974Y1229869D03*
X891247Y1225520D03*
X896907Y1241920D03*
X892000Y1307500D03*
X888854Y1337936D03*
X890620Y1342990D03*
X900885Y1435041D03*
X900808Y1437798D03*
X902377Y1456465D03*
X904850Y1556133D03*
X894150Y1574633D03*
X897150Y1579410D03*
Y1570633D03*
X894050Y1584033D03*
X894150Y1590633D03*
X894850Y1587733D03*
X897049Y1590633D03*
X900150Y1587284D03*
X894150Y1602633D03*
Y1598633D03*
X917387Y184114D03*
X908621Y188899D03*
X910267Y242658D03*
X910093Y246015D03*
X916268Y269859D03*
X909023Y294734D03*
X910752Y286141D03*
X913512Y486743D03*
X903340Y505105D03*
X917582Y549564D03*
X909747Y579695D03*
X911980Y585280D03*
X910731Y590251D03*
X905526Y594657D03*
X910535Y619251D03*
X906706Y614062D03*
X909747Y628426D03*
X915334Y639166D03*
X908823Y655116D03*
X906274Y654921D03*
X909320Y663930D03*
X907207Y667646D03*
X906345Y742414D03*
X904535Y744639D03*
X906387Y821221D03*
Y815721D03*
X906313Y825095D03*
X903149Y825094D03*
X917000Y853000D03*
X907000Y899777D03*
X913000Y909000D03*
X917000D03*
Y918500D03*
X905000D03*
X915575Y948500D03*
X910000Y954500D03*
X912425Y948500D03*
X907075D03*
X910000Y957500D03*
X912500Y963309D03*
X907500D03*
X909000Y974000D03*
Y982000D03*
X911041Y979459D03*
X909000Y977491D03*
X919779Y1155658D03*
X915053Y1219520D03*
Y1222520D03*
X912053D03*
Y1219520D03*
Y1225520D03*
X915053D03*
X910707Y1229920D03*
Y1232920D03*
X905007Y1238920D03*
X910707Y1235920D03*
X905008Y1229940D03*
Y1232940D03*
Y1235940D03*
X905007Y1241920D03*
X917112Y1266300D03*
X917127Y1275251D03*
X917396Y1271025D03*
X917158Y1279451D03*
X917341Y1283775D03*
X916895Y1292330D03*
X916945Y1296713D03*
X917034Y1288235D03*
X912500Y1310000D03*
X914333Y1322700D03*
X914462Y1329351D03*
X914355Y1340726D03*
X914276Y1347550D03*
X913270Y1440429D03*
X910041Y1440536D03*
X907031Y1457231D03*
X909473Y1448779D03*
X910850Y1556133D03*
X907850D03*
X916850D03*
X913850D03*
X907850Y1559133D03*
Y1562133D03*
X910850Y1559133D03*
Y1562133D03*
X907850Y1565133D03*
X910850D03*
X904850Y1559133D03*
Y1562133D03*
Y1565133D03*
X913850Y1559133D03*
Y1562133D03*
Y1565133D03*
X916850Y1559133D03*
Y1562133D03*
Y1565133D03*
X907850Y1568133D03*
Y1571133D03*
X910850Y1568133D03*
Y1571133D03*
X904850Y1568133D03*
Y1571133D03*
X913850Y1568133D03*
Y1571133D03*
X916850Y1568133D03*
Y1571133D03*
X915991Y1667328D03*
X922128Y182486D03*
X923386Y193563D03*
X932129Y244103D03*
X922341Y263875D03*
X923103Y362852D03*
X924724Y372211D03*
X919294Y374503D03*
X921318Y372475D03*
X920018Y362877D03*
X921430Y507156D03*
X921367Y503407D03*
X924430Y507156D03*
X924367Y503407D03*
X922591Y496671D03*
X926730Y540897D03*
X921318Y549357D03*
X920031Y577846D03*
X926449Y577806D03*
X930406Y577308D03*
X923747Y584945D03*
X920989Y614132D03*
X925643Y616620D03*
X920989Y617692D03*
X924987Y622523D03*
X932000Y850500D03*
X920234Y843349D03*
X927777Y843416D03*
X930575Y864075D03*
X918500Y860075D03*
X920897Y881879D03*
X929603Y879000D03*
X920000Y895500D03*
X923000D03*
X925500Y907500D03*
X921000Y921925D03*
X925500Y916500D03*
X929500D03*
X932500Y941500D03*
X919500D03*
X928500D03*
X923500D03*
X926000Y949500D03*
Y946500D03*
X919272Y986782D03*
X920107Y1235920D03*
Y1232920D03*
Y1238920D03*
Y1229920D03*
Y1241920D03*
X924500Y1306000D03*
Y1302000D03*
X918000Y1312500D03*
Y1321500D03*
X925459Y1315352D03*
X925500Y1319000D03*
X922000Y1324000D03*
Y1328000D03*
X931326Y1328467D03*
X931216Y1323050D03*
X918000Y1330500D03*
Y1339500D03*
X922000Y1342000D03*
X925500Y1333000D03*
Y1337000D03*
X922000Y1346000D03*
X922850Y1556133D03*
X919850D03*
X922850Y1559133D03*
Y1562133D03*
Y1565133D03*
X919850Y1559133D03*
Y1562133D03*
Y1565133D03*
X925650Y1581379D03*
X919850Y1568133D03*
Y1571133D03*
X922650Y1583347D03*
X921289Y1666337D03*
X927798Y1660762D03*
X945721Y173389D03*
X943221D03*
Y176389D03*
X945721D03*
X935551Y173329D03*
X938161Y173389D03*
Y176389D03*
X935591Y176049D03*
X940721Y173389D03*
Y176389D03*
X939271Y191419D03*
X935771D03*
X944520Y182094D03*
X936454Y184015D03*
X937267Y189010D03*
X945120Y193264D03*
X938570Y233152D03*
X945380Y233962D03*
X949181Y280131D03*
X939938Y386423D03*
X933390Y386405D03*
X944112Y386593D03*
X941764Y420403D03*
X944264D03*
X933390Y559943D03*
X939613Y562031D03*
X937310Y580755D03*
X941764Y587884D03*
X944264D03*
X935766Y587692D03*
X939511Y597073D03*
X935746Y611573D03*
X935783Y631192D03*
X937580Y655946D03*
X945602Y664653D03*
X934539Y664648D03*
X934339Y668533D03*
X941478Y668648D03*
X939216Y664767D03*
X948644Y811190D03*
X938000Y862620D03*
X943000Y862823D03*
X934925Y891425D03*
X945075Y891500D03*
X938500Y907500D03*
X946500Y915988D03*
X938500Y916500D03*
X934500D03*
X942500Y916340D03*
X942631Y943162D03*
X936960Y942898D03*
X935368Y939182D03*
X944515Y939850D03*
X940000Y973500D03*
Y986500D03*
Y982500D03*
Y977500D03*
X937148Y1134343D03*
X933234Y1145058D03*
X936393Y1148087D03*
X947305Y1150769D03*
X943101Y1219520D03*
Y1222520D03*
X946101D03*
Y1219520D03*
X943101Y1225520D03*
X946101D03*
X945691Y1229920D03*
Y1232920D03*
X940791Y1238920D03*
X935907Y1239520D03*
X945691Y1235920D03*
X940678Y1229763D03*
Y1232763D03*
Y1235763D03*
X935891Y1235586D03*
Y1232586D03*
Y1229586D03*
X940791Y1241920D03*
X940994Y1265636D03*
X941011Y1269499D03*
X941500Y1278059D03*
X941033Y1282115D03*
X946730Y1293219D03*
Y1290719D03*
X940919Y1290152D03*
X940937Y1294191D03*
X941083Y1286156D03*
X947135Y1287403D03*
X945872Y1304541D03*
Y1301500D03*
X945617Y1309500D03*
X935028Y1313769D03*
X935300Y1317525D03*
X939071Y1448219D03*
X949216Y1448337D03*
X944105Y1448317D03*
X946402Y1491204D03*
X943902D03*
X936402D03*
X938902D03*
X941402D03*
X933778D03*
X946402Y1501204D03*
Y1498704D03*
Y1496204D03*
Y1493704D03*
X943902D03*
Y1496204D03*
Y1498704D03*
Y1501204D03*
X936402Y1493704D03*
Y1496204D03*
Y1498704D03*
Y1501204D03*
X938902Y1493704D03*
Y1496204D03*
Y1498704D03*
Y1501204D03*
X941402Y1493704D03*
Y1496204D03*
Y1498704D03*
Y1501204D03*
X933778Y1493704D03*
Y1496204D03*
Y1498704D03*
Y1501204D03*
X936150Y1582233D03*
Y1578233D03*
Y1590233D03*
Y1586233D03*
X943798Y1660762D03*
X948401Y176499D03*
X961407Y205125D03*
X950950Y284662D03*
X947821Y386567D03*
X958158Y449020D03*
X958049Y453912D03*
X958101Y457846D03*
X958255Y465811D03*
X959033Y487289D03*
X957380Y515233D03*
X960054Y516982D03*
X962035Y518988D03*
X954757Y593045D03*
X948156Y593912D03*
X952497Y614080D03*
X951102Y628662D03*
X954362Y633314D03*
Y630061D03*
X954259Y657371D03*
X958299Y659886D03*
X954361Y660215D03*
X957462Y668700D03*
X951886Y804495D03*
X951895Y808163D03*
X951466Y816400D03*
X961592Y821737D03*
X949000Y850500D03*
X951000Y855425D03*
X958000Y865500D03*
Y862000D03*
X949500Y870500D03*
Y886500D03*
X953925Y900500D03*
X951169Y910425D03*
X957075Y906500D03*
X960925D03*
X954500Y915988D03*
X950500Y916150D03*
X948500Y937000D03*
X949407Y1137558D03*
X949507Y1140558D03*
X955958Y1232869D03*
Y1235869D03*
X955891Y1238920D03*
X955958Y1229869D03*
X955891Y1241920D03*
X964669Y1271000D03*
X963500Y1275000D03*
X955000Y1283000D03*
Y1287000D03*
X947650Y1314500D03*
Y1319000D03*
Y1323500D03*
Y1328000D03*
Y1337000D03*
Y1332500D03*
Y1341500D03*
Y1346000D03*
X960313Y1362654D03*
X958306Y1448056D03*
X954541Y1448307D03*
X961566Y1448341D03*
X953902Y1491204D03*
X951402D03*
X948902D03*
X956402D03*
X958902D03*
X961402D03*
X953902Y1501204D03*
Y1498704D03*
Y1496204D03*
Y1493704D03*
X951402Y1501204D03*
Y1498704D03*
Y1496204D03*
Y1493704D03*
X948902Y1501204D03*
Y1498704D03*
Y1496204D03*
Y1493704D03*
X956402D03*
X958902D03*
X961402D03*
X963402Y1501204D03*
X958402D03*
X959584Y1550824D03*
X949195Y1655145D03*
X951798Y1660762D03*
X975691Y161220D03*
X962673Y170263D03*
Y167763D03*
X967943Y204813D03*
X971943D03*
X975749Y202049D03*
X977221Y205399D03*
X964807Y205125D03*
X973997Y320848D03*
X966278Y556736D03*
X964114Y554704D03*
X976528Y801041D03*
Y803541D03*
Y806041D03*
Y808541D03*
X963500Y854719D03*
X973562Y859767D03*
X964075Y900500D03*
X966804Y1155658D03*
X969907Y1219520D03*
Y1222520D03*
X966907D03*
Y1219520D03*
Y1225520D03*
X969907D03*
X969691Y1229920D03*
Y1232920D03*
X963991Y1238920D03*
X969691Y1235920D03*
X963992Y1229940D03*
Y1232940D03*
Y1235940D03*
X979091Y1229920D03*
X963991Y1241920D03*
X964000Y1267000D03*
X966441Y1278145D03*
X972408Y1312557D03*
X973650Y1431424D03*
X969785Y1447987D03*
X967002Y1448013D03*
X964503Y1448097D03*
X969519Y1452784D03*
X973255Y1456714D03*
X975703Y1451367D03*
X967268Y1491204D03*
X969768D03*
X972268D03*
X974768D03*
X977268D03*
X963902D03*
X967268Y1501204D03*
Y1498704D03*
Y1496204D03*
Y1493704D03*
X969768D03*
Y1496204D03*
Y1498704D03*
Y1501204D03*
X972268Y1493704D03*
Y1496204D03*
Y1498704D03*
Y1501204D03*
X974768Y1493704D03*
Y1496204D03*
Y1498704D03*
Y1501204D03*
X977268Y1493704D03*
Y1496204D03*
Y1498704D03*
Y1501204D03*
X963902Y1493704D03*
X962584Y1550824D03*
X990579Y155248D03*
X981112Y161204D03*
X988751Y167541D03*
X986447Y158209D03*
X989605Y175400D03*
X985922Y171861D03*
X985445Y185389D03*
X986021Y195099D03*
X979849Y202049D03*
X983879Y202162D03*
X990221Y199699D03*
X987321Y198599D03*
Y202099D03*
X990221Y206699D03*
Y203199D03*
X987321Y205599D03*
X980406Y218283D03*
X980377Y215740D03*
X978269Y264929D03*
X982455Y260781D03*
Y271443D03*
X978827Y303412D03*
X984509Y303623D03*
X989582Y303563D03*
X988460Y358405D03*
X993460D03*
X984272Y349293D03*
X980346Y353527D03*
X981019Y349387D03*
X992460Y370659D03*
X985668Y389311D03*
X980690Y387784D03*
X984605Y408480D03*
X987581Y408332D03*
X988190Y424626D03*
X983358Y449026D03*
X991664Y446372D03*
X993650Y465315D03*
X988650D03*
X991270Y470212D03*
X990292Y494420D03*
X988125Y485193D03*
X986790Y480140D03*
X987440Y504742D03*
X982806Y498606D03*
X986056Y516014D03*
X994056Y521014D03*
Y516014D03*
Y526074D03*
Y531074D03*
X992125Y1061434D03*
X989125D03*
X986125D03*
X983125D03*
X992125Y1064984D03*
Y1067984D03*
X989125D03*
Y1064984D03*
X992125Y1074534D03*
Y1070984D03*
X989125D03*
Y1074534D03*
X986125D03*
X983125D03*
X979091Y1235920D03*
Y1232920D03*
Y1238920D03*
Y1241920D03*
X985396Y1268154D03*
X982665Y1265474D03*
X978318Y1263128D03*
X988242Y1273193D03*
X979228Y1297918D03*
X982000Y1307500D03*
X978026Y1459998D03*
X980779Y1451545D03*
X990634Y1491204D03*
X979768D03*
X982268D03*
X984768D03*
X987268D03*
X990634Y1493704D03*
Y1496204D03*
Y1498704D03*
Y1501204D03*
X979768Y1493704D03*
X982268D03*
X984768D03*
X987268D03*
X986768Y1501204D03*
X981768D03*
X991196Y1550840D03*
X1006221Y164799D03*
X1002721D03*
X1005307Y155043D03*
X995181Y157689D03*
X999580Y154895D03*
X994257D03*
X996416Y176579D03*
X1002921Y178799D03*
X1002827Y172479D03*
X999221Y189299D03*
X1002721D03*
X1006161Y189019D03*
X1008918Y192994D03*
X1008121Y203525D03*
X1000611Y215039D03*
X1005641Y214969D03*
X1001196Y223898D03*
X1008707Y230423D03*
X997300Y234876D03*
X1006468Y301857D03*
X1003460Y358405D03*
X998460D03*
X994409Y349813D03*
X1000460Y369535D03*
X996889Y374156D03*
X1007080Y367087D03*
X999320Y394480D03*
X1006763Y396206D03*
X1003651Y433426D03*
X998859Y437141D03*
X998359Y451675D03*
X994900Y446192D03*
X998359Y462675D03*
Y457175D03*
X1003909Y454662D03*
Y460162D03*
X998359Y479175D03*
Y468175D03*
Y473675D03*
X996320Y470364D03*
X998359Y484675D03*
X1007077Y484937D03*
X998326Y499675D03*
X995530Y500034D03*
X1006206Y510304D03*
X1002056Y521014D03*
Y516014D03*
Y526074D03*
Y531074D03*
X1004527Y541924D03*
Y553224D03*
X1005270Y625710D03*
X1003090Y1037329D03*
X999350Y1310500D03*
Y1315000D03*
Y1319420D03*
Y1323840D03*
Y1328260D03*
Y1332740D03*
Y1341580D03*
Y1337160D03*
Y1346000D03*
X995500Y1368000D03*
X998000Y1365500D03*
X995000Y1362000D03*
X1000634Y1491204D03*
X998134D03*
X995634D03*
X993134D03*
X1003134D03*
X1005634D03*
X993134Y1496204D03*
Y1493704D03*
X1003134D03*
X1005634D03*
X1000634Y1501204D03*
Y1498704D03*
Y1496204D03*
Y1493704D03*
X998134Y1501204D03*
Y1498704D03*
Y1496204D03*
Y1493704D03*
X995634Y1501204D03*
Y1498704D03*
Y1496204D03*
Y1493704D03*
X993134Y1501204D03*
Y1498704D03*
X1005134Y1501204D03*
X994196Y1550840D03*
X1009721Y164799D03*
X1013221D03*
X1014301Y179699D03*
X1017201D03*
X1019901Y179799D03*
X1011991Y189019D03*
X1014901Y189299D03*
X1017701Y189059D03*
X1011120Y198114D03*
X1020521Y194499D03*
X1011068Y207667D03*
X1021440Y226423D03*
X1019356Y222423D03*
X1010909Y213708D03*
X1011721Y233699D03*
X1019531Y230423D03*
X1018220Y243638D03*
X1015220D03*
X1009220D03*
X1014828Y268427D03*
Y258970D03*
X1013396Y280806D03*
X1011423Y282889D03*
X1023110Y287311D03*
X1017835Y291236D03*
X1023000Y298311D03*
X1016764Y350082D03*
X1010252Y363440D03*
X1009815Y404896D03*
X1020748Y420902D03*
Y425902D03*
X1023420Y462921D03*
X1017220Y464155D03*
X1023515Y454397D03*
X1019205Y457687D03*
X1023420Y468039D03*
X1017350Y472155D03*
X1022874Y474545D03*
X1019210Y480155D03*
X1013306Y518146D03*
Y532501D03*
X1017718Y541201D03*
X1019161Y554757D03*
X1024161D03*
X1017961Y545074D03*
X1009611Y550074D03*
Y545074D03*
X1021425Y568614D03*
X1012925Y558000D03*
X1011602Y568473D03*
X1016000Y563107D03*
X1019261Y571324D03*
X1007587Y761546D03*
Y772480D03*
Y775880D03*
Y764946D03*
Y783482D03*
Y786882D03*
Y794484D03*
Y797884D03*
X1016000Y1303000D03*
X1009905Y1305500D03*
X1009896Y1301500D03*
X1013605Y1316050D03*
X1013529Y1318950D03*
X1012500Y1322500D03*
Y1328500D03*
Y1341580D03*
X1013500Y1332740D03*
Y1337160D03*
X1016000Y1361000D03*
X1012500Y1347500D03*
X1021500Y1491204D03*
X1019000D03*
X1016500D03*
X1014000D03*
X1008134D03*
X1010634D03*
X1021500Y1501204D03*
Y1498704D03*
Y1496204D03*
Y1493704D03*
X1019000Y1501204D03*
Y1498704D03*
Y1496204D03*
Y1493704D03*
X1016500Y1501204D03*
Y1498704D03*
Y1496204D03*
Y1493704D03*
X1014000D03*
Y1496204D03*
Y1498704D03*
Y1501204D03*
X1008134Y1493704D03*
X1010634D03*
X1010134Y1501204D03*
X1022796Y1550840D03*
X1022801Y179799D03*
X1027690Y237902D03*
X1024220Y243638D03*
X1033590Y298311D03*
Y287311D03*
X1029200Y351614D03*
X1022674Y357848D03*
X1028146Y355960D03*
X1034214Y351601D03*
X1029601Y394387D03*
X1034855Y411704D03*
X1034409Y429618D03*
X1024443Y424051D03*
X1039015Y444404D03*
X1034899D03*
X1025830Y449022D03*
X1023320Y451112D03*
X1035860Y485976D03*
X1027504Y485637D03*
X1024509Y500168D03*
X1024546Y511254D03*
X1037254Y521014D03*
X1036708Y514883D03*
X1037254Y526074D03*
X1025631Y540104D03*
X1036021Y534990D03*
X1030000Y554500D03*
X1034412Y567416D03*
X1031000Y568500D03*
X1028500Y563000D03*
X1024000D03*
X1029431Y587342D03*
X1032055Y587260D03*
X1028540Y621000D03*
X1035269Y735474D03*
X1032736Y735320D03*
X1030190Y735023D03*
X1025493Y761819D03*
X1035026Y756009D03*
X1036427Y770532D03*
X1038867Y774960D03*
X1025493Y765719D03*
X1033236Y1279287D03*
X1033184Y1275996D03*
X1036411Y1275658D03*
X1036463Y1278949D03*
X1024000Y1491204D03*
X1026500D03*
X1029000D03*
X1031500D03*
X1034000D03*
X1024000Y1501204D03*
Y1498704D03*
Y1496204D03*
Y1493704D03*
X1026500D03*
X1029000D03*
X1031500D03*
X1034000D03*
X1033500Y1501204D03*
X1028500D03*
X1025796Y1550840D03*
X1046384Y269814D03*
X1049451Y266747D03*
X1040060Y313528D03*
X1051873Y305482D03*
X1049573Y406586D03*
X1042015Y444404D03*
X1047515D03*
X1043377Y452740D03*
X1040836Y510894D03*
X1045254Y516014D03*
Y534074D03*
Y526074D03*
X1043991Y540979D03*
X1047335Y549574D03*
X1047200Y543090D03*
X1037301Y539685D03*
X1039407Y547723D03*
X1039000Y555000D03*
X1039718Y563268D03*
X1042628Y556845D03*
X1050956Y591090D03*
X1040626Y668441D03*
X1042389Y733426D03*
X1044056Y736188D03*
X1040915Y766870D03*
X1037566Y1047135D03*
X1037895Y1251517D03*
X1039546Y1275474D03*
X1039598Y1278765D03*
X1042855Y1275552D03*
X1042649Y1279152D03*
X1047366Y1491204D03*
X1044866D03*
X1037366D03*
X1042366D03*
X1039866D03*
X1049866D03*
X1047366Y1498704D03*
Y1496204D03*
Y1493704D03*
X1044866Y1496204D03*
Y1493704D03*
X1037366D03*
Y1496204D03*
Y1498704D03*
X1047366Y1501204D03*
X1044866D03*
Y1498704D03*
X1042366Y1501204D03*
Y1498704D03*
Y1496204D03*
Y1493704D03*
X1039866Y1501204D03*
Y1498704D03*
Y1496204D03*
Y1493704D03*
X1037366Y1501204D03*
X1049866Y1493704D03*
X1051866Y1501204D03*
X1053290Y1652082D03*
X1045545Y1663089D03*
X1066231Y165078D03*
Y167578D03*
X1062704Y270875D03*
X1056941Y259176D03*
X1054613Y261586D03*
X1062923Y295053D03*
X1063356Y318297D03*
X1055934Y388988D03*
X1068143Y380188D03*
X1055934Y381988D03*
X1052505Y406576D03*
X1057798Y427059D03*
Y429618D03*
X1062642Y444859D03*
X1062640Y449155D03*
X1062741Y457959D03*
X1057276Y458155D03*
X1062173Y479655D03*
X1062873Y490180D03*
X1055905Y492537D03*
X1062250Y484672D03*
X1056960Y482262D03*
X1057450Y509242D03*
X1058231Y523238D03*
X1060719Y512359D03*
Y516059D03*
X1061817Y736362D03*
X1065154Y736282D03*
X1057057Y767299D03*
Y771099D03*
X1055171Y1307203D03*
Y1311203D03*
X1058143Y1433809D03*
X1065732Y1491204D03*
X1063232D03*
X1060732D03*
X1052366D03*
X1054866D03*
X1057366D03*
X1065732Y1501204D03*
Y1498704D03*
Y1496204D03*
Y1493704D03*
X1063232Y1501204D03*
Y1498704D03*
Y1496204D03*
Y1493704D03*
X1060732D03*
Y1496204D03*
Y1498704D03*
Y1501204D03*
X1052366Y1493704D03*
X1054866D03*
X1057366D03*
X1056866Y1501204D03*
X1057396Y1550840D03*
X1054396D03*
X1071698Y270702D03*
X1078823Y269400D03*
X1071656Y366726D03*
X1078400Y391226D03*
X1074654Y380188D03*
X1078400Y383226D03*
X1074249Y387795D03*
X1082866Y403068D03*
X1074736Y396929D03*
X1072135Y396908D03*
X1072738Y411322D03*
Y416763D03*
Y421922D03*
X1072673Y428791D03*
X1077873Y463444D03*
X1080453Y457959D03*
X1071470Y475525D03*
X1080640Y467000D03*
X1080574Y471500D03*
X1071667D03*
Y467000D03*
X1080416Y482772D03*
X1080420Y487782D03*
X1071710Y483655D03*
Y488782D03*
X1081730Y509172D03*
X1078499Y648202D03*
X1072232Y667749D03*
X1068378Y736795D03*
X1070616Y766870D03*
X1076903Y1300361D03*
Y1302861D03*
X1079403D03*
Y1300361D03*
X1074403Y1302861D03*
Y1300361D03*
X1076903Y1305361D03*
X1079403D03*
X1074403D03*
Y1307861D03*
Y1310361D03*
Y1312861D03*
X1079403Y1307861D03*
Y1310361D03*
Y1312861D03*
X1076903D03*
Y1310361D03*
Y1307861D03*
X1079403Y1315361D03*
X1076903D03*
Y1317861D03*
X1079403D03*
X1074403D03*
Y1315361D03*
X1069839Y1368999D03*
Y1371540D03*
X1076601Y1382574D03*
X1071332Y1379914D03*
X1076601Y1380066D03*
X1080555Y1380511D03*
X1073612Y1376389D03*
X1081005Y1425458D03*
X1071117Y1445005D03*
X1077031Y1451498D03*
X1070312Y1452028D03*
X1073307Y1451931D03*
X1070732Y1491204D03*
X1068232D03*
X1073232D03*
X1075732D03*
X1078232D03*
X1080732D03*
X1070732Y1501204D03*
Y1498704D03*
Y1496204D03*
Y1493704D03*
X1068232Y1501204D03*
Y1498704D03*
Y1496204D03*
Y1493704D03*
X1073232D03*
X1075732D03*
X1078232D03*
X1080732D03*
X1080232Y1501204D03*
X1075232D03*
X1072134Y1647920D03*
X1081011Y1685499D03*
X1078011D03*
X1081011Y1682499D03*
X1078011D03*
X1077172Y1676686D03*
X1077881Y1688252D03*
X1080933Y1688245D03*
X1078016Y1691207D03*
X1080966Y1691320D03*
X1087421Y149716D03*
X1086714Y353515D03*
X1090086Y370417D03*
X1090061Y428019D03*
X1087963Y440605D03*
Y446105D03*
X1084840Y438234D03*
Y443515D03*
X1087963Y462605D03*
Y457105D03*
X1087940Y452110D03*
X1084840Y460005D03*
X1085851Y465978D03*
X1087963Y468105D03*
X1095448Y479426D03*
X1084000Y477500D03*
X1090000D03*
X1087963Y484605D03*
Y494641D03*
Y489641D03*
X1083434Y481500D03*
X1085730Y509362D03*
X1091730D03*
X1095730D03*
X1082622Y520652D03*
X1082438Y524033D03*
X1085438D03*
X1085622Y520652D03*
X1083281Y651601D03*
X1091270Y668286D03*
X1086758Y767299D03*
Y771099D03*
X1090203Y1307861D03*
Y1310361D03*
Y1312861D03*
X1092703D03*
Y1310361D03*
Y1307861D03*
Y1300361D03*
Y1302861D03*
X1090203D03*
Y1300361D03*
X1095203Y1302861D03*
Y1300361D03*
X1092703Y1305361D03*
X1090203D03*
X1095203D03*
Y1307861D03*
Y1310361D03*
Y1312861D03*
X1090203Y1315361D03*
X1092703D03*
Y1317861D03*
X1090203D03*
X1095203D03*
Y1315361D03*
X1087059Y1372853D03*
X1089489D03*
X1091919D03*
X1092889Y1367278D03*
Y1370178D03*
X1084043Y1382111D03*
X1083293Y1379543D03*
X1094683Y1379188D03*
Y1376288D03*
X1091598Y1491204D03*
X1089098D03*
X1086598D03*
X1084098D03*
X1091598Y1501204D03*
Y1498704D03*
Y1496204D03*
Y1493704D03*
X1089098Y1501204D03*
Y1498704D03*
Y1496204D03*
Y1493704D03*
X1086598Y1501204D03*
Y1498704D03*
Y1496204D03*
Y1493704D03*
X1084098D03*
Y1498704D03*
Y1501204D03*
Y1496204D03*
X1089934Y1550784D03*
X1092934D03*
X1097000Y1629500D03*
X1096500Y1639000D03*
X1096768Y1635080D03*
X1090958Y1646528D03*
Y1649928D03*
X1084629Y1673002D03*
X1087141Y1688914D03*
X1092980Y1699179D03*
X1089030Y1717841D03*
Y1722841D03*
X1099500Y318000D03*
X1111001Y361272D03*
X1107300Y456944D03*
X1111076Y464388D03*
X1108076Y646774D03*
X1104443Y646983D03*
X1100316Y766870D03*
X1109503Y1302861D03*
X1107003D03*
Y1300361D03*
X1109503Y1305361D03*
X1107003D03*
Y1307861D03*
Y1310361D03*
Y1312861D03*
X1109503Y1307861D03*
Y1310361D03*
Y1312861D03*
Y1300361D03*
Y1315361D03*
Y1317861D03*
X1107003D03*
Y1315361D03*
X1102439Y1368999D03*
Y1371540D03*
X1098949Y1373158D03*
X1109201Y1382574D03*
X1103932Y1379914D03*
X1109201Y1380066D03*
X1106212Y1376389D03*
X1098949Y1378958D03*
X1096849Y1377558D03*
X1098949Y1376058D03*
X1096749Y1374558D03*
X1099098Y1501204D03*
X1102248Y1496186D03*
X1106700Y1526591D03*
X1112529Y1547661D03*
X1111701Y1558640D03*
X1107181Y1615917D03*
X1109811D03*
X1098549Y1625749D03*
X1100961Y1622543D03*
X1109000Y1671107D03*
X1105148Y1696029D03*
X1099108Y1691229D03*
X1100998Y1715841D03*
Y1725991D03*
X1119676Y54132D03*
X1124834Y56805D03*
X1124270Y404640D03*
X1121628Y401915D03*
X1121077Y511498D03*
X1125077D03*
X1126387Y615658D03*
X1118435Y625307D03*
X1114467Y640802D03*
X1120321Y635832D03*
X1116540Y651070D03*
X1112190Y651962D03*
X1116459Y767299D03*
Y771099D03*
X1112003Y1302861D03*
Y1300361D03*
Y1305361D03*
X1122803Y1307861D03*
X1125303D03*
Y1310361D03*
Y1312861D03*
X1122803D03*
Y1310361D03*
X1112003Y1312861D03*
Y1310361D03*
Y1307861D03*
X1125303Y1300361D03*
Y1302861D03*
X1122803D03*
Y1300361D03*
X1125303Y1305361D03*
X1122803D03*
X1125303Y1315361D03*
X1122803D03*
X1112003D03*
Y1317861D03*
X1125303D03*
X1122803D03*
X1124519Y1372853D03*
X1119659D03*
X1122089D03*
X1125469Y1367108D03*
Y1370008D03*
X1116643Y1382111D03*
X1113155Y1380511D03*
X1115893Y1379543D03*
X1124375Y1423488D03*
X1124415Y1426168D03*
Y1428668D03*
Y1431168D03*
Y1433668D03*
X1115098Y1468871D03*
Y1472271D03*
X1124875Y1490042D03*
X1125498Y1487292D03*
X1116917Y1506823D03*
X1119912Y1506936D03*
X1116917Y1509898D03*
X1119912Y1509891D03*
Y1515644D03*
X1116917D03*
X1119912Y1512644D03*
X1116917D03*
X1114617Y1526318D03*
X1113887Y1543447D03*
X1119459Y1556343D03*
X1118133Y1587998D03*
Y1591398D03*
X1115027Y1598788D03*
X1117247Y1604554D03*
X1113847D03*
X1124532Y1634915D03*
X1114286Y1630507D03*
X1117136Y1630441D03*
X1113490Y1651862D03*
X1112500Y1671107D03*
X1125784Y1662705D03*
X1124394Y1658967D03*
X1120595D03*
X1126000Y1672419D03*
X1122610Y1677976D03*
X1124091Y1683983D03*
X1114414Y1698859D03*
X1114394Y1695936D03*
X1119361Y1713734D03*
X1113948Y1711244D03*
X1126902Y60805D03*
X1142144Y63186D03*
X1132340Y468202D03*
Y471702D03*
X1141267Y500296D03*
X1134567Y513870D03*
X1139360Y516031D03*
X1129387Y615658D03*
X1138387D03*
X1132855Y609373D03*
X1135387Y615658D03*
X1130017Y766870D03*
X1127803Y1302861D03*
Y1300361D03*
Y1305361D03*
Y1307861D03*
Y1310361D03*
Y1312861D03*
X1139703Y1302861D03*
Y1300361D03*
Y1305361D03*
Y1307861D03*
Y1310361D03*
Y1312861D03*
X1127803Y1317861D03*
Y1315361D03*
X1139703Y1317861D03*
Y1315361D03*
X1135139Y1368999D03*
Y1371540D03*
X1131549Y1373158D03*
X1136632Y1379914D03*
X1138912Y1376389D03*
X1127283Y1379188D03*
X1129449Y1377558D03*
X1127283Y1376288D03*
X1129349Y1374558D03*
X1131549Y1378958D03*
Y1376058D03*
X1129965Y1403877D03*
X1127465D03*
X1129965Y1401377D03*
X1127465D03*
X1132465Y1403877D03*
Y1401377D03*
X1129925Y1398737D03*
X1127425D03*
X1134925D03*
X1132425D03*
X1137425D03*
X1137465Y1401377D03*
X1134965D03*
Y1403877D03*
X1137465D03*
X1137275Y1424138D03*
X1134775D03*
X1132275D03*
X1126875Y1423488D03*
X1129775Y1424138D03*
X1140175Y1423488D03*
X1140215Y1428668D03*
Y1426168D03*
X1134815Y1433668D03*
X1137315D03*
X1140215D03*
Y1431168D03*
X1132315Y1433668D03*
X1137315Y1426818D03*
X1134815D03*
X1137345Y1431058D03*
X1134845D03*
X1132315Y1426818D03*
X1132345Y1431058D03*
X1126915Y1428668D03*
Y1426168D03*
X1129815Y1433668D03*
X1126915D03*
Y1431168D03*
X1129815Y1426818D03*
X1129845Y1431058D03*
X1131478Y1485427D03*
X1134183Y1483926D03*
X1126951Y1484646D03*
X1140960Y1489434D03*
Y1491934D03*
X1141045Y1534952D03*
Y1537452D03*
Y1544952D03*
Y1542452D03*
Y1539952D03*
X1135033Y1556112D03*
X1142639Y1562789D03*
X1133765Y1568952D03*
X1140655Y1569256D03*
X1137755Y1569543D03*
X1138480Y1576364D03*
X1140422Y1595455D03*
X1139037Y1611383D03*
X1131824Y1600593D03*
Y1603993D03*
X1140325Y1598697D03*
X1139037Y1614153D03*
X1139142Y1618859D03*
X1139188Y1621603D03*
X1132981Y1634531D03*
X1141084Y1646672D03*
Y1643272D03*
X1137542Y1647925D03*
X1134207Y1669230D03*
X1129184Y1662705D03*
X1132406Y1658967D03*
X1136575Y1676239D03*
X1141356Y1676542D03*
X1133206Y1675383D03*
X1132176Y1690038D03*
X1142643Y74738D03*
X1151679Y72258D03*
X1150118Y207344D03*
X1155268D03*
Y212344D03*
X1150118D03*
X1155890Y478812D03*
X1150577Y478840D03*
X1144663Y492319D03*
Y500319D03*
X1151036Y501627D03*
X1143060Y516476D03*
X1154145Y583339D03*
Y586339D03*
X1146160Y767299D03*
Y771099D03*
X1155282Y766806D03*
X1142203Y1300361D03*
Y1302861D03*
X1144703D03*
Y1300361D03*
X1142203Y1305361D03*
X1144703D03*
X1155503Y1312861D03*
Y1310361D03*
Y1307861D03*
X1142203D03*
Y1310361D03*
Y1312861D03*
X1144703D03*
Y1310361D03*
Y1307861D03*
X1155503Y1302861D03*
Y1300361D03*
Y1305361D03*
Y1315361D03*
X1142203D03*
X1144703D03*
X1142203Y1317861D03*
X1144703D03*
X1155503D03*
X1152359Y1372853D03*
X1154789D03*
X1141901Y1382574D03*
Y1380066D03*
X1149343Y1382111D03*
X1145855Y1380511D03*
X1148593Y1379543D03*
X1142675Y1423488D03*
X1145715Y1423555D03*
X1145755Y1426235D03*
Y1428735D03*
Y1431235D03*
Y1433735D03*
X1142715Y1426168D03*
Y1428668D03*
Y1431168D03*
Y1433668D03*
X1150718Y1462792D03*
X1153724Y1462695D03*
X1154824Y1471134D03*
X1145960Y1491934D03*
X1148460D03*
X1150960D03*
X1153460D03*
X1155960D03*
X1145960Y1489434D03*
X1148460D03*
X1150960D03*
X1153460D03*
X1155960D03*
X1143460D03*
Y1491934D03*
X1153545Y1534952D03*
X1151045D03*
X1148545D03*
X1146045D03*
X1143545D03*
X1153545Y1537452D03*
X1151045D03*
X1148545D03*
X1146045D03*
X1143545D03*
X1151045Y1544952D03*
X1148545D03*
X1146045D03*
X1143545D03*
X1153545D03*
X1143545Y1542452D03*
X1146045D03*
X1148545D03*
X1151045D03*
X1153545D03*
Y1539952D03*
X1151045D03*
X1148545D03*
X1146045D03*
X1143545D03*
X1155253Y1559176D03*
X1147814Y1562823D03*
X1154336Y1555979D03*
X1149467Y1568988D03*
X1142917Y1583314D03*
Y1586714D03*
X1155180Y1655534D03*
X1146501Y1655608D03*
Y1652208D03*
X1158343Y1658514D03*
X1152198Y1669629D03*
X1151985Y1666685D03*
X1151707Y1663655D03*
X1152114Y1672517D03*
X1154500Y1677000D03*
X1142033Y1682412D03*
X1152211Y1682373D03*
X1162086Y76509D03*
X1162144Y487630D03*
X1158764Y489516D03*
X1162067Y570050D03*
X1166131Y580602D03*
X1157038Y583298D03*
Y586298D03*
X1166026Y669006D03*
X1159718Y766870D03*
X1158003Y1307861D03*
Y1310361D03*
Y1312861D03*
Y1300361D03*
Y1302861D03*
Y1305361D03*
X1160503Y1302861D03*
Y1300361D03*
Y1305361D03*
Y1307861D03*
Y1310361D03*
Y1312861D03*
X1158003Y1315361D03*
Y1317861D03*
X1160503D03*
Y1315361D03*
X1168039Y1368999D03*
Y1371540D03*
X1157219Y1372853D03*
X1158059Y1367018D03*
Y1369918D03*
X1164249Y1373158D03*
X1169532Y1379914D03*
X1164249Y1376058D03*
X1159983Y1376288D03*
X1162049Y1374558D03*
X1164249Y1378958D03*
X1159983Y1379188D03*
X1162149Y1377558D03*
X1160163Y1445627D03*
X1163422Y1445000D03*
X1166350Y1454234D03*
X1160750Y1463250D03*
X1164300Y1463300D03*
X1159283Y1471132D03*
X1158460Y1491934D03*
Y1489434D03*
X1169061Y1543800D03*
X1170061Y1551040D03*
X1163485Y1546195D03*
X1161492Y1551175D03*
X1164528Y1565578D03*
X1170404Y1556331D03*
Y1559731D03*
X1166873Y1561431D03*
X1157255Y1556000D03*
X1170539Y1595621D03*
X1168023Y1586251D03*
X1170539Y1588751D03*
X1168023D03*
X1170539Y1586251D03*
Y1583751D03*
Y1600621D03*
Y1598121D03*
X1170339Y1603121D03*
X1165806Y1658934D03*
X1159688Y1665427D03*
X1169098Y1666278D03*
X1159703Y1673000D03*
X1159500Y1679000D03*
Y1682500D03*
X1184194Y57015D03*
Y61515D03*
X1185913Y93634D03*
X1174031Y403519D03*
X1181000Y402500D03*
X1175181Y447841D03*
Y442341D03*
X1185952Y444202D03*
Y436202D03*
X1178340Y447734D03*
Y442234D03*
X1176000Y436500D03*
X1180000Y436000D03*
X1175181Y458841D03*
Y464341D03*
Y453341D03*
X1185952Y452202D03*
X1178340Y458734D03*
X1178254Y453142D03*
X1178340Y461615D03*
X1175181Y469841D03*
X1186040Y481691D03*
X1178340Y467165D03*
X1175181Y481691D03*
X1182950Y577030D03*
X1178000Y572602D03*
X1182594Y587759D03*
X1178000Y592673D03*
X1183811Y640682D03*
X1182256Y632368D03*
X1182713Y733815D03*
X1175860Y767299D03*
Y771099D03*
X1184960Y766870D03*
X1172603Y1302861D03*
Y1300361D03*
Y1305361D03*
Y1307861D03*
Y1310361D03*
Y1312861D03*
X1175103Y1300361D03*
Y1302861D03*
X1177603D03*
Y1300361D03*
X1175103Y1305361D03*
X1177603D03*
X1175103Y1307861D03*
Y1310361D03*
Y1312861D03*
X1177603D03*
Y1310361D03*
Y1307861D03*
X1175103Y1315361D03*
X1177603D03*
X1172603Y1317861D03*
Y1315361D03*
X1175103Y1317861D03*
X1177603D03*
X1185259Y1372853D03*
X1174801Y1382574D03*
Y1380066D03*
X1182243Y1382111D03*
X1178755Y1380511D03*
X1181493Y1379543D03*
X1171812Y1376389D03*
X1184900Y1428500D03*
X1183000Y1422900D03*
X1184175Y1435600D03*
X1176500Y1457071D03*
X1180200Y1457100D03*
X1178039Y1595621D03*
X1175539D03*
X1173039D03*
X1180923Y1588751D03*
Y1586251D03*
X1173039Y1588751D03*
X1175539D03*
X1178039D03*
Y1586251D03*
X1175539D03*
X1173039D03*
X1178039Y1583751D03*
X1175539D03*
X1173039D03*
X1178039Y1600621D03*
X1175539D03*
X1173039D03*
X1178039Y1598121D03*
X1175539D03*
X1173039D03*
X1175339Y1603121D03*
X1172839D03*
X1177839D03*
X1184362Y1670254D03*
X1181385Y1670312D03*
X1175726Y1686726D03*
X1195488Y93550D03*
X1190587Y99694D03*
X1199756Y128748D03*
X1189727Y164987D03*
Y160987D03*
X1200037Y177187D03*
X1200012Y181187D03*
X1186821Y185430D03*
Y181930D03*
X1195767Y460202D03*
Y470392D03*
Y465272D03*
X1193040Y481691D03*
X1191087Y573809D03*
X1199370Y578154D03*
X1195236Y581407D03*
X1188267Y571807D03*
X1199392Y590500D03*
X1195336Y586606D03*
X1200923Y601734D03*
Y606134D03*
X1199539Y638492D03*
X1197039D03*
X1194539D03*
X1192039D03*
X1195108Y668148D03*
X1198456Y668138D03*
X1190903Y1307861D03*
Y1310361D03*
Y1312861D03*
X1188403D03*
Y1310361D03*
Y1307861D03*
Y1302861D03*
Y1300361D03*
Y1305361D03*
X1190903Y1300361D03*
Y1302861D03*
X1193403D03*
Y1300361D03*
X1190903Y1305361D03*
X1193403D03*
Y1307861D03*
Y1310361D03*
Y1312861D03*
X1190903Y1315361D03*
X1188403D03*
Y1317861D03*
X1190903D03*
X1193403D03*
Y1315361D03*
X1200839Y1368999D03*
Y1371540D03*
X1190119Y1372853D03*
X1191049Y1367188D03*
Y1370088D03*
X1187689Y1372853D03*
X1197149Y1373158D03*
X1192883Y1379188D03*
X1195049Y1377558D03*
X1197149Y1378958D03*
X1192883Y1376288D03*
X1194949Y1374558D03*
X1197149Y1376058D03*
X1194296Y1396500D03*
X1194000Y1401000D03*
Y1414500D03*
X1203242Y1417440D03*
X1194366Y1405500D03*
X1193929Y1410000D03*
X1202548Y1407453D03*
X1202857Y1412454D03*
X1191000Y1425900D03*
X1198800Y1421500D03*
X1202411Y1427410D03*
X1194000Y1424000D03*
X1203117Y1422452D03*
X1202475Y1432468D03*
X1188000Y1419800D03*
X1194000Y1437500D03*
X1203040D03*
X1194000Y1442500D03*
Y1447500D03*
X1188960Y1609135D03*
X1186455Y1608390D03*
Y1602590D03*
Y1605490D03*
X1190174Y1615418D03*
X1190616Y1670641D03*
X1190314Y1661630D03*
X1199299Y1675517D03*
X1197746Y1680914D03*
X1199272Y1683025D03*
X1189263Y1682551D03*
X1190830Y1675710D03*
X1197612Y1703334D03*
X1192612D03*
X1199612Y1691366D03*
X1189462Y1700334D03*
X1194478Y1699936D03*
X1189407Y1717518D03*
X1205929Y86872D03*
X1206580Y94846D03*
X1208431Y133866D03*
Y128748D03*
X1214094Y258633D03*
Y269008D03*
Y282948D03*
Y287948D03*
X1205625Y313758D03*
X1210698Y313671D03*
X1207447Y341381D03*
X1202508Y341424D03*
X1212700Y475712D03*
X1206590Y481403D03*
X1203269Y481237D03*
X1212051Y559827D03*
X1208733Y585986D03*
X1205900Y582443D03*
X1206191Y588400D03*
X1205679Y594148D03*
X1209796Y668115D03*
X1204334Y668138D03*
X1205630Y766600D03*
X1207903Y1300361D03*
Y1302861D03*
X1210403D03*
Y1300361D03*
X1207903Y1305361D03*
X1210403D03*
X1207903Y1307861D03*
Y1310361D03*
Y1312861D03*
X1210403D03*
Y1310361D03*
Y1307861D03*
X1205403Y1302861D03*
Y1300361D03*
Y1305361D03*
Y1307861D03*
Y1310361D03*
Y1312861D03*
X1207903Y1315361D03*
X1210403D03*
X1205403Y1317861D03*
Y1315361D03*
X1207903Y1317861D03*
X1210403D03*
X1202332Y1379914D03*
X1207601Y1380066D03*
X1215043Y1382111D03*
X1211555Y1380511D03*
X1214293Y1379543D03*
X1207601Y1382574D03*
X1204612Y1376389D03*
X1211000Y1392125D03*
X1211075Y1395200D03*
X1210100Y1436500D03*
X1213000Y1435000D03*
X1210400Y1440000D03*
X1214900Y1439800D03*
X1202697Y1673059D03*
X1205604Y1685400D03*
Y1682200D03*
Y1679000D03*
Y1675800D03*
X1212954Y1703343D03*
X1214954Y1691375D03*
X1204804Y1700343D03*
X1207954Y1703343D03*
X1207770Y1706861D03*
Y1720861D03*
X1205638Y1732766D03*
X1227803Y94210D03*
X1221411Y134230D03*
X1221512Y128239D03*
X1220931Y131307D03*
X1222094Y258633D03*
X1230094D03*
Y269008D03*
X1222094D03*
X1230094Y287948D03*
Y282948D03*
X1222094D03*
Y297066D03*
Y292066D03*
Y314216D03*
Y305216D03*
X1226094Y314216D03*
X1218430Y421012D03*
X1219325Y438151D03*
X1216300Y475682D03*
X1228372Y688501D03*
X1221203Y1312861D03*
Y1310361D03*
Y1307861D03*
X1223703D03*
Y1310361D03*
Y1312861D03*
Y1300361D03*
Y1302861D03*
Y1305361D03*
X1221203Y1302861D03*
Y1300361D03*
Y1305361D03*
Y1315361D03*
X1223703D03*
Y1317861D03*
X1221203D03*
X1222919Y1372853D03*
X1220489D03*
X1223889Y1367188D03*
Y1370088D03*
X1218059Y1372853D03*
X1229949Y1373158D03*
X1228800Y1391300D03*
X1225683Y1379188D03*
X1227849Y1377558D03*
X1225683Y1376288D03*
X1227749Y1374558D03*
X1229949Y1378958D03*
Y1376058D03*
X1227000Y1401300D03*
X1219650Y1392050D03*
X1219500Y1398900D03*
X1224200Y1393500D03*
X1227000Y1404500D03*
X1219500Y1436000D03*
X1221837Y1438800D03*
X1229661Y1442000D03*
X1226200Y1444300D03*
X1222700Y1446300D03*
X1220200Y1449100D03*
X1219738Y1713861D03*
Y1708861D03*
X1216738Y1717011D03*
X1219738Y1722861D03*
Y1727861D03*
X1216738Y1731011D03*
X1238769Y75320D03*
X1233668Y132739D03*
Y128239D03*
X1247834Y159844D03*
X1238094Y258633D03*
X1246094Y269008D03*
X1238094D03*
X1234000Y385500D03*
X1233468Y419742D03*
X1242429Y431255D03*
Y427255D03*
Y435255D03*
X1236879Y449755D03*
X1242429Y439255D03*
X1232081Y460580D03*
X1242692Y483435D03*
X1236100Y773844D03*
X1233084Y772582D03*
X1235215Y777213D03*
X1231397Y769667D03*
X1243207Y779428D03*
X1241057Y782278D03*
X1244986Y787578D03*
X1244127Y784598D03*
X1238257Y779728D03*
X1243294Y1269197D03*
Y1266697D03*
Y1261697D03*
Y1264197D03*
X1243308Y1271754D03*
X1238830Y1322853D03*
Y1325394D03*
X1240323Y1333768D03*
X1245592Y1333920D03*
Y1336428D03*
X1242603Y1330243D03*
X1239800Y1389500D03*
X1235400Y1391200D03*
X1238500Y1400900D03*
X1234900Y1404400D03*
X1233700Y1395600D03*
X1238200Y1395500D03*
X1244300Y1403500D03*
X1235679Y1418908D03*
X1239242Y1418462D03*
X1238731Y1422362D03*
X1239550Y1437050D03*
X1249152Y72895D03*
X1253152Y84895D03*
X1255661Y90470D03*
X1253152Y95525D03*
X1259472Y92864D03*
X1252693Y124739D03*
X1249431Y137739D03*
X1249065Y241594D03*
Y236594D03*
Y251594D03*
Y246594D03*
X1246094Y258633D03*
X1254094D03*
X1262094Y269008D03*
X1254094D03*
X1262094Y282948D03*
X1254094D03*
X1262094Y287948D03*
X1250285Y303307D03*
X1259659Y389456D03*
X1260107Y399125D03*
X1260227Y415128D03*
X1256137Y459182D03*
Y453872D03*
X1245752Y470733D03*
X1250975Y474945D03*
X1248130Y783354D03*
X1251177Y784488D03*
X1254981Y787578D03*
X1256447Y798828D03*
X1259297Y798784D03*
X1251177Y794878D03*
X1257527Y808938D03*
X1260427Y809008D03*
X1259194Y1251697D03*
Y1246697D03*
Y1254197D03*
Y1249197D03*
X1248294Y1259197D03*
Y1256697D03*
X1245794Y1259197D03*
X1259194Y1269215D03*
Y1261715D03*
Y1264215D03*
Y1266715D03*
X1245894Y1269215D03*
X1248394D03*
X1245894Y1261715D03*
Y1264215D03*
Y1266715D03*
X1248394D03*
Y1264215D03*
Y1261715D03*
X1259194Y1256697D03*
Y1259197D03*
X1248308Y1271754D03*
X1245808D03*
X1259108D03*
X1256050Y1326707D03*
X1258480D03*
X1253034Y1335965D03*
X1249546Y1334365D03*
X1252284Y1333397D03*
X1249600Y1403425D03*
X1257594Y1417000D03*
X1253100Y1413500D03*
X1256224Y1430075D03*
X1256600Y1434500D03*
X1275981Y85114D03*
X1263472Y92864D03*
X1269146Y121022D03*
X1263146D03*
X1267037Y180565D03*
Y175030D03*
X1268941Y206017D03*
X1269360Y219632D03*
X1261969Y219505D03*
X1262094Y258633D03*
X1270094D03*
Y269008D03*
Y282948D03*
Y292066D03*
X1268174Y395125D03*
X1275585Y393597D03*
X1269840Y411128D03*
X1270483Y433148D03*
Y435648D03*
X1265227Y454372D03*
X1262457Y798814D03*
X1266677Y802988D03*
X1266568Y809078D03*
X1275177Y808963D03*
X1263647Y809118D03*
X1271177Y808963D03*
X1261694Y1251697D03*
X1264194D03*
Y1246697D03*
X1261694D03*
Y1254197D03*
X1264194D03*
X1261694Y1249197D03*
X1264194D03*
X1261694Y1269215D03*
Y1266715D03*
Y1264215D03*
Y1261715D03*
X1264194Y1269197D03*
Y1256697D03*
Y1259197D03*
Y1261697D03*
X1261694Y1256697D03*
Y1259197D03*
X1264194Y1264197D03*
Y1266697D03*
X1264108Y1271754D03*
X1261608D03*
X1271726Y1322825D03*
Y1325366D03*
X1260910Y1326707D03*
X1262050Y1320878D03*
Y1323778D03*
X1267940Y1327012D03*
X1265740Y1328412D03*
X1273219Y1333740D03*
X1275499Y1330215D03*
X1267940Y1332812D03*
Y1329912D03*
X1265840Y1331412D03*
X1263674Y1330142D03*
Y1333042D03*
X1271042Y1418748D03*
X1266996Y1423617D03*
X1262310Y1428303D03*
X1275195Y1552250D03*
X1275170Y1579519D03*
X1269310Y1583170D03*
X1287486Y134165D03*
X1278050Y152912D03*
X1278137Y166051D03*
X1278211Y161030D03*
Y156030D03*
X1278137Y180565D03*
Y176051D03*
Y171551D03*
Y184987D03*
X1279447Y213292D03*
X1286094Y258633D03*
X1278094D03*
Y269008D03*
X1286094D03*
X1278094Y282948D03*
X1286094D03*
X1278094Y287948D03*
X1286094Y292066D03*
X1290127Y401125D03*
Y410635D03*
X1289352Y418550D03*
Y421950D03*
X1281190Y1254112D03*
X1276190D03*
X1278690D03*
X1281190Y1249112D03*
Y1251612D03*
X1276190D03*
X1278690D03*
X1276190Y1249112D03*
X1278690D03*
X1281190Y1246612D03*
X1276190D03*
X1278690D03*
X1276190Y1269112D03*
Y1266612D03*
X1281190Y1259112D03*
Y1256612D03*
X1276190D03*
Y1259112D03*
Y1261612D03*
Y1264112D03*
X1278690Y1256612D03*
Y1259112D03*
X1278790Y1269130D03*
X1281290D03*
X1278790Y1261630D03*
Y1264130D03*
Y1266630D03*
X1281290D03*
Y1264130D03*
Y1261630D03*
X1281204Y1271669D03*
X1278704D03*
X1276204D03*
X1288946Y1326679D03*
X1278488Y1333892D03*
X1285930Y1335937D03*
X1282442Y1334337D03*
X1285180Y1333369D03*
X1278488Y1336400D03*
X1287600Y1423100D03*
Y1427600D03*
X1276500Y1432000D03*
X1279525D03*
X1287700Y1431700D03*
X1287961Y1542469D03*
X1287372Y1552845D03*
X1287647Y1545220D03*
Y1549120D03*
X1277017Y1544953D03*
Y1547453D03*
Y1549953D03*
X1281470Y1552845D03*
X1281347Y1549120D03*
Y1545220D03*
X1284497Y1549120D03*
Y1545220D03*
X1284510Y1554436D03*
X1277702D03*
X1289919Y1582295D03*
Y1574795D03*
Y1579795D03*
Y1577295D03*
X1287419Y1582295D03*
Y1579795D03*
X1284919D03*
Y1582295D03*
X1282419D03*
Y1579795D03*
X1299196Y76209D03*
X1305685Y74748D03*
X1296200Y66911D03*
X1305091Y123680D03*
Y127830D03*
Y131750D03*
X1301582Y166051D03*
X1301743Y162055D03*
X1301582Y171551D03*
Y184051D03*
X1302094Y258633D03*
X1294094D03*
Y269008D03*
X1302094D03*
X1294094Y287948D03*
Y282948D03*
X1302094D03*
Y292066D03*
X1302069Y303184D03*
X1299026Y389355D03*
X1302226D03*
X1295519Y389561D03*
X1304347Y523237D03*
X1302160Y524916D03*
X1304566Y525743D03*
X1301642Y537299D03*
X1293581Y542716D03*
X1294938Y561331D03*
X1300400Y599413D03*
X1297400D03*
X1298000Y657500D03*
X1303250Y655149D03*
X1295000Y655200D03*
X1292297Y657206D03*
X1302500Y664500D03*
X1305100Y662100D03*
X1301900Y660699D03*
X1294590Y1254112D03*
X1297090D03*
X1292090D03*
Y1249112D03*
X1294590D03*
X1297090D03*
X1292090Y1251612D03*
X1294590D03*
X1297090D03*
X1292090Y1246612D03*
X1297090D03*
X1294590D03*
X1292090Y1269130D03*
X1294590D03*
X1292090Y1261630D03*
Y1264130D03*
Y1266630D03*
X1294590D03*
Y1264130D03*
Y1261630D03*
X1297090Y1269112D03*
Y1256612D03*
Y1259112D03*
Y1261612D03*
X1294590Y1256612D03*
Y1259112D03*
X1297090Y1264112D03*
Y1266612D03*
X1292090Y1256612D03*
Y1259112D03*
X1297004Y1271669D03*
X1292004D03*
X1294504D03*
X1304630Y1322768D03*
Y1325309D03*
X1293806Y1326679D03*
X1291376D03*
X1294956Y1320934D03*
Y1323834D03*
X1300836Y1326984D03*
X1298636Y1328384D03*
X1296570Y1330114D03*
Y1333014D03*
X1298736Y1331384D03*
X1300836Y1329884D03*
Y1332784D03*
X1296000Y1427700D03*
X1301900D03*
X1295700Y1421800D03*
X1300800D03*
X1291700Y1431700D03*
X1302390Y1530430D03*
X1297490Y1526910D03*
X1297620Y1529534D03*
X1291897Y1545076D03*
X1290461Y1542469D03*
X1291897Y1547576D03*
X1302915Y1563596D03*
X1298466Y1556331D03*
Y1559731D03*
X1292419Y1582295D03*
Y1579795D03*
Y1574795D03*
Y1577295D03*
X1294919D03*
Y1574795D03*
X1294387Y1571682D03*
X1291887D03*
X1301789Y1574795D03*
X1304289D03*
X1301789Y1577295D03*
X1304289D03*
Y1579795D03*
X1301789D03*
X1304289Y1582295D03*
X1301789D03*
X1299289Y1574795D03*
Y1582295D03*
Y1579795D03*
Y1577295D03*
X1295877Y1581199D03*
X1298382Y1584844D03*
X1295877Y1584099D03*
X1293459Y1584844D03*
X1320020Y66979D03*
X1308110Y66911D03*
X1307857Y103353D03*
X1313951Y104739D03*
X1311045D03*
X1313011Y135820D03*
Y139845D03*
X1306300Y203917D03*
X1318094Y258633D03*
X1310094D03*
Y269008D03*
X1318094D03*
X1310094Y287948D03*
Y282948D03*
X1318094D03*
X1305426Y389355D03*
X1308926Y524111D03*
X1306815Y522726D03*
X1307117Y525897D03*
X1309870Y552788D03*
X1309776Y559831D03*
X1317266Y597213D03*
X1310544Y613100D03*
X1313544Y610100D03*
X1310544D03*
X1313544Y607100D03*
X1310544D03*
X1313544Y604100D03*
X1310544D03*
X1307544Y610100D03*
Y613100D03*
Y604100D03*
Y607100D03*
X1317266Y600213D03*
X1309166Y601713D03*
X1308776Y599181D03*
X1313544Y613100D03*
X1310544Y616100D03*
X1313544D03*
X1307544D03*
X1308800Y619200D03*
Y622200D03*
Y625200D03*
X1318300D03*
Y622200D03*
Y619200D03*
X1307700Y664600D03*
X1309600Y667700D03*
X1315657Y1199532D03*
Y1196132D03*
X1311715Y1221042D03*
X1318776Y1219566D03*
X1311594Y1251612D03*
X1309094D03*
X1311594Y1254112D03*
X1309094D03*
X1311594Y1246612D03*
X1309094D03*
X1311594Y1249112D03*
X1309094D03*
X1314094Y1246612D03*
Y1251612D03*
Y1249112D03*
Y1254112D03*
X1309090Y1269169D03*
Y1266669D03*
Y1261669D03*
Y1264169D03*
X1314194Y1269130D03*
Y1266630D03*
Y1264130D03*
Y1261630D03*
X1311694Y1269130D03*
Y1261630D03*
Y1264130D03*
Y1266630D03*
X1311594Y1259112D03*
Y1256612D03*
X1309094Y1259112D03*
Y1256612D03*
X1314094D03*
Y1259112D03*
X1309090Y1271669D03*
X1311590D03*
X1314090D03*
X1306123Y1333683D03*
X1311392Y1333835D03*
X1318834Y1335880D03*
X1315346Y1334280D03*
X1318084Y1333312D03*
X1311392Y1336343D03*
X1308403Y1330158D03*
X1308900Y1525510D03*
X1306789Y1574795D03*
Y1582295D03*
Y1579795D03*
Y1577295D03*
X1310914Y1577299D03*
X1331930Y66945D03*
X1327541Y105227D03*
X1337399Y98084D03*
X1333399D03*
X1334094Y258633D03*
X1326094D03*
Y269008D03*
X1334094D03*
Y287948D03*
X1326094Y282948D03*
X1334094D03*
X1326094Y292066D03*
X1328427Y349452D03*
X1329585Y561806D03*
X1325366Y597213D03*
Y600213D03*
X1321300Y619200D03*
Y622200D03*
Y625200D03*
X1326636Y656800D03*
X1322420Y656867D03*
X1332812Y856383D03*
X1325543Y871161D03*
X1329244D03*
X1334301Y867765D03*
X1328992Y1209788D03*
X1327029Y1206788D03*
X1331202Y1206478D03*
X1323169Y1208995D03*
X1333977Y1222158D03*
X1325137Y1210653D03*
X1324901Y1216419D03*
X1322141Y1217365D03*
X1327494Y1246612D03*
Y1251612D03*
Y1249112D03*
Y1254112D03*
X1324994Y1246612D03*
Y1251612D03*
Y1249112D03*
Y1254112D03*
X1329994Y1246612D03*
Y1251612D03*
Y1249112D03*
Y1254112D03*
X1324994Y1269130D03*
Y1261630D03*
Y1264130D03*
Y1266630D03*
X1327494Y1269130D03*
Y1266630D03*
Y1264130D03*
Y1261630D03*
Y1259112D03*
Y1256612D03*
X1324994Y1259112D03*
Y1256612D03*
X1329994Y1259112D03*
Y1256612D03*
Y1266612D03*
Y1264112D03*
Y1261612D03*
Y1269112D03*
X1327490Y1271669D03*
X1324990D03*
X1329990D03*
X1326710Y1326622D03*
X1324280D03*
X1321850D03*
X1327876Y1320934D03*
Y1323834D03*
X1333740Y1326927D03*
X1331540Y1328327D03*
X1333740Y1329827D03*
Y1332727D03*
X1331640Y1331327D03*
X1329474Y1330057D03*
Y1332957D03*
X1322539Y1411278D03*
X1322499Y1413788D03*
X1325499D03*
X1325539Y1411278D03*
Y1416446D03*
X1322539D03*
X1328539Y1411278D03*
X1328499Y1413788D03*
X1328539Y1416446D03*
X1331509Y1416486D03*
X1334509D03*
X1331509Y1408818D03*
X1334509Y1411318D03*
X1334469Y1413828D03*
X1334509Y1408818D03*
X1331469Y1413828D03*
X1331509Y1411318D03*
X1325579Y1418976D03*
X1322579D03*
X1325609Y1421496D03*
X1322609D03*
X1328579Y1418976D03*
X1328609Y1421496D03*
X1331579Y1421536D03*
X1331549Y1419016D03*
X1334579Y1421536D03*
X1334549Y1419016D03*
X1343840Y66911D03*
X1341399Y98084D03*
X1348199D03*
X1342094Y258633D03*
Y269008D03*
X1350094D03*
Y287948D03*
X1342094Y282948D03*
X1350094D03*
X1342094Y292066D03*
X1340257Y677765D03*
Y675111D03*
X1336812Y856383D03*
X1341301Y867765D03*
X1337801D03*
X1341301Y871265D03*
X1344801D03*
X1348301D03*
X1340948Y1177681D03*
X1342507Y1187848D03*
X1340948Y1181681D03*
X1349012Y1204971D03*
X1342036Y1206429D03*
Y1203029D03*
X1346063Y1217729D03*
Y1214329D03*
X1341590Y1254169D03*
Y1251669D03*
Y1249169D03*
Y1246669D03*
X1344090Y1254169D03*
Y1251669D03*
Y1249169D03*
Y1246669D03*
X1346590Y1254169D03*
Y1249169D03*
Y1251669D03*
Y1246669D03*
X1341690Y1269269D03*
Y1264269D03*
Y1266769D03*
Y1261769D03*
X1341590Y1256669D03*
Y1259169D03*
X1344190Y1269187D03*
X1346690D03*
X1344190Y1261687D03*
Y1264187D03*
Y1266687D03*
X1346690D03*
Y1264187D03*
Y1261687D03*
X1344090Y1256669D03*
Y1259169D03*
X1346590D03*
Y1256669D03*
X1341690Y1271769D03*
X1346690D03*
X1344190D03*
X1337430Y1322968D03*
Y1325509D03*
X1338923Y1333883D03*
X1344192Y1334035D03*
X1348146Y1334480D03*
X1344192Y1336543D03*
X1341203Y1330358D03*
X1340556Y1383674D03*
Y1386674D03*
X1337556D03*
Y1383674D03*
X1346556Y1386674D03*
Y1383674D03*
X1343556Y1386674D03*
Y1383674D03*
X1349556D03*
Y1386674D03*
X1337555Y1389658D03*
X1343712Y1389804D03*
X1348712D03*
X1346212D03*
X1341212D03*
X1348823Y1409626D03*
X1348853Y1413866D03*
X1346323Y1409626D03*
X1346353Y1413866D03*
X1343823Y1409626D03*
X1343853Y1413866D03*
X1346509Y1416486D03*
X1349509D03*
X1343509D03*
X1341323Y1409626D03*
X1341353Y1413866D03*
X1337509Y1416486D03*
Y1411318D03*
X1337469Y1413828D03*
X1337509Y1408818D03*
X1340509Y1416486D03*
X1349579Y1421536D03*
X1349549Y1419016D03*
X1346579Y1421536D03*
X1346549Y1419016D03*
X1343549D03*
X1343579Y1421536D03*
X1337579D03*
X1337549Y1419016D03*
X1340579Y1421536D03*
X1340549Y1419016D03*
X1355750Y66886D03*
X1360109Y98050D03*
X1352199D03*
X1364369Y120380D03*
X1358094Y258633D03*
X1350094D03*
X1358094Y269008D03*
X1366094D03*
Y287948D03*
X1358094Y282948D03*
X1366094D03*
X1358094Y292066D03*
X1363857Y626579D03*
X1361427D03*
X1354397Y623374D03*
Y626274D03*
X1356597Y624874D03*
X1358663Y623144D03*
X1356497Y621874D03*
X1354397Y620474D03*
X1358663Y620244D03*
X1360964Y629514D03*
Y632414D03*
X1358461Y684151D03*
Y686651D03*
X1360961Y684073D03*
Y686573D03*
X1363461D03*
Y684073D03*
X1363435Y681573D03*
X1358435D03*
X1360935D03*
X1358461Y694151D03*
X1363461D03*
X1360961D03*
X1358461Y689151D03*
Y691651D03*
X1363461Y696651D03*
X1360961D03*
X1363461Y699151D03*
X1360961Y691573D03*
X1363461D03*
X1360961Y689073D03*
X1363461D03*
X1362523Y1015473D03*
Y1022559D03*
Y1019016D03*
X1355222Y1200561D03*
X1361285Y1206718D03*
X1355641Y1210674D03*
X1362810Y1211071D03*
X1357490Y1254169D03*
Y1249169D03*
Y1251669D03*
Y1246669D03*
X1359990Y1254169D03*
X1362490D03*
X1359990Y1249169D03*
X1362490D03*
X1359990Y1251669D03*
X1362490D03*
Y1246669D03*
X1359990D03*
Y1269187D03*
Y1266687D03*
Y1264187D03*
Y1261687D03*
X1357490Y1269187D03*
Y1261687D03*
Y1264187D03*
Y1266687D03*
Y1256669D03*
Y1259169D03*
X1362490Y1269269D03*
Y1261769D03*
Y1266769D03*
Y1264269D03*
Y1256669D03*
Y1259169D03*
X1359990Y1256669D03*
Y1259169D03*
X1357490Y1271769D03*
X1362490D03*
X1359990D03*
X1359510Y1326822D03*
X1360724Y1321184D03*
Y1324084D03*
X1357080Y1326822D03*
X1354650D03*
X1364340Y1328527D03*
X1351634Y1336080D03*
X1350884Y1333512D03*
X1364440Y1337527D03*
Y1331527D03*
Y1334527D03*
X1362274Y1330257D03*
Y1333157D03*
Y1336057D03*
X1352226Y1386804D03*
Y1383804D03*
X1352225Y1389788D03*
X1358509Y1416486D03*
Y1413818D03*
Y1411318D03*
Y1408818D03*
X1352509Y1416486D03*
Y1411318D03*
Y1413818D03*
Y1408818D03*
X1355509Y1416486D03*
Y1411318D03*
Y1413818D03*
Y1408818D03*
X1352579Y1421536D03*
X1352549Y1419016D03*
X1355549D03*
X1367950Y66886D03*
X1377682Y87587D03*
X1368109Y98000D03*
X1366094Y258633D03*
X1373862Y485552D03*
Y511052D03*
X1381457Y511050D03*
X1376757Y619497D03*
X1369303Y617321D03*
X1372791Y618921D03*
X1370053Y619889D03*
X1376745Y616858D03*
X1379734Y623043D03*
X1366287Y626579D03*
X1376761Y686573D03*
Y684073D03*
X1374261D03*
Y686573D03*
X1374245Y681573D03*
X1376745D03*
X1376761Y694151D03*
X1374261D03*
X1376761Y696651D03*
X1374261D03*
X1376761Y699151D03*
X1374261D03*
X1376761Y701651D03*
X1374261D03*
X1376761Y691573D03*
Y689073D03*
X1374261Y691573D03*
Y689073D03*
X1376761Y706651D03*
Y704151D03*
X1374261Y706651D03*
Y704151D03*
X1377483Y1015473D03*
X1370003D03*
X1377483Y1022559D03*
Y1019016D03*
X1370003Y1022559D03*
Y1019016D03*
X1370685Y1223032D03*
Y1226432D03*
X1374476Y1266143D03*
X1376976D03*
X1379476D03*
X1374476Y1268643D03*
X1376976D03*
X1379476D03*
X1374476Y1273643D03*
Y1271143D03*
X1374576Y1283743D03*
Y1281243D03*
X1374476Y1276143D03*
Y1278643D03*
X1376976Y1273643D03*
Y1271143D03*
X1379476Y1273643D03*
Y1271143D03*
X1377076Y1281161D03*
Y1283661D03*
X1379576D03*
Y1281161D03*
X1376976Y1276143D03*
Y1278643D03*
X1379476D03*
Y1276143D03*
X1379576Y1288661D03*
X1377076Y1286161D03*
X1379576D03*
X1377076Y1288661D03*
X1379576Y1291243D03*
X1377076D03*
X1374576Y1288743D03*
Y1286243D03*
Y1291243D03*
X1370012Y1342299D03*
X1371505Y1353214D03*
X1376774Y1353366D03*
X1370012Y1344840D03*
X1376774Y1355874D03*
X1373785Y1349689D03*
X1382045Y1700038D03*
X1379804Y1733118D03*
X1383715Y236594D03*
Y241594D03*
X1381457Y485550D03*
X1382014Y619518D03*
X1383507Y627892D03*
Y630433D03*
X1387097Y656274D03*
X1389297Y657774D03*
X1391363Y656044D03*
X1387097Y653374D03*
X1389197Y654774D03*
X1391363Y653144D03*
X1394127Y659479D03*
X1387097Y659174D03*
X1393664Y662384D03*
Y665284D03*
X1393343Y716971D03*
X1390807Y717053D03*
X1390817Y714471D03*
X1393317D03*
X1393343Y719471D03*
X1390807Y719553D03*
X1393367Y727023D03*
Y729523D03*
X1393343Y724471D03*
Y721971D03*
X1390807Y722053D03*
Y724553D03*
X1390853Y727053D03*
X1391460Y1009764D03*
Y1006024D03*
Y1013504D03*
Y1020985D03*
Y1024725D03*
Y1028465D03*
Y1017244D03*
X1390376Y1268643D03*
X1392876D03*
Y1283661D03*
Y1281161D03*
X1390376D03*
Y1283661D03*
Y1273643D03*
Y1271143D03*
Y1276143D03*
Y1278643D03*
X1392876Y1273643D03*
Y1271143D03*
Y1276143D03*
Y1278643D03*
Y1288661D03*
Y1286161D03*
X1390376Y1288661D03*
Y1286161D03*
Y1291243D03*
X1392876D03*
X1393306Y1340515D03*
Y1343415D03*
X1384216Y1355411D03*
X1380728Y1353811D03*
X1383466Y1352843D03*
X1392092Y1346153D03*
X1389662D03*
X1387232D03*
X1385068Y1664907D03*
X1390738Y1664938D03*
X1392068Y1676875D03*
X1381918D03*
X1391750Y1697747D03*
X1382045Y1704038D03*
X1390045Y1712038D03*
X1390179Y1733118D03*
X1404917Y116911D03*
X1395302Y251136D03*
Y256136D03*
X1411000Y460362D03*
X1406500Y458362D03*
X1400500Y458377D03*
X1409445Y652266D03*
X1402003Y650221D03*
X1405491Y651821D03*
X1402753Y652789D03*
X1409445Y649758D03*
X1398987Y659479D03*
X1396557D03*
X1409143Y716971D03*
X1395843D03*
X1406643D03*
X1409127Y714471D03*
X1395817D03*
X1406627D03*
X1409143Y719471D03*
X1395843D03*
X1406643D03*
X1395867Y732023D03*
Y727023D03*
Y729523D03*
X1406667Y727023D03*
X1409167Y732023D03*
Y729523D03*
X1406667Y732023D03*
Y729523D03*
X1409167Y727023D03*
X1409143Y724471D03*
Y721971D03*
X1395843Y724471D03*
Y721971D03*
X1406643Y724471D03*
Y721971D03*
X1409167Y739523D03*
Y734523D03*
Y737023D03*
X1406667Y734523D03*
Y737023D03*
Y739523D03*
X1401015Y1014744D03*
X1399953Y1005799D03*
X1403693D03*
X1407433D03*
X1401015Y1023012D03*
Y1018878D03*
X1407433Y1032430D03*
X1403693D03*
X1395060Y1032205D03*
X1399953Y1032430D03*
X1395376Y1268643D03*
Y1273643D03*
Y1271143D03*
Y1281243D03*
Y1283743D03*
Y1276143D03*
Y1278643D03*
Y1288743D03*
Y1286243D03*
Y1291243D03*
X1399122Y1352258D03*
X1394856Y1352488D03*
X1399122Y1346458D03*
Y1349358D03*
X1396922Y1347858D03*
X1394856Y1349588D03*
X1397022Y1350858D03*
X1405811Y1430021D03*
X1409532Y1552845D03*
X1409409Y1549120D03*
Y1545220D03*
X1403257Y1552250D03*
X1405079Y1549953D03*
Y1544953D03*
Y1547453D03*
X1405764Y1554436D03*
X1403232Y1579519D03*
X1397030Y1594060D03*
X1409286Y1605796D03*
X1406666Y1616332D03*
X1400029Y1615796D03*
X1406447Y1619572D03*
X1396783Y1617170D03*
X1408023Y1638705D03*
X1398058Y1628651D03*
X1408208D03*
X1406814Y1652439D03*
X1399599Y1657583D03*
X1398883Y1680341D03*
X1410750Y244583D03*
X1417000Y460362D03*
X1419335Y533958D03*
X1414714Y653008D03*
X1412434Y655943D03*
X1416207Y663333D03*
Y660792D03*
X1421797Y687354D03*
X1423963Y685724D03*
X1419697Y685954D03*
X1421897Y690354D03*
X1423963Y688624D03*
X1419697Y688854D03*
Y691754D03*
X1423417Y747051D03*
X1423407Y757133D03*
Y749633D03*
Y752133D03*
Y754633D03*
X1416301Y970340D03*
Y977840D03*
Y985340D03*
X1414576Y989765D03*
X1414501Y993765D03*
Y997765D03*
X1410858Y1014744D03*
X1418653Y1005799D03*
X1414913D03*
X1411173D03*
X1414501Y1001765D03*
X1419716Y1014744D03*
X1422394Y1005799D03*
X1410858Y1023012D03*
X1419716D03*
X1410858Y1018878D03*
X1419716D03*
X1422394Y1032430D03*
X1419026Y1038765D03*
Y1042765D03*
X1414913Y1032430D03*
X1418653D03*
X1411173D03*
X1417301Y1051540D03*
X1418982Y1175144D03*
X1414165Y1289564D03*
X1414172Y1286188D03*
X1415434Y1552845D03*
X1415709Y1545220D03*
Y1549120D03*
X1418523Y1542469D03*
X1419959Y1545076D03*
Y1547576D03*
X1416023Y1542469D03*
X1412559Y1549120D03*
Y1545220D03*
X1412572Y1554436D03*
X1417981Y1568680D03*
X1423531Y1574795D03*
Y1582295D03*
Y1579795D03*
Y1577295D03*
X1424621Y1571911D03*
Y1569411D03*
X1416862Y1582871D03*
X1419811Y1599084D03*
X1416709Y1592819D03*
X1413836Y1586944D03*
X1412467Y1602234D03*
X1419914Y1602777D03*
X1418000Y1607500D03*
X1422154Y1626270D03*
X1423722Y1616780D03*
X1419622Y1616000D03*
X1422266Y1628947D03*
X1411113Y1637767D03*
X1421890Y1635500D03*
X1418755Y1654999D03*
X1410315Y1646967D03*
X1424315D03*
X1434262Y52892D03*
X1438262D03*
X1431262Y61392D03*
X1439049Y107443D03*
X1429169Y107313D03*
X1431300Y538800D03*
X1435400Y536200D03*
X1431400Y533400D03*
X1435400Y530800D03*
X1434603Y682801D03*
X1438091Y684401D03*
X1435353Y685369D03*
X1431617Y692359D03*
X1429187D03*
X1426757D03*
X1426264Y694954D03*
Y697854D03*
X1439227Y747051D03*
X1425917D03*
X1428417D03*
X1428407Y762133D03*
Y759633D03*
X1425907D03*
X1439257Y762133D03*
Y759633D03*
X1425943Y757051D03*
X1428443D03*
X1425943Y749551D03*
Y752051D03*
Y754551D03*
X1428443D03*
Y752051D03*
Y749551D03*
X1439243Y757051D03*
Y749551D03*
Y752051D03*
Y754551D03*
X1439257Y764633D03*
Y769633D03*
Y767133D03*
X1429952Y1014744D03*
X1433614Y1005799D03*
X1426134D03*
X1429874D03*
X1429952Y1023012D03*
Y1018878D03*
X1426134Y1032430D03*
X1433614D03*
X1429874D03*
X1435160Y1516590D03*
Y1513190D03*
Y1534990D03*
Y1538390D03*
X1434235Y1550240D03*
X1433235Y1543800D03*
X1430735D03*
X1431735Y1550240D03*
X1434578Y1556331D03*
Y1559731D03*
X1430213Y1553652D03*
X1427713D03*
X1426031Y1582295D03*
X1431031Y1574795D03*
Y1577295D03*
X1426031Y1579795D03*
Y1577295D03*
Y1574795D03*
X1428531D03*
Y1577295D03*
Y1579795D03*
Y1582295D03*
X1430431Y1570595D03*
X1427931D03*
X1437901Y1579795D03*
Y1577295D03*
Y1574795D03*
Y1582295D03*
X1435401D03*
Y1579795D03*
Y1577295D03*
Y1574795D03*
X1431989Y1581199D03*
X1434494Y1584844D03*
X1431989Y1584099D03*
X1429571Y1584844D03*
X1430244Y1609966D03*
X1438565Y1612583D03*
X1434316Y1616909D03*
X1430238Y1617137D03*
X1437594Y1616845D03*
X1426899Y1616990D03*
X1429072Y1643655D03*
X1433911Y1649037D03*
X1433618Y1659331D03*
X1433157Y1651977D03*
X1436311Y1665948D03*
X1438078Y1669992D03*
X1439316Y1675080D03*
X1435904Y1694335D03*
X1443049Y107443D03*
X1448549Y114643D03*
X1446040Y120218D03*
X1452040Y113018D03*
X1440871Y152166D03*
X1454769Y163842D03*
X1444769D03*
Y174217D03*
X1453974Y174414D03*
X1449769Y174217D03*
X1439769D03*
Y182217D03*
X1449769D03*
X1456500Y457000D03*
X1441053Y560535D03*
X1441898Y576755D03*
X1452708Y610954D03*
Y607954D03*
X1449708Y610954D03*
X1446708D03*
Y607954D03*
X1449708D03*
X1440708Y610954D03*
X1443708D03*
X1440708Y607954D03*
X1443708D03*
X1452708Y613954D03*
X1446708Y616954D03*
Y619954D03*
X1440708D03*
Y616954D03*
X1443708D03*
Y619954D03*
X1449708Y613954D03*
X1446708D03*
X1440708D03*
X1443708D03*
X1446708Y622954D03*
X1440708D03*
X1443708D03*
X1452938Y617364D03*
X1450438D03*
X1452898Y621844D03*
X1450398D03*
X1448996Y645270D03*
Y647770D03*
X1451496Y645270D03*
X1453996D03*
Y647770D03*
X1451496D03*
X1449046Y650370D03*
X1454046D03*
X1451546D03*
X1446426D03*
X1443926D03*
X1443876Y645270D03*
Y647770D03*
X1446376Y645270D03*
Y647770D03*
X1447314Y684998D03*
X1442091Y684846D03*
X1442045Y682338D03*
X1448807Y695913D03*
Y693372D03*
X1445034Y688523D03*
X1452615Y705531D03*
X1441727Y747051D03*
X1444257Y757133D03*
Y759633D03*
Y762133D03*
X1441757Y759633D03*
Y762133D03*
X1441743Y757051D03*
Y754551D03*
Y752051D03*
Y749551D03*
X1444257Y772133D03*
Y764633D03*
Y769633D03*
Y767133D03*
X1441757Y772133D03*
Y764633D03*
Y769633D03*
Y767133D03*
X1442107Y1013504D03*
Y1009764D03*
Y1006024D03*
Y1020985D03*
Y1024725D03*
Y1028465D03*
Y1017244D03*
Y1032205D03*
X1451498Y1485895D03*
X1448098D03*
X1444798Y1495595D03*
X1441398D03*
X1439850Y1541470D03*
X1440401Y1574795D03*
Y1582295D03*
Y1579795D03*
Y1577295D03*
X1442901Y1582295D03*
Y1579795D03*
Y1577295D03*
Y1574795D03*
X1447026Y1577299D03*
X1448061Y1593055D03*
X1451000Y1601000D03*
X1446000Y1600500D03*
X1450500Y1614500D03*
Y1624000D03*
X1445500Y1614500D03*
X1441000D03*
X1440027Y1667945D03*
X1455579Y1665701D03*
X1453553Y1686892D03*
X1445079Y1686678D03*
X1449070Y1686722D03*
X1448000Y1676000D03*
X1464830Y59054D03*
X1466681Y78590D03*
X1454549Y107443D03*
X1455667Y125733D03*
X1463017Y139518D03*
X1456226Y152166D03*
X1462682Y450372D03*
X1456982Y437362D03*
X1466609Y458608D03*
X1465395Y487582D03*
X1465832Y530656D03*
X1463647Y544977D03*
X1464257Y560977D03*
Y557498D03*
X1462497Y555021D03*
X1464257Y568977D03*
Y572977D03*
Y580977D03*
Y576977D03*
X1467708Y610954D03*
Y607954D03*
X1464708Y610954D03*
Y607954D03*
X1458708Y610954D03*
X1455708D03*
X1461708D03*
Y607954D03*
X1455708D03*
X1458708D03*
X1467708Y616954D03*
Y619954D03*
Y613954D03*
X1461708Y616954D03*
Y619954D03*
X1464708Y616954D03*
Y619954D03*
Y613954D03*
X1458708D03*
X1455708D03*
X1461708D03*
X1467708Y622954D03*
X1461708D03*
X1464708D03*
X1455438Y617364D03*
X1457938D03*
X1455398Y621844D03*
X1457898D03*
X1456496Y645270D03*
X1459396D03*
X1456496Y647770D03*
X1459396D03*
X1456546Y650370D03*
X1459446D03*
X1467521Y702378D03*
X1454715Y700931D03*
X1468271Y704946D03*
X1462045Y711826D03*
X1464475D03*
X1459615D03*
X1456881Y708201D03*
Y705301D03*
X1454715Y706931D03*
Y703931D03*
X1454815Y709931D03*
X1458777Y714194D03*
Y717094D03*
X1456335Y771710D03*
Y766628D03*
X1458861Y776628D03*
X1461361D03*
X1458861Y769128D03*
Y771628D03*
Y774128D03*
X1461361D03*
Y771628D03*
Y769128D03*
X1461335Y766628D03*
X1458835D03*
X1456335Y776710D03*
Y774210D03*
Y769210D03*
X1461371Y791696D03*
Y789196D03*
X1458871Y779196D03*
X1461371D03*
X1458871Y784196D03*
Y781696D03*
Y786696D03*
X1461371Y784196D03*
Y786696D03*
Y781696D03*
X1456371Y779210D03*
Y781710D03*
Y784210D03*
X1456945Y1015473D03*
X1464526D03*
X1456945Y1019016D03*
Y1022559D03*
X1464526Y1019016D03*
Y1022559D03*
X1464898Y1505295D03*
X1461498D03*
X1468198Y1495595D03*
X1468102Y1670817D03*
X1458795Y1687083D03*
X1457940Y1675710D03*
X1463038Y1687060D03*
X1466111Y1685098D03*
X1472129Y56083D03*
X1483820Y132405D03*
X1471395Y487582D03*
X1473947Y492169D03*
X1472647Y539478D03*
X1475257Y530656D03*
X1473444Y555208D03*
X1473408Y547948D03*
X1478147Y547728D03*
X1478257Y543977D03*
X1481257Y544977D03*
X1482044Y542517D03*
X1472257Y551241D03*
X1472757Y561264D03*
X1473362Y558380D03*
X1472257Y564977D03*
X1481898Y585476D03*
X1484347Y580388D03*
X1478258Y588108D03*
Y584142D03*
X1474963Y701915D03*
X1480232Y704575D03*
X1475009Y704488D03*
X1481725Y715490D03*
X1471009Y703978D03*
X1481725Y712949D03*
X1477952Y708100D03*
X1477171Y774196D03*
Y771696D03*
Y769196D03*
Y776696D03*
X1474661Y776628D03*
Y774128D03*
Y771628D03*
Y769128D03*
X1472161Y776628D03*
Y769128D03*
Y771628D03*
Y774128D03*
X1472145Y766628D03*
X1474645D03*
X1477145D03*
X1477171Y791696D03*
X1474671D03*
X1472171D03*
X1477171Y786696D03*
X1474671D03*
X1477171Y781696D03*
X1474671D03*
X1472171Y789196D03*
Y779196D03*
Y784196D03*
Y786696D03*
Y781696D03*
X1477171Y789196D03*
X1474671D03*
X1477171Y779196D03*
X1474671D03*
X1477171Y784196D03*
X1474671D03*
X1481177Y803488D03*
X1469950Y813232D03*
X1473728Y813552D03*
X1480677Y813488D03*
X1484177Y812988D03*
X1474177Y816872D03*
X1471526Y1015473D03*
Y1019016D03*
Y1022559D03*
X1478298Y1485895D03*
X1474898D03*
X1471598Y1495595D03*
X1482798Y1685982D03*
X1469588Y1673342D03*
X1486000Y1686000D03*
X1470500Y1685500D03*
X1494891Y121171D03*
X1488647Y134562D03*
X1497386Y464980D03*
X1495682Y473302D03*
X1484395Y487582D03*
X1492514Y539657D03*
X1484416Y541658D03*
X1488510Y542816D03*
X1490602Y544755D03*
X1497310Y543960D03*
X1494967Y541898D03*
X1487660Y585748D03*
X1491677Y583588D03*
X1490677Y580688D03*
X1492789Y576602D03*
X1495236Y612838D03*
X1495486Y599938D03*
X1497986Y602438D03*
Y599938D03*
X1495236Y605338D03*
X1495486Y602438D03*
X1495236Y607838D03*
Y610338D03*
X1492636Y605258D03*
Y607758D03*
Y610258D03*
Y612758D03*
X1497986Y612838D03*
Y605338D03*
Y607838D03*
Y610338D03*
X1495486Y615988D03*
Y618488D03*
X1497986Y615988D03*
Y618488D03*
X1492886Y618408D03*
Y615908D03*
X1497587Y711636D03*
X1495157D03*
X1492727D03*
X1489963Y705301D03*
X1487797Y706931D03*
X1487897Y709931D03*
X1489963Y708201D03*
X1485697Y708431D03*
Y705531D03*
Y711331D03*
X1492264Y714544D03*
Y717444D03*
X1491943Y776628D03*
X1494443D03*
X1491943Y769128D03*
Y771628D03*
Y774128D03*
X1494443D03*
Y771628D03*
Y769128D03*
X1494417Y766628D03*
X1491917D03*
X1489417Y776710D03*
Y774210D03*
Y769210D03*
Y771710D03*
Y766628D03*
X1494487Y779210D03*
Y784210D03*
Y786710D03*
Y781710D03*
X1491987Y779210D03*
Y784210D03*
Y786710D03*
Y781710D03*
X1489487Y779210D03*
Y784210D03*
Y786710D03*
Y781710D03*
X1500500Y809063D03*
X1496532Y803513D03*
X1485177Y803488D03*
X1489177Y812988D03*
X1487923Y816770D03*
X1490973Y825557D03*
X1498177Y829359D03*
X1495670Y826073D03*
X1486761Y826279D03*
X1493260Y1167390D03*
X1496960D03*
X1491698Y1505295D03*
X1488298D03*
X1498398Y1495595D03*
X1494998D03*
X1488875Y1677385D03*
X1503785Y464815D03*
X1505974Y470636D03*
X1511917Y483878D03*
X1499752Y488424D03*
X1502085Y545432D03*
X1507109Y550059D03*
X1507644Y554372D03*
X1507468Y564357D03*
X1506337Y561677D03*
X1502757Y570977D03*
X1508281Y559390D03*
X1509757Y575477D03*
X1501821Y577664D03*
X1502986Y602438D03*
Y599938D03*
X1500486Y602438D03*
Y599938D03*
X1502486Y605338D03*
Y607838D03*
Y610338D03*
Y612838D03*
X1500486Y615988D03*
Y618488D03*
X1502986Y615988D03*
Y618488D03*
X1500603Y702378D03*
X1508045Y701915D03*
X1513314Y704575D03*
X1508045Y704423D03*
X1504091Y703978D03*
X1501353Y704946D03*
X1511034Y708100D03*
X1510287Y771710D03*
Y769210D03*
Y774210D03*
Y776710D03*
X1507743Y776628D03*
Y774128D03*
Y771628D03*
Y769128D03*
X1505243Y776628D03*
Y769128D03*
Y771628D03*
Y774128D03*
X1505227Y766628D03*
X1507727D03*
X1510227D03*
X1507787Y786710D03*
Y781710D03*
X1505287Y779210D03*
Y784210D03*
Y786710D03*
Y781710D03*
X1510287Y779210D03*
Y784210D03*
Y786710D03*
Y781710D03*
X1507787Y779210D03*
Y784210D03*
X1508177Y803488D03*
X1501500Y799948D03*
X1510261Y814611D03*
X1500422Y814180D03*
X1512523Y809679D03*
X1502177Y817013D03*
X1512539Y812920D03*
X1505016Y817107D03*
X1501636Y828796D03*
X1499469Y860322D03*
Y863322D03*
X1504362Y1167390D03*
X1508063D03*
X1505098Y1485895D03*
X1501698D03*
X1515854Y119810D03*
X1517708Y216505D03*
X1527392Y238017D03*
X1519120Y479215D03*
X1515936Y484412D03*
X1516757Y537477D03*
X1516257Y547977D03*
X1516336Y551977D03*
X1519457Y556338D03*
X1519317Y561977D03*
X1527853Y560264D03*
X1524777Y605488D03*
Y607988D03*
X1527277Y605488D03*
Y607988D03*
X1524777Y610588D03*
X1527277D03*
X1524777Y613088D03*
X1527277D03*
X1524777Y615618D03*
X1527277D03*
X1524777Y618118D03*
X1527277D03*
X1514807Y715490D03*
Y712949D03*
X1525527Y711636D03*
X1527957D03*
X1522763Y708201D03*
Y705301D03*
X1518497Y705531D03*
X1520597Y706931D03*
X1518497Y708431D03*
X1520697Y709931D03*
X1518497Y711331D03*
X1525064Y714544D03*
Y717444D03*
X1522217Y771710D03*
X1527217Y766628D03*
X1522217Y769210D03*
X1524717Y766628D03*
X1522217D03*
Y774210D03*
Y776710D03*
X1524743Y776628D03*
X1527243D03*
X1524743Y769128D03*
Y771628D03*
Y774128D03*
X1527243D03*
Y771628D03*
Y769128D03*
X1527217Y779210D03*
Y784210D03*
Y786710D03*
Y781710D03*
X1524717Y779210D03*
X1522217D03*
X1524717Y784210D03*
Y786710D03*
X1522217Y784210D03*
Y786710D03*
X1524717Y781710D03*
X1522217D03*
X1517431Y811466D03*
X1521003Y1169488D03*
X1521217Y1190088D03*
X1524425Y1185241D03*
X1528498Y1485895D03*
X1518498Y1505295D03*
X1525198Y1495595D03*
X1515098Y1505295D03*
X1521798Y1495595D03*
X1538342Y28406D03*
X1540342Y48720D03*
X1537450Y226293D03*
X1533160Y231250D03*
X1536538Y296819D03*
X1536422Y292816D03*
X1536542Y308819D03*
X1534584Y467067D03*
X1539693Y543613D03*
X1532824Y555981D03*
X1539693Y558943D03*
X1532730Y562949D03*
X1534565Y564945D03*
X1533403Y702378D03*
X1540845Y701915D03*
Y704423D03*
X1536891Y703978D03*
X1534153Y704946D03*
X1543834Y708100D03*
X1530387Y711636D03*
X1538027Y766628D03*
X1540527D03*
X1540543Y776628D03*
Y774128D03*
Y771628D03*
Y769128D03*
X1538043Y776628D03*
Y769128D03*
Y771628D03*
Y774128D03*
X1538027Y784710D03*
Y779210D03*
X1540527D03*
X1538027Y781710D03*
X1540527D03*
X1539972Y807319D03*
X1529306Y1177468D03*
X1540801Y1178265D03*
X1537301D03*
X1539301Y1175765D03*
X1532896Y1234836D03*
X1542747Y1253602D03*
X1538587Y1245065D03*
X1543772Y1241016D03*
X1543519Y1248205D03*
X1536916Y1240844D03*
X1531898Y1485895D03*
X1541898D03*
X1543582Y1524562D03*
X1541191Y1544953D03*
Y1547453D03*
Y1549953D03*
X1539369Y1552250D03*
X1541876Y1554436D03*
X1539344Y1579519D03*
X1552674Y26477D03*
X1556379Y19541D03*
X1549274Y26477D03*
X1554360Y207251D03*
X1556960Y287478D03*
X1551900Y287288D03*
X1544489Y288816D03*
X1546789Y287116D03*
X1548772Y291916D03*
X1553154Y479063D03*
X1558198Y486791D03*
X1551779Y530698D03*
X1546149Y541169D03*
X1545987Y562012D03*
X1553657Y678965D03*
X1553827Y687991D03*
X1556027Y680391D03*
X1555893Y686261D03*
Y683361D03*
X1553657Y681965D03*
X1553727Y684991D03*
X1558657Y689696D03*
X1558194Y695501D03*
Y692501D03*
X1546114Y704575D03*
X1547607Y715490D03*
Y712949D03*
X1556708Y747282D03*
X1556688Y744688D03*
X1556708Y749782D03*
Y754782D03*
Y752282D03*
Y757282D03*
Y762282D03*
Y759782D03*
Y764782D03*
Y769782D03*
Y767282D03*
X1556121Y798542D03*
X1551124Y801289D03*
X1551961Y807269D03*
X1556361D03*
X1547561D03*
X1551113Y1238088D03*
X1548360Y1234750D03*
X1550517Y1232905D03*
X1545627Y1254068D03*
X1545480Y1245090D03*
X1544911Y1260654D03*
X1543980Y1258312D03*
X1554692Y1269688D03*
X1557559Y1269095D03*
X1557510Y1280291D03*
X1554377Y1278763D03*
X1560454Y1279004D03*
X1553226Y1288814D03*
X1553548Y1284991D03*
X1556515Y1292232D03*
X1555222Y1302757D03*
X1547195Y1478165D03*
X1547216Y1480812D03*
X1545298Y1485895D03*
X1545473Y1522117D03*
X1547548Y1520070D03*
X1552668Y1513682D03*
Y1517082D03*
Y1530482D03*
Y1527082D03*
X1551821Y1549120D03*
Y1545220D03*
X1551546Y1552845D03*
X1556071Y1547576D03*
X1554635Y1542469D03*
X1552135D03*
X1556071Y1545076D03*
X1545644Y1552845D03*
X1545521Y1549120D03*
Y1545220D03*
X1548671Y1549120D03*
Y1545220D03*
X1548684Y1554436D03*
X1554093Y1582295D03*
Y1574795D03*
Y1579795D03*
Y1577295D03*
X1551593Y1582295D03*
Y1579795D03*
X1556593Y1582295D03*
Y1579795D03*
Y1574795D03*
Y1577295D03*
X1549093Y1579795D03*
Y1582295D03*
X1546593D03*
Y1579795D03*
X1558560Y1571682D03*
X1556060D03*
X1557633Y1584844D03*
X1566847Y26477D03*
X1559779Y19541D03*
X1570552D03*
X1563447Y26477D03*
X1572502Y254250D03*
X1572549Y257491D03*
X1566442Y294816D03*
X1564506Y310334D03*
Y313734D03*
X1571516Y319099D03*
X1568070Y497847D03*
X1573070D03*
X1570570D03*
X1570068Y534095D03*
X1573326Y543351D03*
X1573487Y546996D03*
X1572436Y578933D03*
X1568446Y582733D03*
X1572436Y582433D03*
X1564946Y582733D03*
X1561246Y580393D03*
X1572436Y574022D03*
X1568936Y585933D03*
Y589433D03*
X1565436Y585933D03*
Y589433D03*
X1562016Y584283D03*
Y587783D03*
X1572436Y589433D03*
Y585933D03*
X1566533Y680438D03*
X1570021Y682038D03*
X1567283Y683006D03*
X1563517Y689696D03*
X1561087D03*
X1572514Y747188D03*
X1561714D03*
X1559214D03*
X1561688Y744688D03*
X1559188D03*
X1572498D03*
X1572588Y757282D03*
Y759782D03*
X1561708Y757282D03*
X1559208D03*
X1561708Y759782D03*
X1559208D03*
X1561708Y762282D03*
X1559208D03*
X1572514Y752188D03*
Y749688D03*
Y754688D03*
X1561714Y749688D03*
Y752188D03*
X1559214D03*
Y749688D03*
X1561714Y754688D03*
X1559214D03*
X1561708Y769782D03*
X1559208D03*
X1561708Y767282D03*
X1559208D03*
X1561708Y764782D03*
X1559208D03*
X1570583Y800104D03*
X1572668Y806778D03*
X1567737Y1271411D03*
X1561927Y1269901D03*
X1559181Y1287165D03*
X1568100Y1290418D03*
X1567000Y1293446D03*
X1562820Y1309360D03*
X1568456Y1311533D03*
X1572416Y1303160D03*
X1564268Y1338440D03*
X1562937Y1341609D03*
X1572331Y1348205D03*
X1566901Y1347726D03*
X1564758Y1367834D03*
X1572906Y1366759D03*
X1563967Y1363205D03*
X1572860Y1495595D03*
X1569460D03*
X1563222Y1516590D03*
Y1513190D03*
Y1534990D03*
Y1538390D03*
X1567089Y1563596D03*
X1562640Y1556331D03*
Y1559731D03*
X1559093Y1577295D03*
Y1574795D03*
X1565963D03*
X1568463D03*
X1565963Y1577295D03*
X1568463D03*
Y1579795D03*
X1565963D03*
X1568463Y1582295D03*
X1565963D03*
X1570963Y1574795D03*
Y1582295D03*
Y1579795D03*
Y1577295D03*
X1563463Y1574795D03*
Y1582295D03*
Y1579795D03*
Y1577295D03*
X1560051Y1581199D03*
X1574966Y1577038D03*
X1562556Y1584844D03*
X1560051Y1584099D03*
X1588125Y19541D03*
X1581020Y26477D03*
X1573952Y19541D03*
X1584725D03*
X1577620Y26477D03*
X1586291Y303596D03*
X1586621Y484304D03*
X1580519Y497650D03*
X1575570Y497847D03*
X1584397Y655622D03*
X1586497Y651222D03*
X1586597Y654222D03*
X1584397Y652722D03*
Y649822D03*
X1573975Y679975D03*
X1579244Y682635D03*
X1573975Y682483D03*
X1576964Y686160D03*
X1580737Y693550D03*
Y691009D03*
X1577588Y747282D03*
X1575014Y747188D03*
X1577498Y744688D03*
X1574998D03*
X1575088Y757282D03*
X1577588Y749782D03*
Y754782D03*
Y752282D03*
X1575014Y749688D03*
Y752188D03*
Y754688D03*
X1578690Y1283310D03*
X1585290Y1285098D03*
X1574168Y1283300D03*
X1577077Y1270937D03*
X1580577D03*
X1584068Y1271198D03*
X1580010Y1296100D03*
X1574560Y1296410D03*
X1580520Y1289900D03*
X1586167Y1295478D03*
X1575024Y1306373D03*
X1586557Y1304509D03*
X1578336Y1359253D03*
X1578411Y1348623D03*
X1578020Y1344773D03*
X1584156Y1381419D03*
X1586000Y1387641D03*
X1590723Y1381589D03*
X1579560Y1485895D03*
X1576160D03*
X1602299Y19541D03*
X1595194Y26477D03*
X1598899Y19541D03*
X1591794Y26477D03*
X1603970Y222956D03*
X1593303Y234250D03*
Y239250D03*
X1598303Y234250D03*
X1596462Y229790D03*
X1593658Y252010D03*
X1593303Y244250D03*
X1593349Y248160D03*
X1597481Y271991D03*
X1600918Y521688D03*
X1604890Y531226D03*
X1596299Y536344D03*
X1599303Y646669D03*
X1602791Y648269D03*
X1600053Y649237D03*
X1596287Y655927D03*
X1591427D03*
X1593857D03*
X1588663Y649592D03*
Y652492D03*
X1590964Y661741D03*
Y658741D03*
X1594844Y713419D03*
Y715919D03*
X1592344D03*
Y713419D03*
X1594818Y710919D03*
X1594844Y718419D03*
X1592344D03*
X1594844Y720919D03*
X1592344D03*
X1594688Y723512D03*
Y726012D03*
Y728512D03*
Y731012D03*
X1592188Y723512D03*
Y726012D03*
Y728512D03*
Y731012D03*
X1594688Y736012D03*
X1592188D03*
X1594688Y733512D03*
X1592188D03*
X1594900Y780112D03*
X1598467Y1267539D03*
X1588832Y1269083D03*
X1597177Y1282288D03*
X1594152Y1282578D03*
X1598883Y1270766D03*
X1590827Y1271378D03*
X1593397Y1271458D03*
X1596273Y1271472D03*
X1591005Y1288892D03*
X1596363Y1286296D03*
X1590921Y1309276D03*
X1599241Y1306622D03*
X1589845Y1305289D03*
X1599007Y1309762D03*
X1597621Y1365384D03*
X1595438Y1370603D03*
X1592788Y1388318D03*
X1597234Y1382689D03*
X1600531Y1404710D03*
X1597992Y1433183D03*
X1595716Y1431861D03*
X1602782Y1435920D03*
X1600442Y1434535D03*
X1602960Y1485895D03*
X1592960Y1505295D03*
X1599660Y1495595D03*
X1589560Y1505295D03*
X1596260Y1495595D03*
X1615020Y183050D03*
X1619909Y298742D03*
Y293742D03*
X1612144Y418552D03*
X1614701Y422587D03*
X1616464Y457509D03*
X1616250Y465042D03*
X1609166Y527300D03*
X1611775D03*
X1609166Y524700D03*
X1611775D03*
X1613169Y531819D03*
X1604991Y536344D03*
X1616084Y549105D03*
X1616198Y556364D03*
X1618859Y542820D03*
X1618356Y612137D03*
Y609137D03*
X1618434Y605753D03*
X1609044Y600986D03*
X1617397Y630822D03*
Y636622D03*
Y633722D03*
X1606745Y646206D03*
X1612014Y648866D03*
X1606745Y648714D03*
X1613507Y657240D03*
X1609734Y652391D03*
X1613507Y659781D03*
X1605644Y715919D03*
Y713419D03*
X1608144D03*
Y715919D03*
X1605628Y710919D03*
X1608128D03*
X1610628D03*
X1610718Y713513D03*
Y716013D03*
X1605644Y718419D03*
Y720919D03*
X1608144Y718419D03*
Y720919D03*
X1610718Y721013D03*
Y718513D03*
X1608118Y723512D03*
X1605618D03*
X1608118Y726012D03*
X1605618D03*
X1610618Y723512D03*
X1605618Y728512D03*
X1617200Y766870D03*
X1607267Y1271978D03*
X1604137Y1271358D03*
X1605801Y1286168D03*
X1608901Y1285887D03*
X1605360Y1294595D03*
X1608652Y1303338D03*
X1608341Y1313269D03*
X1608418Y1333589D03*
Y1331089D03*
X1614767Y1443512D03*
X1605648Y1437305D03*
X1606360Y1485895D03*
X1616360Y1505295D03*
X1622329Y28261D03*
X1631060Y26477D03*
X1627660D03*
X1623189Y48720D03*
X1631200Y164110D03*
X1631455Y167875D03*
X1627152Y168920D03*
X1629597Y227157D03*
X1627156Y238303D03*
X1627986Y282728D03*
X1627909Y286742D03*
Y298742D03*
Y294742D03*
Y290742D03*
X1619909Y303596D03*
X1627909Y302742D03*
X1621680Y366920D03*
X1625000Y383399D03*
X1631657Y392925D03*
X1632012Y603015D03*
X1621512D03*
X1625012D03*
X1628512D03*
X1632303Y627669D03*
X1633053Y630237D03*
X1626857Y636927D03*
X1629287D03*
X1624427D03*
X1621663Y630592D03*
X1619597Y635222D03*
X1621663Y633492D03*
X1619497Y632222D03*
X1623964Y642741D03*
Y639741D03*
X1627643Y694419D03*
Y696919D03*
Y699419D03*
X1625143D03*
Y696919D03*
Y694419D03*
X1627643Y701919D03*
X1625143D03*
X1627617Y691919D03*
X1625117D03*
Y709512D03*
Y704512D03*
Y707012D03*
Y712012D03*
X1627617Y709512D03*
Y704512D03*
Y707012D03*
Y712012D03*
X1628046Y763765D03*
X1626928Y1260917D03*
X1629428D03*
X1631928D03*
X1626333Y1311091D03*
Y1308091D03*
X1627174Y1420450D03*
X1625285Y1433384D03*
X1635281Y1422450D03*
X1627217Y1428366D03*
X1622697Y1440797D03*
X1625170Y1444016D03*
X1635227Y1436528D03*
X1633160Y1485895D03*
X1629760D03*
X1619760Y1505295D03*
X1626460Y1495595D03*
X1623060D03*
X1645233Y26477D03*
X1638165Y19541D03*
X1641833Y26477D03*
X1634765Y19541D03*
X1636047Y224597D03*
Y229912D03*
X1647310Y408922D03*
Y411422D03*
X1635697Y561253D03*
X1635944Y609510D03*
Y612510D03*
X1636022Y606126D03*
X1647158Y618971D03*
X1639745Y627206D03*
X1646507Y640781D03*
X1645014Y629866D03*
X1639745Y629714D03*
X1635791Y629269D03*
X1646507Y638240D03*
X1642734Y633391D03*
X1638443Y699419D03*
Y696919D03*
Y694419D03*
Y701919D03*
X1640943Y694419D03*
Y696919D03*
Y699419D03*
Y701919D03*
X1643517Y702013D03*
Y699513D03*
Y694513D03*
Y697013D03*
X1643427Y691919D03*
X1640927D03*
X1638427D03*
X1640877Y706972D03*
Y709472D03*
X1638377D03*
Y704472D03*
Y706972D03*
X1640877Y704472D03*
X1643377Y709510D03*
Y704510D03*
Y707010D03*
X1640877Y711972D03*
X1638377D03*
X1643377Y712010D03*
X1635088Y767205D03*
Y771005D03*
X1644188Y766870D03*
X1634428Y1260917D03*
X1645163Y1276184D03*
X1641677Y1341488D03*
Y1344488D03*
X1641087Y1396118D03*
X1641065Y1403393D03*
X1644001Y1408069D03*
X1646483Y1412741D03*
X1641065Y1406393D03*
X1635619Y1430536D03*
X1639834Y1434478D03*
X1636167Y1446746D03*
X1642400Y1439674D03*
X1645979Y1437950D03*
X1650400Y1437820D03*
X1641167Y1446746D03*
X1646560Y1505295D03*
X1643160D03*
X1646879Y1681738D03*
X1645029Y1715609D03*
Y1710609D03*
X1648029Y1708609D03*
Y1723759D03*
X1645029Y1725759D03*
Y1730759D03*
X1652338Y19541D03*
X1648938D03*
X1652525Y146762D03*
Y151762D03*
Y161762D03*
X1650023Y221842D03*
X1654419Y224597D03*
X1659419D03*
X1650023Y227157D03*
X1654419Y229912D03*
X1661928Y230172D03*
X1650020Y408952D03*
Y411452D03*
X1654110Y434177D03*
X1657545Y434506D03*
X1650035Y434750D03*
X1657194Y599956D03*
X1651194D03*
X1660194Y609450D03*
X1654194D03*
X1660194Y599956D03*
X1657194Y609450D03*
X1654194Y599956D03*
X1651194Y609450D03*
X1654147Y616523D03*
X1662377Y696300D03*
Y693300D03*
X1651072Y1314137D03*
X1660572Y1313837D03*
X1660635Y1329166D03*
X1651072Y1323137D03*
Y1320137D03*
Y1317137D03*
X1660572Y1322837D03*
Y1319837D03*
X1660635Y1326466D03*
X1660572Y1316837D03*
X1658015Y1328966D03*
X1658115Y1326466D03*
X1660635Y1331666D03*
Y1334166D03*
Y1339166D03*
Y1336666D03*
X1650177Y1341488D03*
X1658277Y1341888D03*
X1658015Y1336466D03*
Y1338966D03*
Y1331466D03*
Y1333966D03*
X1650177Y1344488D03*
X1658677D03*
X1653390Y1386316D03*
Y1388857D03*
X1649197Y1396743D03*
X1654883Y1397231D03*
X1660152Y1397383D03*
X1664106Y1397828D03*
X1660152Y1399891D03*
X1657163Y1393706D03*
X1661807Y1416948D03*
X1663777Y1421568D03*
X1662487Y1424178D03*
X1658089Y1437444D03*
X1649380Y1446713D03*
X1659960Y1485895D03*
X1656560D03*
X1653260Y1495595D03*
X1649860D03*
X1659975Y1592929D03*
X1656101Y1671720D03*
X1651101Y1671833D03*
X1653930Y1660640D03*
X1656180Y1659220D03*
X1656849Y1664949D03*
X1651698Y1665045D03*
X1661125Y1690751D03*
X1656101Y1701094D03*
X1656997Y1718759D03*
Y1733909D03*
X1675194Y26477D03*
X1671794D03*
X1673100Y121762D03*
Y136762D03*
Y131762D03*
X1673403Y199997D03*
X1664335Y210191D03*
X1663310Y215488D03*
X1664789Y767265D03*
Y771065D03*
X1673889Y766870D03*
X1674972Y1313837D03*
X1675134Y1329219D03*
X1675234Y1326519D03*
X1674972Y1316837D03*
X1672623Y1326476D03*
X1663437Y1326526D03*
X1674972Y1319837D03*
Y1322837D03*
X1677754Y1326519D03*
Y1329019D03*
X1663437Y1334726D03*
X1672623Y1334676D03*
X1663437Y1329726D03*
X1672623Y1332176D03*
X1663437Y1332226D03*
X1672623Y1329676D03*
X1675134Y1331719D03*
Y1334219D03*
Y1336719D03*
Y1339219D03*
X1677754Y1339019D03*
Y1336519D03*
Y1331519D03*
Y1334019D03*
X1675931Y1384335D03*
Y1387235D03*
X1667594Y1399428D03*
X1666844Y1396860D03*
X1675470Y1390170D03*
X1673040D03*
X1670610D03*
X1672501Y1416678D03*
X1675641Y1432891D03*
X1672401Y1423365D03*
X1664237Y1426278D03*
X1671079Y1435069D03*
X1663239Y1428592D03*
X1670147Y1444311D03*
X1673360Y1485895D03*
X1669960D03*
X1676685Y1537893D03*
X1671034Y1549734D03*
Y1552234D03*
X1668703Y1550898D03*
X1671034Y1546934D03*
X1668827Y1553551D03*
X1671034Y1557234D03*
Y1554734D03*
X1673706Y1560425D03*
X1671006Y1576744D03*
Y1574244D03*
Y1571744D03*
X1668826Y1575498D03*
Y1572998D03*
X1676176Y1580650D03*
X1674923Y1582973D03*
X1677556Y1656405D03*
X1674356D03*
X1671156D03*
X1666168Y1667688D03*
X1670202Y1663150D03*
X1675290Y1663157D03*
X1674338Y1677832D03*
X1671902Y1676267D03*
X1669377Y1675241D03*
X1670773Y1688827D03*
X1680029Y1710609D03*
Y1715609D03*
X1672500Y1708927D03*
X1675360Y1721252D03*
X1689367Y26477D03*
X1682299Y19541D03*
X1685967Y26477D03*
X1678899Y19541D03*
X1695100Y121762D03*
X1683275Y120762D03*
X1695100Y136762D03*
Y131762D03*
X1684925D03*
Y136762D03*
Y123762D03*
Y126762D03*
Y145762D03*
X1695100Y146762D03*
X1684925Y141762D03*
X1695100Y156762D03*
Y161762D03*
Y166762D03*
X1684925Y157762D03*
Y166762D03*
X1678809Y206451D03*
X1682433Y220857D03*
X1682408Y228337D03*
X1689000Y234000D03*
X1692429Y403985D03*
X1694050Y416643D03*
X1690208Y421855D03*
X1690140Y434160D03*
X1692450Y436772D03*
X1692974Y553115D03*
X1685890Y708610D03*
X1684672Y1313837D03*
X1690697Y1329066D03*
Y1326566D03*
X1684672Y1322837D03*
Y1319837D03*
Y1316837D03*
X1690697Y1336566D03*
Y1334066D03*
Y1331566D03*
X1679028Y1341733D03*
X1687234Y1341533D03*
Y1344033D03*
X1679028Y1344233D03*
X1690697Y1339066D03*
X1686172Y1386416D03*
Y1388957D03*
X1687665Y1397331D03*
X1692934Y1397483D03*
Y1399991D03*
X1689945Y1393806D03*
X1682500Y1390475D03*
X1680300Y1391875D03*
X1682500Y1396275D03*
X1680400Y1394875D03*
X1678234Y1393605D03*
Y1396505D03*
X1682500Y1393375D03*
X1683741Y1443075D03*
X1681538Y1451522D03*
X1689062Y1451496D03*
X1687783Y1472068D03*
X1680730Y1517082D03*
Y1513682D03*
Y1530482D03*
Y1527082D03*
X1685745Y1552579D03*
X1686219Y1549994D03*
X1685745Y1555079D03*
Y1557579D03*
X1685995Y1561516D03*
X1680589Y1559626D03*
Y1563526D03*
X1690353Y1591494D03*
X1680695Y1656307D03*
X1686675Y1659287D03*
X1692415Y1663740D03*
X1685500Y1663599D03*
X1680367Y1663367D03*
X1691952Y1698947D03*
X1689184Y1702095D03*
X1683029Y1708609D03*
X1680877Y1723593D03*
X1692218Y1717539D03*
X1685383Y1729559D03*
X1707186Y15708D03*
X1696472Y19541D03*
X1693072D03*
X1703583Y26505D03*
X1700183D03*
X1703536Y50649D03*
X1700136D03*
X1695100Y126762D03*
Y141762D03*
Y151762D03*
X1705120Y143610D03*
X1693000Y234000D03*
X1698220Y369652D03*
X1699809Y403985D03*
X1695579D03*
X1702959Y404243D03*
X1697161Y406602D03*
X1706500Y415862D03*
Y413362D03*
X1707780Y410738D03*
X1695455Y422287D03*
X1707568Y420370D03*
X1701124Y423802D03*
X1707544Y431745D03*
X1704974Y553115D03*
X1700974D03*
X1696974D03*
X1693490Y620672D03*
X1697530Y636369D03*
X1701661Y644554D03*
X1705561D03*
X1699500Y654738D03*
Y673738D03*
X1694490Y767265D03*
Y771065D03*
X1708049Y766870D03*
X1699072Y1313737D03*
X1696047Y1326576D03*
X1705383D03*
X1693417Y1329266D03*
X1693217Y1326566D03*
X1699072Y1322737D03*
Y1319737D03*
Y1316737D03*
X1693417Y1334266D03*
Y1331766D03*
X1705383Y1334676D03*
X1696047D03*
X1705383Y1329676D03*
X1696047Y1332176D03*
Y1329676D03*
X1705383Y1332176D03*
X1693417Y1336766D03*
Y1339266D03*
X1700376Y1399528D03*
X1696888Y1397928D03*
X1699626Y1396960D03*
X1703392Y1390270D03*
X1705822D03*
X1700272Y1460547D03*
X1702281Y1449801D03*
X1705108Y1451774D03*
X1695020Y1465621D03*
X1698440Y1466590D03*
X1705246Y1465325D03*
X1701348Y1466557D03*
X1709964Y1597490D03*
X1709833Y1612940D03*
Y1606340D03*
X1701984Y1671618D03*
X1695987D03*
X1700156Y1698830D03*
X1702750Y1696185D03*
X1706086Y1691568D03*
X1717148Y19910D03*
X1712977Y19986D03*
X1722148Y19910D03*
X1722085Y25908D03*
X1717055D03*
X1710106Y39768D03*
X1723241Y48822D03*
X1710106Y48978D03*
X1721646Y68115D03*
X1716558Y67866D03*
X1715861Y72593D03*
X1712486Y117908D03*
X1712686Y111908D03*
X1719909Y112713D03*
Y116713D03*
X1713399Y132858D03*
X1721384Y135373D03*
X1717384D03*
X1716609Y141297D03*
X1721628Y147312D03*
X1714293Y156278D03*
X1711293D03*
X1716893D03*
X1719493D03*
X1722093D03*
X1711293Y158878D03*
X1714293D03*
X1711293Y161478D03*
X1714293D03*
X1711293Y163978D03*
X1714293D03*
X1711293Y166478D03*
X1714293D03*
X1722093Y158878D03*
X1719493D03*
X1716893D03*
X1722093Y161478D03*
Y163978D03*
Y166478D03*
X1719493Y161478D03*
X1716893D03*
X1719493Y163978D03*
X1716893D03*
Y166478D03*
X1719493D03*
X1719200Y371162D03*
X1717220Y381152D03*
X1713720D03*
X1717220Y384652D03*
Y388152D03*
X1713720D03*
Y384652D03*
X1717220Y391652D03*
X1713720D03*
X1709000Y415862D03*
Y413362D03*
X1709339Y637251D03*
X1718465Y657982D03*
X1720050Y649142D03*
X1716030Y668182D03*
X1709759Y670221D03*
X1718686Y676154D03*
X1722672Y1313237D03*
X1708672Y1313737D03*
X1707916Y1329319D03*
X1722672Y1316237D03*
X1708672Y1322737D03*
Y1319737D03*
X1710536Y1329119D03*
X1708016Y1326619D03*
X1710536D03*
X1722672Y1319237D03*
Y1322237D03*
X1719916Y1326559D03*
X1717396D03*
X1719916Y1329059D03*
X1717396D03*
X1708672Y1316737D03*
X1707916Y1334319D03*
Y1331819D03*
Y1339319D03*
Y1336819D03*
X1710536Y1336619D03*
Y1339119D03*
X1719916Y1339059D03*
X1717396D03*
X1719916Y1336559D03*
X1717396D03*
X1710536Y1334119D03*
Y1331619D03*
X1719916Y1331559D03*
Y1334059D03*
X1717396D03*
Y1331559D03*
X1710176Y1342089D03*
X1718706Y1341629D03*
Y1344129D03*
X1710176Y1344589D03*
X1708713Y1384435D03*
Y1387335D03*
X1708252Y1390270D03*
X1715282Y1396375D03*
X1713082Y1391975D03*
X1715282Y1390575D03*
X1711016Y1393705D03*
Y1396605D03*
X1713182Y1394975D03*
X1715282Y1393475D03*
X1717447Y1417213D03*
X1714447D03*
X1717447Y1423213D03*
Y1420213D03*
X1714447D03*
Y1423213D03*
X1722334Y1468146D03*
X1718425Y1468245D03*
X1722347Y1471246D03*
X1716070Y1472037D03*
X1712870Y1586615D03*
X1715693Y1597190D03*
X1713593Y1609640D03*
Y1603040D03*
X1720845Y1668498D03*
X1719181Y1706712D03*
X1721172Y1712115D03*
X1710360Y1706502D03*
X1721912Y1705115D03*
X1719218Y1727265D03*
X1719148Y1721530D03*
X1722149Y1720265D03*
X1710230Y1729654D03*
X1736006Y41838D03*
Y44338D03*
X1729836Y54524D03*
X1727336D03*
X1724685Y51454D03*
X1727225Y51424D03*
X1729895Y51354D03*
X1726741Y48822D03*
X1730241D03*
X1737617Y75640D03*
Y73140D03*
Y79140D03*
Y81640D03*
X1722984Y101713D03*
X1723184Y93313D03*
X1736731Y102293D03*
X1728965Y112941D03*
X1729046Y118178D03*
X1739686Y120938D03*
X1725093Y156278D03*
Y158878D03*
Y161478D03*
Y163978D03*
Y166478D03*
X1735471Y293682D03*
Y290682D03*
Y296682D03*
Y299682D03*
X1730331Y293722D03*
Y296722D03*
X1732831D03*
X1730331Y299722D03*
X1732831D03*
Y293722D03*
X1723492Y293068D03*
X1732751Y305732D03*
X1730251D03*
X1732751Y302732D03*
X1730251D03*
X1735391Y305692D03*
Y302692D03*
X1725344Y359334D03*
X1728300Y377787D03*
X1733043Y657091D03*
X1736848Y650974D03*
X1726409Y653641D03*
X1737002Y671494D03*
X1724191Y767299D03*
Y771099D03*
X1737850Y766794D03*
X1732702Y1313007D03*
Y1316007D03*
Y1322007D03*
Y1319007D03*
X1732766Y1410562D03*
Y1413062D03*
X1735266Y1410562D03*
Y1413062D03*
X1732766Y1426362D03*
Y1428862D03*
X1735266Y1426362D03*
Y1428862D03*
X1730004Y1540968D03*
X1726604Y1540970D03*
X1735379Y1566282D03*
X1735354Y1580480D03*
X1735351Y1569832D03*
X1736479Y1584330D03*
X1730202Y1602093D03*
X1735463Y1651965D03*
X1730381Y1647386D03*
X1726381D03*
X1734500Y1656965D03*
X1734589Y1666203D03*
X1734962Y1662965D03*
X1734963Y1673465D03*
X1724263Y1672465D03*
X1734763Y1680465D03*
X1735463Y1694465D03*
X1725423Y1692656D03*
X1731936Y1690165D03*
X1731117Y1715265D03*
X1732251Y1708265D03*
X1731117Y1730415D03*
X1748708Y26641D03*
X1751031Y39063D03*
X1738093Y53103D03*
Y55603D03*
X1741621Y76613D03*
Y74113D03*
Y82613D03*
Y80113D03*
X1743491Y92827D03*
X1738435Y100244D03*
X1741935D03*
X1745435D03*
X1740231Y102293D03*
X1743731D03*
X1748686Y97408D03*
X1740091Y92827D03*
X1750786Y120018D03*
X1744976Y122998D03*
X1754339Y128242D03*
X1752022Y269794D03*
Y266794D03*
X1742971Y293682D03*
Y290682D03*
X1737971D03*
X1740471Y293682D03*
Y290682D03*
Y299682D03*
X1737971D03*
X1740471Y296682D03*
X1737971D03*
Y293682D03*
X1751352Y293386D03*
X1745671Y290682D03*
Y293682D03*
X1737891Y302692D03*
X1740391D03*
X1737891Y305692D03*
X1740391D03*
X1744510Y377452D03*
X1744380Y382892D03*
X1742398Y484304D03*
X1742306Y661032D03*
X1745484Y668216D03*
X1751490Y713890D03*
X1748990D03*
X1746490D03*
X1743990D03*
X1751490Y706390D03*
X1748990D03*
X1746490D03*
X1743990D03*
X1751490Y708890D03*
X1748990D03*
X1746490D03*
X1743990D03*
X1751490Y711390D03*
X1748990D03*
X1746490D03*
X1743990D03*
X1742766Y1418462D03*
Y1415962D03*
X1737766Y1410562D03*
Y1413062D03*
X1740266Y1410562D03*
Y1413062D03*
X1742766D03*
Y1410562D03*
X1740266Y1415962D03*
Y1418462D03*
X1737766Y1426362D03*
Y1428862D03*
X1742766Y1423462D03*
X1740266Y1426362D03*
Y1423462D03*
Y1420962D03*
X1742766D03*
X1741329Y1506405D03*
Y1503405D03*
Y1509405D03*
Y1512405D03*
X1745543Y1518678D03*
X1742758Y1521239D03*
X1745746D03*
X1751120Y1521223D03*
X1751087Y1518704D03*
X1748346Y1521223D03*
X1748313Y1518704D03*
X1739565Y1528105D03*
X1751132Y1526748D03*
Y1524248D03*
Y1529248D03*
X1742810Y1524534D03*
X1745410D03*
X1748358Y1526748D03*
Y1524248D03*
Y1529248D03*
X1746779Y1583378D03*
X1751558Y1579332D03*
X1746079Y1587705D03*
X1750463Y1654465D03*
X1744963Y1656465D03*
X1744463Y1651229D03*
X1747986Y1686215D03*
X1751340Y1686140D03*
X1744620Y1716018D03*
X1750380Y1707468D03*
X1747120Y1710824D03*
X1749480Y1718158D03*
X1765920Y17031D03*
X1765980Y27031D03*
X1765920Y22031D03*
X1758638Y26477D03*
X1755238D03*
X1767266Y48748D03*
X1763010Y51223D03*
X1765527Y53692D03*
X1758635Y50649D03*
X1755235D03*
X1757923Y72637D03*
X1767956Y76843D03*
X1767136Y83653D03*
X1761417Y90017D03*
X1760444Y106173D03*
X1763644D03*
X1755944Y111073D03*
Y108473D03*
X1760944Y116773D03*
X1757944D03*
X1760124Y128246D03*
X1755504Y202263D03*
X1758030D03*
X1762564Y202326D03*
X1765090D03*
X1761573Y266657D03*
X1764573D03*
X1761573Y269657D03*
X1764573D03*
X1758022Y269794D03*
Y266794D03*
X1755022Y269794D03*
Y266794D03*
X1755772Y278859D03*
X1758772D03*
X1761772D03*
X1755772Y281859D03*
X1758772D03*
X1761772D03*
X1752772Y278859D03*
Y281859D03*
X1756800Y364048D03*
Y368048D03*
X1756933Y372452D03*
X1759379Y507927D03*
X1753566Y512968D03*
X1768041Y556537D03*
X1753990Y711390D03*
Y708890D03*
Y706390D03*
Y713890D03*
X1753891Y767305D03*
Y771105D03*
X1767450Y766870D03*
X1759949Y1297324D03*
X1764267Y1460080D03*
X1756329Y1506405D03*
Y1503405D03*
X1764029Y1506405D03*
Y1503405D03*
X1756329Y1509405D03*
Y1512405D03*
X1764029Y1509405D03*
Y1512405D03*
X1765286Y1518471D03*
X1765176Y1515902D03*
X1765286Y1521095D03*
X1765246Y1524001D03*
Y1526601D03*
X1765334Y1529342D03*
X1764679Y1572105D03*
X1765679Y1575405D03*
X1762679D03*
X1766079Y1578705D03*
X1763079D03*
X1753512Y1583478D03*
X1763706Y1616451D03*
X1760206D03*
X1767206D03*
X1765854Y1646456D03*
X1755463Y1654465D03*
X1767888Y1664465D03*
X1762263Y1671765D03*
X1765163Y1670543D03*
X1765463Y1677465D03*
X1761463Y1683465D03*
X1775920Y17031D03*
X1770920D03*
X1775920Y27068D03*
X1770920Y22031D03*
X1775920D03*
X1768956Y37558D03*
X1777720Y37792D03*
X1773830Y49000D03*
X1779377Y50738D03*
X1774294Y60133D03*
X1774291Y57191D03*
X1769240Y50788D03*
X1769200Y54300D03*
X1780300Y54400D03*
X1775546Y73376D03*
X1774294Y63033D03*
X1779744Y72973D03*
Y70073D03*
X1770334Y72737D03*
X1778205Y90982D03*
X1781451Y88238D03*
X1773577Y88339D03*
X1778544Y97973D03*
X1769244Y113773D03*
Y110973D03*
Y108073D03*
X1781368Y162824D03*
X1780929Y179408D03*
X1776930Y179051D03*
X1773581Y194120D03*
X1771055D03*
X1771931Y200920D03*
X1769405D03*
X1777170Y201002D03*
X1774644D03*
X1778796Y261633D03*
X1767573Y266657D03*
X1775633Y261666D03*
X1767573Y269657D03*
X1778796Y266633D03*
Y269133D03*
Y264133D03*
X1775633Y269166D03*
Y266666D03*
Y264166D03*
X1778796Y271633D03*
X1775633Y271666D03*
X1770280Y372452D03*
X1770220Y382952D03*
Y377452D03*
X1782324Y403932D03*
Y410432D03*
Y418932D03*
Y425432D03*
X1779376Y558324D03*
X1782376D03*
X1773963Y557537D03*
X1776986Y749023D03*
X1776550Y763765D03*
X1769650Y1280200D03*
X1771000Y1278060D03*
X1782369Y1447581D03*
X1782385Y1450095D03*
X1782337Y1453191D03*
X1775682Y1466568D03*
X1779029Y1506405D03*
Y1503405D03*
Y1509405D03*
Y1512405D03*
X1780012Y1518631D03*
Y1516031D03*
Y1521231D03*
X1777152Y1518631D03*
Y1516031D03*
Y1521231D03*
X1774552D03*
Y1516031D03*
Y1518631D03*
X1768176Y1515902D03*
X1768286Y1518471D03*
Y1521095D03*
X1770886D03*
Y1518471D03*
X1770776Y1515902D03*
X1780039Y1523860D03*
Y1526360D03*
X1779997Y1528888D03*
X1777179Y1526360D03*
Y1523860D03*
X1774579D03*
Y1526360D03*
X1768246Y1526601D03*
Y1524001D03*
X1768334Y1529342D03*
X1770846Y1524001D03*
Y1526601D03*
X1771079Y1566782D03*
X1770404Y1575330D03*
X1780579Y1582178D03*
X1771094Y1570332D03*
X1778794Y1585332D03*
X1768105Y1595925D03*
X1775794Y1585332D03*
X1768030Y1599249D03*
X1768180Y1606549D03*
X1768030Y1603149D03*
X1780154Y1615026D03*
X1777454D03*
X1780154Y1617726D03*
X1777454D03*
X1773349Y1631938D03*
Y1634438D03*
Y1636938D03*
X1770649Y1631938D03*
Y1634438D03*
X1781423Y1634394D03*
Y1636894D03*
X1778723Y1634294D03*
X1776023D03*
Y1636894D03*
X1778723D03*
X1773929Y1657465D03*
Y1654956D03*
X1768929Y1651956D03*
X1774338Y1676865D03*
X1771038Y1692956D03*
X1787826Y37548D03*
X1783700Y50011D03*
X1794099Y50461D03*
X1788204Y74958D03*
X1785108Y76078D03*
X1787756Y85178D03*
X1788204Y82338D03*
Y78108D03*
X1784144Y113973D03*
Y111173D03*
Y108273D03*
X1797692Y146285D03*
X1784006Y137395D03*
X1788950Y142750D03*
X1787390Y165834D03*
Y156834D03*
Y151834D03*
X1793444Y178083D03*
X1785320Y193072D03*
X1784915Y186053D03*
X1783896Y266633D03*
Y269133D03*
X1794174Y274499D03*
X1790674D03*
X1783896Y271633D03*
X1789771Y367866D03*
X1797929Y385293D03*
X1786260Y379059D03*
X1792507Y403932D03*
X1792335Y418775D03*
X1792450Y410615D03*
X1792220Y425432D03*
X1785376Y558324D03*
X1788376D03*
X1792895Y683536D03*
X1783592Y767565D03*
Y771365D03*
X1792692Y766870D03*
X1794362Y1275546D03*
X1785336Y1447565D03*
Y1450065D03*
X1785634Y1456326D03*
X1782530Y1456229D03*
X1785408Y1453385D03*
X1788029Y1506405D03*
Y1503405D03*
Y1509405D03*
Y1512405D03*
X1794265Y1518262D03*
Y1520862D03*
Y1523462D03*
Y1526062D03*
X1794268Y1528720D03*
X1784601Y1578967D03*
X1787239Y1579406D03*
X1789294Y1583278D03*
X1797118Y1596588D03*
X1797143Y1607014D03*
X1797076Y1603662D03*
X1797043Y1599811D03*
X1791979Y1616550D03*
X1795479D03*
X1782654Y1615026D03*
Y1617726D03*
X1784048Y1636875D03*
Y1634375D03*
X1786615Y1631800D03*
X1786588Y1634472D03*
X1786624Y1637021D03*
X1802565Y156557D03*
X1800554Y177229D03*
X1808622Y170869D03*
X1806470Y186866D03*
X1802570Y186913D03*
X1811274Y198098D03*
X1807596Y264133D03*
Y266633D03*
Y269133D03*
X1797674Y274499D03*
X1801174D03*
X1807596Y271633D03*
X1800160Y362542D03*
X1808962Y698055D03*
Y700555D03*
Y703055D03*
X1798462Y698055D03*
X1801962D03*
X1805462D03*
Y700555D03*
X1801962D03*
X1798462D03*
X1805462Y703055D03*
X1801962D03*
X1798462D03*
X1808962Y705555D03*
Y708055D03*
X1798462Y705555D03*
X1801962D03*
X1805462D03*
X1798462Y708055D03*
X1801962D03*
X1805462D03*
X1809002Y710945D03*
Y713445D03*
Y715945D03*
X1805502Y710945D03*
Y713445D03*
Y715945D03*
X1802050Y710940D03*
X1811526Y1281671D03*
X1803029Y1506405D03*
Y1503405D03*
X1812029Y1506405D03*
Y1503405D03*
X1803029Y1509405D03*
Y1512405D03*
X1812029Y1509405D03*
Y1512405D03*
X1797362Y1518304D03*
X1799882Y1520912D03*
Y1518312D03*
X1797362Y1520904D03*
X1804049Y1528031D03*
X1799882Y1523512D03*
X1797362Y1523504D03*
X1799882Y1526112D03*
X1797362Y1526104D03*
X1799994Y1528674D03*
X1797450Y1528768D03*
X1809890Y1524532D03*
X1807290D03*
X1798479Y1575605D03*
X1798879Y1578905D03*
X1801479Y1575605D03*
X1800479Y1572305D03*
X1801879Y1578905D03*
X1798979Y1616550D03*
X1815005Y149325D03*
X1817196Y163797D03*
Y159947D03*
X1818828Y175241D03*
X1817275Y180619D03*
X1813224Y194699D03*
X1816190Y208879D03*
X1817157Y373829D03*
X1828669Y379552D03*
X1816994Y398052D03*
X1816224Y410432D03*
X1822724Y424948D03*
X1815724Y423932D03*
X1825874Y424948D03*
X1822394Y436225D03*
X1827073Y565157D03*
X1824073D03*
X1821073D03*
X1812462Y698055D03*
Y700555D03*
Y703055D03*
Y705555D03*
Y708055D03*
X1812502Y710945D03*
Y713445D03*
Y715945D03*
X1827029Y1506405D03*
Y1503405D03*
Y1509405D03*
Y1512405D03*
X1818475Y1524682D03*
X1815875D03*
X1823649Y1525144D03*
X1831166Y149986D03*
X1827580Y151834D03*
X1829732Y371329D03*
X1828483Y431678D03*
X1833288Y1469639D03*
X1850791Y170287D03*
G54D30*
X180780Y1507509D03*
X178580D03*
X177487Y1521612D03*
X177086Y1518121D03*
X178745Y1513218D03*
X177533Y1535698D03*
Y1537898D03*
X178980Y1540317D03*
X183051Y1544625D03*
X188155Y1516970D03*
X192879D03*
X197604D03*
X189730Y1519698D03*
X194454D03*
X199178D03*
X202328Y1516970D03*
X207052D03*
X211777D03*
X216501D03*
X203903Y1519698D03*
X208627D03*
X213352D03*
X221226Y1516970D03*
X225950D03*
X230674D03*
X218076Y1519698D03*
X222800D03*
X227525D03*
X235399Y1516970D03*
X240123D03*
X244848D03*
X236974Y1519698D03*
X241698D03*
X246422D03*
X232249D03*
X249572Y1516970D03*
X254297D03*
X259021D03*
X251147Y1519698D03*
X255871D03*
X260596D03*
X265421Y1507355D03*
X263321D03*
X266828Y1514073D03*
X266772Y1516336D03*
X267123Y1536640D03*
Y1534540D03*
X267124Y1531618D03*
X267035Y1528698D03*
X266538Y1538658D03*
X305549Y1521612D03*
X305148Y1518121D03*
X305595Y1535698D03*
Y1537898D03*
X316107Y895569D03*
X314256Y905135D03*
Y924269D03*
X316107Y914702D03*
Y933836D03*
Y952970D03*
X314256Y943403D03*
Y962537D03*
X316107Y972104D03*
X314256Y981671D03*
Y1000805D03*
X316107Y991238D03*
X317957Y988049D03*
X317288Y1028056D03*
X313587D03*
X320988D03*
X315437Y1037623D03*
X319138Y1031245D03*
X315437Y1056757D03*
X317288Y1047190D03*
X319138Y1056757D03*
X320988Y1047190D03*
X317288Y1066324D03*
Y1085458D03*
X315437Y1075891D03*
X317288Y1104592D03*
X315437Y1095025D03*
Y1114159D03*
Y1133293D03*
X317288Y1123726D03*
Y1142859D03*
X315437Y1158804D03*
Y1152426D03*
X319138Y1158804D03*
X308893Y1507460D03*
X316217Y1516970D03*
X320941D03*
X317792Y1519698D03*
X306807Y1513218D03*
X316217Y1530608D03*
X320941D03*
X317792Y1533336D03*
X311113Y1544625D03*
X307042Y1540317D03*
X327209Y882813D03*
X332760Y886002D03*
X330910Y889191D03*
Y895569D03*
X332760Y892380D03*
X323508Y882813D03*
X330910Y908325D03*
X332760Y898758D03*
X330910Y901947D03*
X332760Y905135D03*
Y911513D03*
Y917891D03*
X330910Y921080D03*
X332760Y924269D03*
X330910Y914702D03*
Y927458D03*
X332760Y937025D03*
X330910Y940214D03*
Y933836D03*
X332760Y930647D03*
Y943403D03*
X330910Y946592D03*
X332760Y956159D03*
X330910Y952970D03*
X332760Y949781D03*
Y962537D03*
X330910Y965726D03*
Y959348D03*
X332760Y968915D03*
Y975293D03*
X330910Y978482D03*
Y972104D03*
X332760Y994427D03*
X330910Y997616D03*
X332760Y1000805D03*
X330910Y991238D03*
X332760Y988049D03*
X323508Y991238D03*
X330910Y1010372D03*
X332760Y1007183D03*
X330910Y1003994D03*
X323508Y1010372D03*
X324689Y1028056D03*
X332091D03*
Y1034434D03*
X333941Y1037623D03*
X332091Y1040812D03*
X333941Y1044001D03*
Y1031245D03*
X326540Y1044001D03*
X332091Y1059946D03*
X333941Y1050379D03*
X332091Y1053568D03*
X333941Y1056757D03*
X332091Y1047190D03*
X324689Y1053568D03*
X332091Y1072702D03*
X333941Y1063135D03*
Y1069513D03*
X332091Y1066324D03*
X333941Y1075891D03*
X332091Y1079080D03*
X333941Y1082269D03*
Y1088647D03*
X332091Y1085458D03*
X333941Y1101403D03*
X332091Y1091836D03*
X333941Y1095025D03*
X332091Y1098214D03*
Y1104592D03*
Y1110970D03*
X333941Y1114159D03*
X332091Y1117348D03*
X333941Y1107781D03*
Y1120537D03*
X332091Y1130103D03*
X333941Y1133293D03*
Y1126915D03*
X332091Y1123726D03*
Y1136481D03*
X333941Y1139670D03*
X332091Y1149237D03*
X333941Y1146048D03*
X332091Y1142859D03*
X333941Y1152426D03*
X332091Y1155615D03*
Y1161993D03*
X333941Y1165182D03*
X326539D03*
X324689Y1161993D03*
X325666Y1516970D03*
X330390D03*
X335114D03*
X322516Y1519698D03*
X327240D03*
X331965D03*
X325666Y1530608D03*
X330390D03*
X335114D03*
X322516Y1533336D03*
X327240D03*
X331965D03*
X343862Y886002D03*
X349414Y889191D03*
X345713D03*
Y895569D03*
X349414D03*
X343862Y892380D03*
X338311Y889191D03*
X336461Y892380D03*
X338311Y895569D03*
X342012D03*
X345713Y908325D03*
X343862Y898758D03*
X349414Y901947D03*
X345713D03*
X343862Y905135D03*
X349414Y908325D03*
X343862Y911513D03*
X336461D03*
X338311Y901947D03*
X336461Y905135D03*
X338311Y908325D03*
X336461Y898758D03*
X340162Y905135D03*
X343862Y917891D03*
X349414Y921080D03*
X345713D03*
X343862Y924269D03*
X345713Y914702D03*
X349414D03*
X338311Y921080D03*
X336461Y924269D03*
X338311Y914702D03*
X336461Y917891D03*
X340162Y924269D03*
X342012Y914702D03*
X349414Y927458D03*
X345713D03*
X343862Y937025D03*
X349414Y940214D03*
X345713D03*
Y933836D03*
X349414D03*
X343862Y930647D03*
X338311Y927458D03*
X336461Y930647D03*
X338311Y940214D03*
Y933836D03*
X336461Y937025D03*
X342012Y933836D03*
X343862Y943403D03*
X349414Y946592D03*
X345713D03*
X343862Y956159D03*
X345713Y952970D03*
X349414D03*
X343862Y949781D03*
X336461Y943403D03*
X338311Y946592D03*
X336461Y949781D03*
X338311Y952970D03*
X336461Y956159D03*
X342012Y952970D03*
X340162Y943403D03*
X343862Y962537D03*
X349414Y965726D03*
X345713D03*
X349414Y959348D03*
X345713D03*
X343862Y968915D03*
X338311Y965726D03*
X336461Y968915D03*
X338311Y959348D03*
X336461Y962537D03*
X340162D03*
X349414Y984860D03*
X343862Y975293D03*
X349414Y978482D03*
X345713D03*
Y972104D03*
X349414D03*
X338311Y984860D03*
Y978482D03*
X336461Y981671D03*
X338311Y972104D03*
X336461Y975293D03*
X342012Y972104D03*
X340162Y981671D03*
X343862Y994427D03*
X345713Y997616D03*
X349414D03*
X343862Y1000805D03*
X345713Y991238D03*
X336461Y988049D03*
X338311Y997616D03*
X336461Y1000805D03*
Y994427D03*
X340162Y1000805D03*
X342012Y991238D03*
X338311D03*
X349414D03*
X343862Y988049D03*
X345713Y1010372D03*
X343862Y1007183D03*
X345713Y1003994D03*
X349414D03*
X338311D03*
X336461Y1007183D03*
X338311Y1010372D03*
X349414D03*
X343193Y1028056D03*
X350595D03*
X339492D03*
X346894D03*
X350595Y1034434D03*
X346894D03*
X345043Y1037623D03*
X350595Y1040812D03*
X346894D03*
X345043Y1044001D03*
X337642Y1031245D03*
X339492Y1034434D03*
X337642Y1037623D03*
X339492Y1040812D03*
X341343Y1037623D03*
X337642Y1044001D03*
X345043Y1031245D03*
X346894Y1059946D03*
X350595Y1047190D03*
X345043Y1050379D03*
X346894Y1053568D03*
X337642Y1050379D03*
X339492Y1047190D03*
X341343Y1056757D03*
X343193Y1047190D03*
X339492Y1053568D03*
X345043Y1056757D03*
X346894Y1047190D03*
X350595Y1053568D03*
X346894Y1072702D03*
X345043Y1063135D03*
X350595Y1066324D03*
X345043Y1069513D03*
X350595Y1072702D03*
X346894Y1066324D03*
X337642Y1063135D03*
X339492Y1066324D03*
X337642Y1069513D03*
X339492Y1072702D03*
X343193Y1066324D03*
X345043Y1075891D03*
X350595Y1079080D03*
X346894D03*
X345043Y1082269D03*
X350595Y1085458D03*
X345043Y1088647D03*
X346894Y1085458D03*
X337642Y1075891D03*
X339492Y1079080D03*
X337642Y1082269D03*
X339492Y1085458D03*
X337642Y1088647D03*
X343193Y1085458D03*
X341343Y1075891D03*
X345043Y1101403D03*
X350595Y1104592D03*
X346894Y1091836D03*
X345043Y1095025D03*
X350595Y1098214D03*
X346894D03*
Y1104592D03*
X350595Y1091836D03*
X339492Y1104592D03*
X337642Y1095025D03*
X339492Y1098214D03*
X337642Y1101403D03*
X339492Y1091836D03*
X341343Y1095025D03*
X343193Y1104592D03*
X346894Y1110970D03*
X345043Y1114159D03*
X350595Y1117348D03*
X346894D03*
X345043Y1107781D03*
X350595Y1110970D03*
X337642Y1114159D03*
X339492Y1117348D03*
X337642Y1107781D03*
X339492Y1110970D03*
X341343Y1114159D03*
X345043Y1120537D03*
X350595Y1123726D03*
X346894Y1130103D03*
X345043Y1133293D03*
Y1126915D03*
X346894Y1123726D03*
X350595Y1130103D03*
X337642Y1120537D03*
X339492Y1123726D03*
X337642Y1133293D03*
Y1126915D03*
X339492Y1130103D03*
X343193Y1123726D03*
X341343Y1133293D03*
X350595Y1136481D03*
X346894D03*
X345043Y1139670D03*
X350595Y1142859D03*
X346894Y1149237D03*
X345043Y1146048D03*
X346894Y1142859D03*
X350595Y1149237D03*
X339492Y1136481D03*
X337642Y1139670D03*
X339492Y1142859D03*
X337642Y1146048D03*
X339492Y1149237D03*
X343193Y1142859D03*
X345043Y1152426D03*
X350595Y1155615D03*
X337642Y1152426D03*
X339492Y1161993D03*
X341343Y1165182D03*
X350595Y1161993D03*
X341343Y1152426D03*
X345043Y1158804D03*
X339839Y1516970D03*
X344563D03*
X349288D03*
X336689Y1519698D03*
X341414D03*
X346138D03*
X350862D03*
X339839Y1530608D03*
X344563D03*
X349288D03*
X336689Y1533336D03*
X341414D03*
X346138D03*
X350862D03*
X364217Y876435D03*
X358665Y879624D03*
X351264Y892380D03*
Y911513D03*
Y905135D03*
Y898758D03*
Y924269D03*
Y917891D03*
Y930647D03*
Y937025D03*
Y943403D03*
Y949781D03*
Y956159D03*
Y968915D03*
Y962537D03*
Y981671D03*
Y975293D03*
Y988049D03*
Y1000805D03*
Y994427D03*
X364217Y991238D03*
X358666Y988049D03*
X351264Y1007183D03*
X364217Y1010372D03*
X365398Y1028056D03*
X357996D03*
X352445Y1031245D03*
Y1037623D03*
X363547Y1044001D03*
X359847Y1031245D03*
X352445Y1044001D03*
Y1050379D03*
X359847Y1056757D03*
X357996Y1047190D03*
X365398Y1053568D03*
X352445Y1063135D03*
Y1069513D03*
Y1075891D03*
Y1082269D03*
Y1088647D03*
Y1095025D03*
Y1101403D03*
Y1114159D03*
Y1107781D03*
Y1120537D03*
Y1133293D03*
Y1126915D03*
Y1139670D03*
Y1146048D03*
Y1152426D03*
X359847Y1165182D03*
X357996Y1161993D03*
X352445Y1165182D03*
X365398Y1161993D03*
X363461Y1516970D03*
X354012D03*
X358736D03*
X365036Y1519698D03*
X355587D03*
X360311D03*
X363461Y1530608D03*
X354012D03*
X358736D03*
X365036Y1533336D03*
X355587D03*
X360311D03*
X367917Y876435D03*
X371618D03*
X379020D03*
X369768Y873246D03*
X373469D03*
X377169D03*
X371618Y882813D03*
X375319D03*
X379020Y889191D03*
X367917Y895569D03*
X366067Y905135D03*
X379020Y901947D03*
X366067Y924269D03*
X367917Y914702D03*
X379020D03*
X367917Y933836D03*
X379020Y927458D03*
X366067Y943403D03*
X367917Y952970D03*
X379020Y946592D03*
X366067Y962537D03*
X379020Y959348D03*
X366067Y981671D03*
X367917Y972104D03*
X379020D03*
X366067Y1000805D03*
X367917Y991238D03*
X375319D03*
X369768Y988049D03*
X379020Y1010372D03*
X375319D03*
X369099Y1028056D03*
X376500D03*
X372799D03*
X367248Y1037623D03*
X378351Y1044001D03*
X370949Y1031245D03*
X367248Y1056757D03*
X369099Y1047190D03*
X370949Y1056757D03*
X372799Y1047190D03*
X376500Y1053568D03*
X369099Y1066324D03*
X380201D03*
X367248Y1075891D03*
X369099Y1085458D03*
X380201Y1079080D03*
Y1091836D03*
X367248Y1095025D03*
X369099Y1104592D03*
X367248Y1114159D03*
X380201Y1110970D03*
X369099Y1123726D03*
X367248Y1133293D03*
X380201Y1123726D03*
Y1149237D03*
X369099Y1142859D03*
X380201Y1136481D03*
X378351Y1165182D03*
X374650D03*
X367248Y1158804D03*
X370949D03*
X369099Y1161993D03*
X372799D03*
X380201D03*
X367248Y1152426D03*
X368185Y1516970D03*
X372910D03*
X377634D03*
X369760Y1519698D03*
X374484D03*
X379209D03*
X368185Y1530608D03*
X372910D03*
X377634D03*
X369760Y1533336D03*
X374484D03*
X379209D03*
X393823Y876435D03*
X382721D03*
X390122D03*
X380870Y879624D03*
X384571D03*
X380870Y873246D03*
X391973D03*
X395673D03*
Y879624D03*
X391973D03*
Y886002D03*
X393823Y895569D03*
X380870Y886002D03*
X382721Y895569D03*
X390122Y889191D03*
X386421Y895569D03*
X395673Y886002D03*
X393823Y908325D03*
X386421D03*
X382721D03*
X393823Y921080D03*
X382721D03*
X386421D03*
X393823Y940214D03*
X382721D03*
X386421D03*
X380870Y937025D03*
X395673D03*
X388272D03*
X391973D03*
X384571D03*
X393823Y952970D03*
X382721D03*
X386421D03*
X393823Y965726D03*
X382721D03*
X386421D03*
X395673Y962537D03*
Y968915D03*
X384571Y962537D03*
Y968915D03*
X388272Y962537D03*
Y968915D03*
X380870Y981671D03*
X382721Y984860D03*
X388272Y981671D03*
X390122Y984860D03*
X386421Y978482D03*
X393823D03*
X395673Y981671D03*
X382721Y978482D03*
X395673Y975293D03*
X384571D03*
X388272D03*
X395673Y994427D03*
Y988049D03*
Y1000805D03*
X380870Y988049D03*
Y994427D03*
X382721Y997616D03*
Y991238D03*
X380870Y1000805D03*
X388272Y994427D03*
X390122Y997616D03*
X388272Y988049D03*
X390122Y991238D03*
X388272Y1000805D03*
X380870Y1007183D03*
X382721Y1003994D03*
X388272Y1007183D03*
X390122Y1003994D03*
X393823Y1010372D03*
X386421D03*
X391303Y1028056D03*
X383902D03*
X382051Y1031245D03*
Y1037623D03*
Y1044001D03*
X391303Y1034434D03*
X389453Y1037623D03*
X391303Y1040812D03*
X389453Y1044001D03*
Y1031245D03*
X383902Y1040812D03*
Y1034434D03*
X395004Y1059946D03*
X383902D03*
X387603D03*
X389453Y1056757D03*
X382051Y1050379D03*
X391303Y1047190D03*
X383902D03*
X391303Y1053568D03*
X389453Y1050379D03*
X383902Y1053568D03*
X385752Y1056757D03*
X382051D03*
X395004Y1072702D03*
X383902D03*
X387603D03*
X395004Y1085458D03*
X383902D03*
X387603D03*
X395004Y1098214D03*
X383902D03*
X387603D03*
X382051Y1101403D03*
X393154D03*
X389453D03*
X385752D03*
X395004Y1117348D03*
X387603D03*
X383902D03*
X395004Y1130103D03*
X387603D03*
X383902D03*
X395004Y1142859D03*
X387603D03*
X383902D03*
X391303Y1149237D03*
X382051Y1152426D03*
X383902Y1161993D03*
X391303D03*
X395004D03*
X393154Y1152426D03*
X393483Y1507355D03*
X391383D03*
X382359Y1516970D03*
X387083D03*
X383933Y1519698D03*
X388658D03*
X394890Y1514073D03*
X394834Y1516336D03*
X382359Y1530608D03*
X387083D03*
X383933Y1533336D03*
X388658D03*
X395185Y1536640D03*
Y1534540D03*
X395186Y1531618D03*
X395097Y1528698D03*
X394600Y1538658D03*
X404925Y876435D03*
X401225D03*
X403075Y879624D03*
X406776D03*
X403075Y873246D03*
X397524Y895569D03*
X403075Y886002D03*
X401225Y889191D03*
X408626Y895569D03*
X404925D03*
X406776Y886002D03*
X410477D03*
X399374D03*
X397524Y908325D03*
X408626D03*
X404925Y908324D03*
X397524Y921080D03*
X408626D03*
X404925D03*
X397524Y940214D03*
X410477Y930647D03*
X406776D03*
X408626Y940214D03*
X404925D03*
X403075Y937025D03*
X404925Y933836D03*
X410477Y937025D03*
X408626Y933836D03*
X399374Y937025D03*
X406776D03*
X397524Y952970D03*
X408626D03*
X404925D03*
X397524Y965726D03*
X408626D03*
X404925D03*
X406776Y962537D03*
Y968915D03*
X399374Y962537D03*
Y968915D03*
X410477Y962537D03*
Y968915D03*
X397524Y978482D03*
Y984860D03*
X404925Y978482D03*
X408626D03*
X410477Y981671D03*
X403075D03*
X404925Y984860D03*
X406776Y975293D03*
X399374D03*
X410477D03*
X397524Y991238D03*
X410477Y988049D03*
X403075D03*
X404925Y991238D03*
X397524Y997616D03*
X403075Y994427D03*
Y1000805D03*
X401225Y1010372D03*
X397524Y1003994D03*
X406763Y1007175D03*
X403075Y1007183D03*
X406094Y1028064D03*
X402406Y1028056D03*
X406104Y1040820D03*
X404256Y1044001D03*
X398705Y1040812D03*
X406094Y1034442D03*
X404256Y1037623D03*
Y1031245D03*
X402406Y1034434D03*
X396855Y1044001D03*
Y1031245D03*
Y1037623D03*
X398705Y1047190D03*
X406107D03*
X404256Y1050379D03*
X398705Y1059946D03*
Y1053568D03*
X396855Y1050379D03*
Y1056757D03*
X409807Y1059946D03*
X406107D03*
Y1053568D03*
X404256Y1056757D03*
X398705Y1072702D03*
X406107D03*
X409807D03*
X398705Y1085458D03*
X406107D03*
X409807D03*
X398705Y1098214D03*
X406107D03*
X409807D03*
Y1104592D03*
X407957Y1101403D03*
X404256D03*
X396855D03*
X406107Y1104592D03*
X400555Y1101403D03*
X398705Y1117348D03*
X407957Y1107781D03*
X406107Y1117348D03*
X409807D03*
X398705Y1130103D03*
X406107D03*
X409807D03*
X398705Y1142859D03*
X406107D03*
X409807D03*
X402406Y1149237D03*
X404256Y1152426D03*
X406107Y1161993D03*
X402406D03*
X416028Y876435D03*
X412327D03*
X423429D03*
X414177Y873246D03*
X412327Y889191D03*
X425280Y886002D03*
X423429Y889191D03*
X419729Y895569D03*
X416028D03*
X414177Y886002D03*
X419729Y908325D03*
X416028D03*
Y921080D03*
X419729D03*
X417878Y930647D03*
X421579D03*
X416028Y940214D03*
X419729D03*
X416028Y952970D03*
X419729D03*
Y965726D03*
X416028D03*
X417878Y962537D03*
Y968915D03*
X421579Y962537D03*
Y968915D03*
X412327Y984860D03*
X416028Y978482D03*
X419729D03*
X425280Y981671D03*
X417878D03*
X419729Y984860D03*
X417878Y975293D03*
X421579D03*
X417878Y988049D03*
X425280D03*
X412315Y997608D03*
X412327Y991238D03*
X419716Y997608D03*
X419729Y991238D03*
X413496Y1040820D03*
X420897D03*
X413508Y1047190D03*
X420910D03*
X419059Y1050379D03*
X411658D03*
X413508Y1053568D03*
X411658Y1056757D03*
X420910Y1053568D03*
X419059Y1056757D03*
X417209Y1059946D03*
X420910D03*
X417209Y1072702D03*
X420910D03*
X417209Y1085458D03*
X420910D03*
Y1098214D03*
X417209D03*
X411658Y1101403D03*
Y1107781D03*
X422760D03*
X419059D03*
X420910Y1117348D03*
X417209D03*
X420910Y1130103D03*
X417209D03*
Y1142859D03*
X420910D03*
X413508Y1149237D03*
X424610D03*
Y1161993D03*
X415358Y1152426D03*
X413508Y1161993D03*
X417209D03*
X427130Y876435D03*
X428981Y892380D03*
X432681D03*
X428981Y911513D03*
X432681D03*
X428981Y898758D03*
X432681D03*
X428981Y924269D03*
X432681D03*
X427130Y933836D03*
X430831D03*
X428981Y943403D03*
Y956159D03*
X432681Y943403D03*
Y956159D03*
X428981Y968915D03*
X432681D03*
X427130Y959348D03*
Y965726D03*
X430831Y959348D03*
Y965726D03*
X427130Y984860D03*
X432681Y981671D03*
X434532Y984860D03*
X427130Y978482D03*
Y972104D03*
X430831Y978482D03*
Y972104D03*
X432681Y988049D03*
X434532Y991238D03*
X427118Y997608D03*
X427130Y991238D03*
X434519Y997608D03*
X428299Y1040820D03*
X428311Y1047190D03*
X435713D03*
X433862Y1050379D03*
X426461D03*
Y1056757D03*
X428311Y1053568D03*
X433862Y1056757D03*
X435713Y1053568D03*
X430162Y1069513D03*
X433862D03*
X430162Y1082269D03*
X433862D03*
X430162Y1095025D03*
X428311Y1104592D03*
X433862Y1095025D03*
X432012Y1104592D03*
X430162Y1114159D03*
X433862D03*
X430162Y1126915D03*
X433862D03*
X430162Y1139670D03*
Y1146048D03*
X433862Y1139670D03*
Y1146048D03*
Y1158804D03*
X432012Y1161993D03*
X428311D03*
X426461Y1152426D03*
X430162D03*
X433862D03*
X432012Y1155615D03*
X426461Y1158804D03*
X428311Y1155615D03*
X454861Y873246D03*
X453011Y876435D03*
X449310D03*
X451160Y879624D03*
X454861D03*
X451160Y873246D03*
Y886002D03*
X454861D03*
X451160Y892380D03*
X447460D03*
Y886002D03*
X449310Y882813D03*
X451160Y911513D03*
X447460D03*
X451160Y898758D03*
X447460D03*
X449310Y921080D03*
Y914702D03*
X453011Y921080D03*
Y914702D03*
X451160Y924269D03*
X447460D03*
X453011Y940214D03*
X449310D03*
Y927458D03*
X453011D03*
X449310Y933836D03*
X453011D03*
Y952970D03*
Y946592D03*
X449310Y952970D03*
Y946592D03*
X451160Y943403D03*
Y956159D03*
X447460Y943403D03*
Y956159D03*
X453011Y959348D03*
Y965726D03*
X449310Y959348D03*
Y965726D03*
X451160Y968915D03*
X447460D03*
X453011Y978482D03*
Y972104D03*
X449310Y978482D03*
Y972104D03*
X451160Y981671D03*
X449310Y984860D03*
X449323Y997608D03*
X451160Y988049D03*
X449310Y991238D03*
X450491Y1047190D03*
X452341Y1056757D03*
X450491Y1053568D03*
X452341Y1050379D03*
X448641Y1069513D03*
X452341D03*
X448641Y1082269D03*
X452341D03*
X448641Y1095025D03*
X452341D03*
X450491Y1104592D03*
X454192D03*
X448641Y1114159D03*
X452341D03*
X448641Y1126915D03*
X452341D03*
X448641Y1139670D03*
X452341D03*
X448641Y1146048D03*
X452341D03*
X450491Y1161993D03*
X452341Y1165182D03*
X454192Y1161993D03*
X452341Y1152426D03*
X448640Y1165182D03*
X448641Y1158804D03*
X452341D03*
X450491Y1155615D03*
X444953Y1507509D03*
X442753D03*
X442918Y1513218D03*
X441660Y1521612D03*
X441259Y1518121D03*
X441706Y1535698D03*
Y1537898D03*
X443153Y1540317D03*
X447224Y1544625D03*
X462263Y879624D03*
X458562D03*
Y873246D03*
X462263D03*
X456712Y876435D03*
X467814D03*
X464113D03*
X465964Y879624D03*
Y873246D03*
X460412Y882813D03*
X464113D03*
X469664Y886002D03*
X456712Y889191D03*
X460412Y895569D03*
X465964Y886002D03*
X467814Y889191D03*
X464113Y895569D03*
X462263Y886002D03*
X458562D03*
X456712Y882813D03*
X458562Y911513D03*
X469664D03*
X462263D03*
X460412Y908325D03*
X464113D03*
X458562Y924269D03*
Y917891D03*
X469664Y924269D03*
Y917891D03*
X462263Y924269D03*
Y917891D03*
X460412Y921080D03*
X464113D03*
X462263Y937025D03*
X458562D03*
X462263Y930647D03*
X458562D03*
X460412Y940214D03*
X469664Y930647D03*
X464113Y940214D03*
X465964Y930647D03*
X469664Y937025D03*
X462263Y956159D03*
Y943403D03*
Y949781D03*
X458562Y956159D03*
Y943403D03*
Y949781D03*
X469664Y956159D03*
Y943403D03*
Y949781D03*
X460412Y952970D03*
X464113D03*
X462263Y962537D03*
Y968915D03*
X458562Y962537D03*
Y968915D03*
X469664Y962537D03*
Y968915D03*
X460412Y965726D03*
X464113D03*
X462263Y975293D03*
X458562D03*
X469664D03*
X460412Y978482D03*
X458562Y981671D03*
X456712Y984860D03*
X464113Y978482D03*
X465964Y981671D03*
X464113Y984860D03*
X458562Y988049D03*
X456724Y997608D03*
X456712Y991238D03*
X464126Y997608D03*
X465964Y988049D03*
X464113Y991238D03*
X457905Y1040820D03*
X465307D03*
X457893Y1047190D03*
X465294D03*
X459743Y1050379D03*
X465294Y1053568D03*
X467145Y1056757D03*
Y1050379D03*
X457893Y1053568D03*
X461593Y1059946D03*
X459743Y1056757D03*
X465294Y1059946D03*
X461593Y1072702D03*
X465294D03*
X461593Y1085458D03*
X465294D03*
X461593Y1098214D03*
X465294D03*
X459743Y1107781D03*
X461593Y1117348D03*
X463444Y1107781D03*
X465294Y1117348D03*
X461593Y1130103D03*
X465294D03*
X461593Y1142859D03*
X457893Y1149237D03*
X465294Y1142859D03*
X468995Y1149237D03*
X467145Y1165182D03*
X468995Y1161993D03*
X465294D03*
X467145Y1152426D03*
X457893Y1161993D03*
X456042Y1152426D03*
X459743Y1165182D03*
X456042Y1158804D03*
X457893Y1155615D03*
X456042Y1165182D03*
X461593Y1161993D03*
Y1155615D03*
X463444Y1152426D03*
Y1158804D03*
X467145D03*
X468995Y1155615D03*
X463444Y1165182D03*
X484467Y873246D03*
X473365D03*
X477066D03*
X484467Y879624D03*
X477066D03*
X473365D03*
X475215Y876435D03*
X478916D03*
X484467Y886002D03*
X480767D03*
X473365D03*
X477066D03*
X475215Y895569D03*
X471515D03*
X478916Y889191D03*
X482617Y895569D03*
X480767Y911513D03*
X484467D03*
X473365D03*
X475215Y908325D03*
X471515D03*
X482617D03*
X480767Y917891D03*
Y924269D03*
X484467Y917891D03*
Y924269D03*
X473365D03*
Y917891D03*
X475215Y921080D03*
X471515D03*
X482617D03*
X480767Y930647D03*
X484467D03*
X473365D03*
X471515Y940214D03*
X475215D03*
X482617D03*
X477066Y937025D03*
X480767D03*
X475215Y933836D03*
X471515D03*
X484467Y937025D03*
X473365D03*
X484467Y956159D03*
Y943403D03*
Y949781D03*
X473365Y956159D03*
Y943403D03*
Y949781D03*
X480767Y956159D03*
Y943403D03*
Y949781D03*
X475215Y952970D03*
X471515D03*
X482617D03*
X484467Y962537D03*
Y968915D03*
X473365Y962537D03*
Y968915D03*
X480767Y962537D03*
Y968915D03*
X475215Y965726D03*
X471515D03*
X482617D03*
X484467Y975293D03*
X473365D03*
X480767D03*
X475215Y978482D03*
X471515D03*
X473365Y981671D03*
X471515Y984860D03*
X478916D03*
X482617Y978482D03*
X480767Y981671D03*
X473365Y988049D03*
X471527Y997608D03*
X471515Y991238D03*
X478916Y997616D03*
Y991238D03*
X480767Y994427D03*
Y988049D03*
Y1000805D03*
X478916Y1003994D03*
Y1010372D03*
X480767Y1007183D03*
X483798Y1028056D03*
X472708Y1040820D03*
X481948Y1044001D03*
Y1037623D03*
X480097Y1040812D03*
X483798Y1034434D03*
X478247Y1031245D03*
X472696Y1047190D03*
X480097D03*
X474546Y1050379D03*
Y1056757D03*
X472696Y1053568D03*
Y1059946D03*
X476397D03*
X483798D03*
X481948Y1056757D03*
X480097Y1053568D03*
X481948Y1050379D03*
X476397Y1072702D03*
X472696D03*
X483798D03*
X472696Y1085458D03*
X476397D03*
X483798D03*
X472696Y1098214D03*
X476397D03*
X483798D03*
X478247Y1101403D03*
X472696Y1104592D03*
X481948Y1101403D03*
X476397Y1104592D03*
X470845Y1101403D03*
X474546D03*
X470845Y1107781D03*
X474546D03*
X476397Y1117348D03*
X472696D03*
X483798D03*
X472696Y1130103D03*
X483798D03*
X476396D03*
X472696Y1142859D03*
X476397D03*
X483798D03*
X480097Y1149237D03*
X483798Y1155615D03*
X480097Y1161993D03*
X476397D03*
X478247Y1152426D03*
X470846Y1165182D03*
X481948D03*
X483798Y1161993D03*
X472696Y1155615D03*
X481948Y1152426D03*
X478247Y1158804D03*
X474546D03*
X478247Y1165182D03*
X480097Y1155615D03*
X474546Y1165182D03*
X470845Y1152426D03*
X472696Y1161993D03*
X499271Y879624D03*
X488168Y873246D03*
Y879624D03*
X486318Y876435D03*
X490019D03*
X497420D03*
X495570Y879624D03*
Y886002D03*
X491869D03*
X488168D03*
X490019Y889191D03*
X493719Y895569D03*
X486318D03*
X499271Y886002D03*
X497420Y895569D03*
Y882813D03*
X493719Y908325D03*
X486318D03*
X497420D03*
X491869Y917891D03*
Y924269D03*
X495570Y917891D03*
Y924269D03*
X493719Y921080D03*
X486318D03*
X497420D03*
X491869Y930647D03*
X495570D03*
X493719Y940214D03*
X486318D03*
X497420D03*
X499271Y937025D03*
X488168D03*
X491869D03*
X495570D03*
Y956159D03*
Y943403D03*
Y949781D03*
X491869Y956159D03*
Y943403D03*
Y949781D03*
X486318Y952970D03*
X493719D03*
X497420D03*
X495570Y962537D03*
Y968915D03*
X491869Y962537D03*
Y968915D03*
X493719Y965726D03*
X486318D03*
X497420D03*
X495570Y975293D03*
X491869D03*
X493719Y978482D03*
X486318D03*
X488168Y981671D03*
X493719Y984860D03*
X486318D03*
X495570Y981671D03*
X497420Y978482D03*
X488168Y988049D03*
Y994427D03*
X486318Y997616D03*
X493719D03*
X486318Y991238D03*
X493719D03*
X488168Y1000805D03*
X495570Y994427D03*
Y988049D03*
Y1000805D03*
X488168Y1007183D03*
X486318Y1003994D03*
Y1010372D03*
X493719Y1003994D03*
Y1010372D03*
X495570Y1007183D03*
X491200Y1028056D03*
X498601D03*
X494901Y1040812D03*
X489349Y1044001D03*
X487499Y1040812D03*
X489349Y1037623D03*
X496751Y1044001D03*
Y1037623D03*
X485649Y1031245D03*
X493050D03*
X491200Y1034434D03*
X498601D03*
X496751Y1050379D03*
X494901Y1047190D03*
X487499D03*
X489349Y1050379D03*
X494901Y1059946D03*
Y1053568D03*
X487499Y1059946D03*
X489349Y1056757D03*
X487499Y1053568D03*
X496751Y1056757D03*
X498601Y1059946D03*
X494901Y1072702D03*
X487499D03*
X498601D03*
X494901Y1085458D03*
X487499D03*
X498601D03*
X494901Y1098214D03*
X487499D03*
X498601D03*
X493050Y1101403D03*
X485649D03*
X489349D03*
X494901Y1117348D03*
X487499D03*
X498601D03*
X487499Y1130103D03*
X494901D03*
X498601D03*
X494901Y1142859D03*
X487499D03*
X491200Y1149237D03*
X498601Y1142859D03*
Y1161993D03*
X487499D03*
X491200D03*
X489349Y1152426D03*
X493050Y1165182D03*
X485649Y1158804D03*
Y1165182D03*
X496751D03*
Y1158804D03*
X489349D03*
X491200Y1155615D03*
X493050Y1152426D03*
X494901Y1161993D03*
Y1155615D03*
X489349Y1165182D03*
X510373Y879624D03*
X514074D03*
X508523Y876435D03*
X506672Y879624D03*
X512223Y876435D03*
X501121D03*
Y889191D03*
X512223Y895569D03*
X501121Y882813D03*
X514074Y905135D03*
X501121Y901947D03*
X512223Y914702D03*
X514074Y924269D03*
X501121Y914702D03*
X512223Y933836D03*
X501121Y927458D03*
X514074Y943403D03*
X512223Y952970D03*
X501121Y946592D03*
X514074Y962537D03*
X501121Y959348D03*
X514074Y981671D03*
X512223Y972104D03*
X501121D03*
Y984860D03*
Y997616D03*
Y991238D03*
X512223D03*
X514074Y1000805D03*
X502971Y994427D03*
X508523Y991238D03*
X501121Y1010372D03*
X512223D03*
X501121Y1003994D03*
X504822Y1010372D03*
X506003Y1028056D03*
X509704D03*
X502302Y1040812D03*
X500452Y1031245D03*
X511554Y1044001D03*
Y1031245D03*
X502302Y1047190D03*
Y1053568D03*
X513405Y1047190D03*
X511554Y1056757D03*
X509704Y1047190D03*
X506003Y1053568D03*
X513405Y1066324D03*
X502302D03*
X513405Y1085458D03*
X502302Y1079080D03*
X513405Y1104592D03*
X502302Y1091836D03*
X500452Y1101403D03*
X502302Y1110970D03*
X513405Y1123726D03*
X502302D03*
X513405Y1142859D03*
X502302Y1136481D03*
Y1149237D03*
X513405Y1161993D03*
X511554Y1158804D03*
X509704Y1161993D03*
X502302D03*
X500452Y1152426D03*
X506003Y1161993D03*
X500452Y1158804D03*
Y1165182D03*
X507853D03*
X504153D03*
X521475Y879624D03*
X519625Y876435D03*
X517775Y879624D03*
X521475Y873246D03*
X517775D03*
X527027Y876435D03*
X528877Y879624D03*
Y892380D03*
X515924Y882813D03*
X527027D03*
X528877Y911513D03*
Y905135D03*
Y898758D03*
Y924269D03*
Y917891D03*
Y930647D03*
Y937025D03*
Y943403D03*
Y949781D03*
Y956159D03*
Y968915D03*
Y962537D03*
Y981671D03*
Y975293D03*
Y988049D03*
Y1000805D03*
X517775Y994427D03*
X523326Y991238D03*
X528877Y994427D03*
Y1007183D03*
X515924Y1010372D03*
X517105Y1028056D03*
X524507D03*
X515255Y1037623D03*
X522656Y1044001D03*
Y1031245D03*
X515255Y1056757D03*
X522656D03*
X524507Y1047190D03*
X517105Y1053568D03*
X515255Y1075891D03*
Y1095025D03*
Y1114159D03*
Y1133293D03*
X528208Y1161993D03*
X515255Y1152426D03*
X524507Y1161993D03*
X520806D03*
X518956Y1158804D03*
X529594Y1507355D03*
X527494D03*
X530727Y876435D03*
X532578Y873246D03*
X536279Y886002D03*
X530727Y889191D03*
X534428D03*
Y895569D03*
X530727D03*
X536279Y892380D03*
X541830Y889191D03*
X543680Y892380D03*
X541830Y895569D03*
X538129D03*
X539979Y886002D03*
X530727Y882813D03*
X541830D03*
X534428Y908325D03*
X536279Y898758D03*
X530727Y901947D03*
X534428D03*
X536279Y905135D03*
X530727Y908325D03*
X536279Y911513D03*
X543680D03*
X541830Y901947D03*
X543680Y905135D03*
X541830Y908325D03*
X543680Y898758D03*
X539979Y905135D03*
X536279Y917891D03*
X530727Y921080D03*
X534428D03*
X536279Y924269D03*
X534428Y914702D03*
X530727D03*
X541830Y921080D03*
X543680Y924269D03*
X541830Y914702D03*
X543680Y917891D03*
X539979Y924269D03*
X538129Y914702D03*
X530727Y927458D03*
X534428D03*
X536279Y937025D03*
X530727Y940214D03*
X534428D03*
Y933836D03*
X530727D03*
X536279Y930647D03*
X541830Y927458D03*
X543680Y930647D03*
X541830Y940214D03*
Y933836D03*
X543680Y937025D03*
X538129Y933836D03*
X536279Y943403D03*
X530727Y946592D03*
X534428D03*
X536279Y956159D03*
X534428Y952970D03*
X530727D03*
X536279Y949781D03*
X543680Y943403D03*
X541830Y946592D03*
X543680Y949781D03*
X541830Y952970D03*
X543680Y956159D03*
X538129Y952970D03*
X539979Y943403D03*
X536279Y962537D03*
X530727Y965726D03*
X534428D03*
X530727Y959348D03*
X534428D03*
X536279Y968915D03*
X541830Y965726D03*
X543680Y968915D03*
X541830Y959348D03*
X543680Y962537D03*
X539979D03*
X530727Y984860D03*
X536279Y975293D03*
X530727Y978482D03*
X534428D03*
Y972104D03*
X530727D03*
X541830Y984860D03*
Y978482D03*
X543680Y981671D03*
X541830Y972104D03*
X543680Y975293D03*
X538129Y972104D03*
X539979Y981671D03*
X536279Y994427D03*
X534428Y997616D03*
X530727D03*
X536279Y1000805D03*
Y988049D03*
X530727Y991238D03*
X543680Y988049D03*
X541830Y997616D03*
X543680Y1000805D03*
X541830Y991238D03*
X539979Y1000805D03*
X538129Y991238D03*
X543680Y994427D03*
X534428Y991238D03*
Y1010372D03*
X536279Y1007183D03*
X534428Y1003994D03*
X530727D03*
X541830D03*
X543680Y1007183D03*
X538129Y1010372D03*
X530727D03*
X541830D03*
X531908Y1028056D03*
X543011D03*
X535609D03*
X530058Y1031245D03*
X531908Y1034434D03*
X535609D03*
X537460Y1037623D03*
X530058D03*
X531908Y1040812D03*
X535609D03*
X530058Y1044001D03*
X543011Y1034434D03*
Y1040812D03*
X541160Y1037623D03*
X537460Y1044001D03*
Y1031245D03*
X530058Y1050379D03*
X535609Y1059946D03*
X531908Y1047190D03*
X537460Y1050379D03*
X535609Y1053568D03*
X543011Y1047190D03*
X541160Y1056757D03*
X539310Y1047190D03*
X543011Y1053568D03*
X537460Y1056757D03*
X535609Y1047190D03*
X531908Y1053568D03*
X535609Y1072702D03*
X530058Y1063135D03*
X537460D03*
X531908Y1066324D03*
X530058Y1069513D03*
X537460D03*
X531908Y1072702D03*
X535609Y1066324D03*
X543011D03*
Y1072702D03*
X539310Y1066324D03*
X530058Y1075891D03*
X537460D03*
X531908Y1079080D03*
X535609D03*
X530058Y1082269D03*
X537460D03*
X531908Y1085458D03*
X537460Y1088647D03*
X530058D03*
X535609Y1085458D03*
X543011Y1079080D03*
Y1085458D03*
X539310D03*
X541160Y1075891D03*
X537460Y1101403D03*
X531908Y1104592D03*
X535609Y1091836D03*
X530058Y1095025D03*
X537460D03*
X531908Y1098214D03*
X535609D03*
X530058Y1101403D03*
X535609Y1104592D03*
X531908Y1091836D03*
X543011Y1104592D03*
Y1098214D03*
Y1091836D03*
X541160Y1095025D03*
X539310Y1104592D03*
X535609Y1110970D03*
X530058Y1114159D03*
X537460D03*
X531908Y1117348D03*
X535609D03*
X537460Y1107781D03*
X530058D03*
X531908Y1110970D03*
X543011Y1117348D03*
Y1110970D03*
X541160Y1114159D03*
X530058Y1120537D03*
X537460D03*
X531908Y1123726D03*
X535609Y1130103D03*
X530058Y1133293D03*
X537460D03*
Y1126915D03*
X530058D03*
X535609Y1123726D03*
X531908Y1130103D03*
X543011Y1123726D03*
Y1130103D03*
X539310Y1123726D03*
X541160Y1133293D03*
X531908Y1136481D03*
X535609D03*
X530058Y1139670D03*
X537460D03*
X531908Y1142859D03*
X535609Y1149237D03*
X537460Y1146048D03*
X530058D03*
X535609Y1142859D03*
X531908Y1149237D03*
X543011Y1136481D03*
Y1142859D03*
Y1149237D03*
X539310Y1142859D03*
X530058Y1152426D03*
X537460D03*
X531908Y1155615D03*
X541160Y1152426D03*
X531908Y1161993D03*
X535609D03*
X539310D03*
X537460Y1158804D03*
X541160D03*
X531001Y1514073D03*
X530945Y1516336D03*
X532310Y1536640D03*
X531926Y1534540D03*
X531537Y1531618D03*
X531208Y1528698D03*
X530711Y1538658D03*
X554783Y879624D03*
X547381Y886002D03*
X549231Y889191D03*
Y895569D03*
X547381Y892380D03*
X556633Y882813D03*
X552932D03*
X549231Y908325D03*
X547381Y898758D03*
X549231Y901947D03*
X547381Y905135D03*
Y911513D03*
Y917891D03*
X549231Y921080D03*
X547381Y924269D03*
X549231Y914702D03*
Y927458D03*
X547381Y937025D03*
X549231Y940214D03*
Y933836D03*
X547381Y930647D03*
Y943403D03*
X549231Y946592D03*
X547381Y956159D03*
X549231Y952970D03*
X547381Y949781D03*
Y962537D03*
X549231Y965726D03*
Y959348D03*
X547381Y968915D03*
Y975293D03*
X549231Y978482D03*
Y972104D03*
X547381Y994427D03*
X549231Y997616D03*
X547381Y1000805D03*
Y988049D03*
X554782Y994427D03*
X549231Y991238D03*
Y1010372D03*
X547381Y1007183D03*
X549231Y1003994D03*
X556633Y1010372D03*
X557814Y1028056D03*
X550412D03*
X544861Y1031245D03*
X550412Y1034434D03*
X548562Y1037623D03*
X544861D03*
X550412Y1040812D03*
X544861Y1044001D03*
X548562D03*
Y1031245D03*
X544861Y1050379D03*
X550412Y1059946D03*
X548562Y1050379D03*
X550412Y1053568D03*
X557814D03*
X548562Y1056757D03*
X550412Y1047190D03*
Y1072702D03*
X544861Y1063135D03*
X548562D03*
X544861Y1069513D03*
X548562D03*
X550412Y1066324D03*
X544861Y1075891D03*
X548562D03*
X550412Y1079080D03*
X544861Y1082269D03*
X548562D03*
Y1088647D03*
X544861D03*
X550412Y1085458D03*
X548562Y1101403D03*
X550412Y1091836D03*
X544861Y1095025D03*
X548562D03*
X550412Y1098214D03*
X544861Y1101403D03*
X550412Y1104592D03*
Y1110970D03*
X544861Y1114159D03*
X548562D03*
X550412Y1117348D03*
X548562Y1107781D03*
X544861D03*
Y1120537D03*
X548562D03*
X550412Y1130103D03*
X544861Y1133293D03*
X548562D03*
Y1126915D03*
X544861D03*
X550412Y1123726D03*
Y1136481D03*
X544861Y1139670D03*
X548562D03*
X550412Y1149237D03*
X548562Y1146048D03*
X544861D03*
X550412Y1142859D03*
X546712Y1161993D03*
X544861Y1152426D03*
X548562D03*
X550412Y1155615D03*
X557814Y1161993D03*
X544861Y1158804D03*
X562184Y873246D03*
X565885Y879624D03*
X564034Y876435D03*
X573286Y879624D03*
X571436Y876435D03*
X569586Y879624D03*
X564034Y895569D03*
X565885Y886002D03*
X567735Y882813D03*
X565885Y905135D03*
Y924269D03*
X564034Y914702D03*
Y933836D03*
Y952970D03*
X565885Y943403D03*
Y962537D03*
Y981671D03*
X564034Y972104D03*
X565885Y1000805D03*
X564034Y991238D03*
X560334D03*
X564034Y1010372D03*
X567735D03*
X568916Y1028056D03*
X561515D03*
X567066Y1037623D03*
X563365Y1044001D03*
Y1031245D03*
X567066Y1056757D03*
X565215Y1047190D03*
X563365Y1056757D03*
X561515Y1047190D03*
X565215Y1066324D03*
Y1085458D03*
X567066Y1075891D03*
X565215Y1104592D03*
X567066Y1095025D03*
Y1114159D03*
Y1133293D03*
X565215Y1123726D03*
Y1142859D03*
X567066Y1158804D03*
X563365D03*
X567066Y1152426D03*
X572617Y1161993D03*
X570767Y1165182D03*
X567066D03*
X568916Y1161993D03*
X570815Y1507509D03*
X573066Y1507460D03*
X570980Y1513218D03*
X569722Y1521612D03*
X569321Y1518121D03*
X569768Y1535698D03*
Y1537898D03*
X571215Y1540317D03*
X575286Y1544625D03*
X657656Y1507355D03*
X655556D03*
X659063Y1514073D03*
X659007Y1516336D03*
X659358Y1536640D03*
Y1534540D03*
X659359Y1531618D03*
X659270Y1528698D03*
X662353Y1534413D03*
X660877Y1530158D03*
X658773Y1538658D03*
X1184959Y1551121D03*
X1185360Y1554612D03*
X1185406Y1568698D03*
Y1570898D03*
X1196028Y1549970D03*
X1197603Y1552698D03*
X1188653Y1540509D03*
X1186453D03*
X1186618Y1546218D03*
X1186853Y1573317D03*
X1190924Y1577625D03*
X1200752Y1549970D03*
X1205477D03*
X1210201D03*
X1214925D03*
X1202327Y1552698D03*
X1207051D03*
X1211776D03*
X1219650Y1549970D03*
X1224374D03*
X1229099D03*
X1216500Y1552698D03*
X1221225D03*
X1225949D03*
X1243272Y1549970D03*
X1233823D03*
X1238547D03*
X1244847Y1552698D03*
X1230673D03*
X1235398D03*
X1240122D03*
X1247996Y1549970D03*
X1252721D03*
X1257445D03*
X1249571Y1552698D03*
X1254295D03*
X1259020D03*
X1262170Y1549970D03*
X1266894D03*
X1263744Y1552698D03*
X1268469D03*
X1273294Y1540355D03*
X1271194D03*
X1274701Y1547073D03*
X1274645Y1549336D03*
X1274996Y1567540D03*
X1274997Y1564618D03*
X1274908Y1561698D03*
X1274411Y1571658D03*
X1274996Y1569640D03*
X1288549Y876434D03*
X1288548Y1010371D03*
X1289729Y1028055D03*
X1297800Y879623D03*
X1299650Y876434D03*
X1290399Y879623D03*
X1303351Y882812D03*
X1292249Y895568D03*
X1299650Y882812D03*
X1290398Y905134D03*
X1292249Y914701D03*
X1290398Y924268D03*
X1292249Y933835D03*
Y952969D03*
X1290398Y943402D03*
Y962536D03*
X1292249Y972103D03*
X1290398Y981670D03*
X1292249Y991237D03*
X1290398Y1000804D03*
X1299650Y991237D03*
X1294099Y988048D03*
X1299650Y1010371D03*
X1293430Y1028055D03*
X1300831D03*
X1297130D03*
X1291579Y1037622D03*
X1302682Y1044000D03*
X1295280Y1031244D03*
X1291579Y1056756D03*
X1293430Y1047189D03*
X1295280Y1056756D03*
X1297130Y1047189D03*
X1300831Y1053567D03*
X1293430Y1066323D03*
Y1085457D03*
X1291579Y1075890D03*
X1293430Y1104591D03*
X1291579Y1095024D03*
Y1114158D03*
Y1133292D03*
X1293430Y1123725D03*
Y1142858D03*
X1291579Y1158803D03*
X1295280D03*
X1291579Y1152425D03*
X1300831Y1161992D03*
X1302682Y1165181D03*
X1318154Y876434D03*
X1305201Y879623D03*
X1312603D03*
X1316304D03*
X1307052Y876434D03*
X1308902Y886001D03*
X1314453Y889190D03*
X1307052D03*
X1312603Y892379D03*
X1307052Y895568D03*
X1314453D03*
X1308902Y892379D03*
X1318154Y895568D03*
X1307052Y908324D03*
X1312603Y911512D03*
X1308902Y898757D03*
X1314453Y901946D03*
X1307052D03*
X1312603Y905134D03*
X1308902D03*
X1314453Y908324D03*
X1308902Y911512D03*
X1312603Y898757D03*
X1316304Y905134D03*
X1308902Y917890D03*
X1314453Y921079D03*
X1307052D03*
X1312603Y924268D03*
X1308902D03*
X1307052Y914701D03*
X1314453D03*
X1312603Y917890D03*
X1316304Y924268D03*
X1318154Y914701D03*
X1314453Y927457D03*
X1307052D03*
X1312603Y930646D03*
X1308902Y937024D03*
X1314453Y940213D03*
X1307052D03*
Y933835D03*
X1314453D03*
X1308902Y930646D03*
X1312603Y937024D03*
X1318154Y933835D03*
X1312603Y943402D03*
X1308902D03*
X1314453Y946591D03*
X1307052D03*
X1312603Y949780D03*
X1308902Y956158D03*
X1307052Y952969D03*
X1314453D03*
X1308902Y949780D03*
X1312603Y956158D03*
X1318154Y952969D03*
X1316304Y943402D03*
X1308902Y962536D03*
X1314453Y965725D03*
X1307052D03*
X1312603Y968914D03*
X1314453Y959347D03*
X1307052D03*
X1312603Y962536D03*
X1308902Y968914D03*
X1316304Y962536D03*
X1314453Y984859D03*
X1308902Y975292D03*
X1314453Y978481D03*
X1307052D03*
X1312603Y981670D03*
X1307052Y972103D03*
X1314453D03*
X1312603Y975292D03*
X1316304Y981670D03*
X1318154Y972103D03*
X1312603Y988048D03*
X1308902Y994426D03*
X1307052Y997615D03*
X1314453D03*
X1312603Y1000804D03*
X1308902D03*
X1307052Y991237D03*
X1312603Y994426D03*
X1316304Y1000804D03*
X1318154Y991237D03*
X1314453D03*
X1308902Y988048D03*
X1307052Y1010371D03*
X1308902Y1007182D03*
X1307052Y1003993D03*
X1314453D03*
X1312603Y1007182D03*
X1314453Y1010371D03*
X1319335Y1028055D03*
X1315634D03*
X1308233D03*
X1313784Y1031244D03*
X1315634Y1034433D03*
X1308233D03*
X1310083Y1037622D03*
X1313784D03*
X1315634Y1040811D03*
X1308233D03*
X1310083Y1044000D03*
X1317485Y1037622D03*
X1313784Y1044000D03*
X1310083Y1031244D03*
X1313784Y1050378D03*
X1308233Y1059945D03*
X1315634Y1047189D03*
X1310083Y1050378D03*
X1308233Y1053567D03*
X1317485Y1056756D03*
X1319335Y1047189D03*
X1310083Y1056756D03*
X1308233Y1047189D03*
X1315634Y1053567D03*
X1308233Y1072701D03*
X1313784Y1063134D03*
X1310083D03*
X1315634Y1066323D03*
X1313784Y1069512D03*
X1310083D03*
X1315634Y1072701D03*
X1308233Y1066323D03*
X1319335D03*
X1313784Y1075890D03*
X1310083D03*
X1315634Y1079079D03*
X1308233D03*
X1313784Y1082268D03*
X1310083D03*
X1315634Y1085457D03*
X1310083Y1088646D03*
X1313784D03*
X1308233Y1085457D03*
X1319335D03*
X1317485Y1075890D03*
X1310083Y1101402D03*
X1315634Y1104591D03*
X1308233Y1091835D03*
X1313784Y1095024D03*
X1310083D03*
X1315634Y1098213D03*
X1308233D03*
X1313784Y1101402D03*
X1308233Y1104591D03*
X1315634Y1091835D03*
X1319335Y1104591D03*
X1317485Y1095024D03*
X1308233Y1110969D03*
X1313784Y1114158D03*
X1310083D03*
X1315634Y1117347D03*
X1308233D03*
X1310083Y1107780D03*
X1313784D03*
X1315634Y1110969D03*
X1317485Y1114158D03*
X1313784Y1120536D03*
X1310083D03*
X1315634Y1123725D03*
X1308233Y1130102D03*
X1313784Y1133292D03*
X1310083D03*
Y1126914D03*
X1313784D03*
X1308233Y1123725D03*
X1315634Y1130102D03*
X1317485Y1133292D03*
X1319335Y1123725D03*
X1315634Y1136480D03*
X1308233D03*
X1313784Y1139669D03*
X1310083D03*
X1315634Y1142858D03*
X1308233Y1149236D03*
X1310083Y1146047D03*
X1313784D03*
X1308233Y1142858D03*
X1315634Y1149236D03*
X1319335Y1142858D03*
X1313784Y1152425D03*
X1310083D03*
X1308233Y1155614D03*
X1317485Y1152425D03*
X1308233Y1161992D03*
X1310083Y1165181D03*
X1317485D03*
X1315634Y1161992D03*
X1316766Y1540460D03*
X1314515Y1540509D03*
X1314680Y1546218D03*
X1313021Y1551121D03*
X1313422Y1554612D03*
X1313468Y1568698D03*
Y1570898D03*
X1318986Y1577625D03*
X1314915Y1573317D03*
X1323705Y879623D03*
X1327406D03*
X1321855Y876434D03*
X1332957D03*
X1329256D03*
X1334807Y879623D03*
X1320004Y886001D03*
X1325556Y889190D03*
X1321855D03*
X1327406Y892379D03*
X1321855Y895568D03*
X1325556D03*
X1320004Y892379D03*
X1321855Y908324D03*
X1327406Y911512D03*
X1320004Y898757D03*
X1325556Y901946D03*
X1321855D03*
X1327406Y905134D03*
X1320004D03*
X1325556Y908324D03*
X1320004Y911512D03*
X1327406Y898757D03*
X1320004Y917890D03*
X1325556Y921079D03*
X1321855D03*
X1327406Y924268D03*
X1320004D03*
X1321855Y914701D03*
X1325556D03*
X1327406Y917890D03*
X1325556Y927457D03*
X1321855D03*
X1327406Y930646D03*
X1320004Y937024D03*
X1325556Y940213D03*
X1321855D03*
Y933835D03*
X1325556D03*
X1320004Y930646D03*
X1327406Y937024D03*
Y943402D03*
X1320004D03*
X1325556Y946591D03*
X1321855D03*
X1327406Y949780D03*
X1320004Y956158D03*
X1321855Y952969D03*
X1325556D03*
X1320004Y949780D03*
X1327406Y956158D03*
X1320004Y962536D03*
X1325556Y965725D03*
X1321855D03*
X1327406Y968914D03*
X1325556Y959347D03*
X1321855D03*
X1327406Y962536D03*
X1320004Y968914D03*
X1325556Y984859D03*
X1320004Y975292D03*
X1325556Y978481D03*
X1321855D03*
X1327406Y981670D03*
X1321855Y972103D03*
X1325556D03*
X1327406Y975292D03*
Y988048D03*
X1320004Y994426D03*
X1321855Y997615D03*
X1325556D03*
X1327406Y1000804D03*
X1320004D03*
X1321855Y991237D03*
X1327406Y994426D03*
X1334808Y988048D03*
X1325556Y991237D03*
X1320004Y988048D03*
X1321855Y1010371D03*
X1320004Y1007182D03*
X1321855Y1003993D03*
X1325556D03*
X1327406Y1007182D03*
X1325556Y1010371D03*
X1326737Y1028055D03*
X1334138D03*
X1323036D03*
X1328587Y1031244D03*
X1326737Y1034433D03*
X1323036D03*
X1321185Y1037622D03*
X1328587D03*
X1326737Y1040811D03*
X1323036D03*
X1321185Y1044000D03*
X1328587D03*
X1321185Y1031244D03*
X1328587Y1050378D03*
X1323036Y1059945D03*
X1326737Y1047189D03*
X1321185Y1050378D03*
X1323036Y1053567D03*
X1334138Y1047189D03*
X1321185Y1056756D03*
X1323036Y1047189D03*
X1326737Y1053567D03*
X1323036Y1072701D03*
X1328587Y1063134D03*
X1321185D03*
X1326737Y1066323D03*
X1328587Y1069512D03*
X1321185D03*
X1326737Y1072701D03*
X1323036Y1066323D03*
X1328587Y1075890D03*
X1321185D03*
X1326737Y1079079D03*
X1323036D03*
X1328587Y1082268D03*
X1321185D03*
X1326737Y1085457D03*
X1321185Y1088646D03*
X1328587D03*
X1323036Y1085457D03*
X1321185Y1101402D03*
X1326737Y1104591D03*
X1323036Y1091835D03*
X1328587Y1095024D03*
X1321185D03*
X1326737Y1098213D03*
X1323036D03*
X1328587Y1101402D03*
X1323036Y1104591D03*
X1326737Y1091835D03*
X1323036Y1110969D03*
X1328587Y1114158D03*
X1321185D03*
X1326737Y1117347D03*
X1323036D03*
X1321185Y1107780D03*
X1328587D03*
X1326737Y1110969D03*
X1328587Y1120536D03*
X1321185D03*
X1326737Y1123725D03*
X1323036Y1130102D03*
X1328587Y1133292D03*
X1321185D03*
Y1126914D03*
X1328587D03*
X1323036Y1123725D03*
X1326737Y1130102D03*
Y1136480D03*
X1323036D03*
X1328587Y1139669D03*
X1321185D03*
X1326737Y1142858D03*
X1323036Y1149236D03*
X1321185Y1146047D03*
X1328587D03*
X1323036Y1142858D03*
X1326737Y1149236D03*
X1328587Y1152425D03*
X1321185D03*
X1326737Y1155614D03*
X1321185Y1158803D03*
X1334138Y1161992D03*
X1324090Y1549970D03*
X1328814D03*
X1333539D03*
X1325665Y1552698D03*
X1330389D03*
X1344059Y876434D03*
X1347760D03*
X1340359D03*
X1347760Y882812D03*
X1344059Y895568D03*
X1342209Y905134D03*
X1344059Y914701D03*
X1342209Y924268D03*
X1344059Y933835D03*
X1342209Y943402D03*
X1344059Y952969D03*
X1342209Y962536D03*
Y981670D03*
X1344059Y972103D03*
Y991237D03*
X1342209Y1000804D03*
X1340359Y991237D03*
X1345910Y988048D03*
X1340359Y1010371D03*
X1345241Y1028055D03*
X1341540D03*
X1348941D03*
X1343390Y1037622D03*
X1339689Y1044000D03*
X1335989Y1031244D03*
X1347091D03*
X1345241Y1047189D03*
X1343390Y1056756D03*
X1335989D03*
X1341540Y1053567D03*
X1347091Y1056756D03*
X1348941Y1047189D03*
X1345241Y1066323D03*
X1343390Y1075890D03*
X1345241Y1085457D03*
X1343390Y1095024D03*
X1345241Y1104591D03*
X1343390Y1114158D03*
Y1133292D03*
X1345241Y1123725D03*
Y1142858D03*
X1347091Y1158803D03*
X1348941Y1161992D03*
X1345241D03*
X1343390Y1152425D03*
X1335989Y1165181D03*
X1343390Y1158803D03*
X1341540Y1161992D03*
X1338263Y1549970D03*
X1342987D03*
X1347712D03*
X1335113Y1552698D03*
X1339838D03*
X1344562D03*
X1349287D03*
X1358863Y876434D03*
X1355162D03*
X1351461Y882812D03*
X1357012Y886001D03*
X1362563Y895568D03*
X1358863D03*
X1355162Y889190D03*
X1362563Y908324D03*
X1358863D03*
X1355162Y901946D03*
X1364414Y917890D03*
Y924268D03*
X1360713Y917890D03*
Y924268D03*
X1358863Y921079D03*
X1362563D03*
X1355162Y914701D03*
X1364414Y930646D03*
X1360713D03*
X1362563Y940213D03*
X1358863D03*
X1357012Y937024D03*
X1355162Y927457D03*
X1364414Y937024D03*
X1360713D03*
Y956158D03*
Y943402D03*
Y949780D03*
X1364414Y956158D03*
Y943402D03*
Y949780D03*
X1362563Y952969D03*
X1358863D03*
X1355162Y946591D03*
X1360713Y962536D03*
Y968914D03*
X1364414Y962536D03*
Y968914D03*
X1362563Y965725D03*
X1358863D03*
X1355162Y959347D03*
X1360713Y975292D03*
X1364414D03*
X1357012Y981670D03*
X1364414D03*
X1358863Y984859D03*
X1362563Y978481D03*
X1358863D03*
X1355162Y972103D03*
X1357012Y988048D03*
X1358863Y997615D03*
X1357012Y994426D03*
X1358863Y991237D03*
X1364414Y988048D03*
Y994426D03*
X1357012Y1000804D03*
X1364414D03*
X1351461Y991237D03*
X1357012Y1007182D03*
X1358863Y1003993D03*
X1364414Y1007182D03*
X1355162Y1010371D03*
X1362563D03*
X1351461D03*
X1360044Y1028055D03*
X1352642D03*
X1358193Y1031244D03*
X1360044Y1040811D03*
Y1034433D03*
X1358193Y1037622D03*
Y1044000D03*
X1354493D03*
X1363745Y1059945D03*
X1360044D03*
Y1047189D03*
X1358193Y1050378D03*
X1360044Y1053567D03*
X1361894Y1056756D03*
X1358193D03*
X1352642Y1053567D03*
X1363745Y1072701D03*
X1360044D03*
X1356343Y1066323D03*
X1363745Y1085457D03*
X1360044D03*
X1356343Y1079079D03*
X1363745Y1098213D03*
X1360044D03*
X1356343Y1091835D03*
X1358193Y1101402D03*
X1361894D03*
X1363745Y1117347D03*
X1360044D03*
X1356343Y1110969D03*
X1363745Y1130102D03*
X1360044D03*
X1356343Y1123725D03*
X1360044Y1142858D03*
X1363745D03*
X1356343Y1149236D03*
Y1136480D03*
X1358193Y1152425D03*
X1356343Y1161992D03*
X1360044D03*
X1352436Y1549970D03*
X1357161D03*
X1361885D03*
X1354011Y1552698D03*
X1358735D03*
X1363460D03*
X1369965Y876434D03*
X1366264D03*
X1377367D03*
X1368115Y879623D03*
X1371815D03*
X1368115Y886001D03*
X1369965Y895568D03*
X1373666D03*
X1366264Y889190D03*
X1377366D03*
X1379216Y886001D03*
X1371815D03*
X1375516D03*
Y911512D03*
X1371815D03*
X1369965Y908324D03*
X1373666D03*
X1375516Y917890D03*
Y924268D03*
X1371815Y917890D03*
Y924268D03*
X1369965Y921079D03*
X1373666D03*
X1375516Y930646D03*
X1371815D03*
X1369965Y940213D03*
X1373666D03*
X1371815Y937024D03*
X1379217D03*
X1368115D03*
X1375516D03*
X1371815Y956158D03*
Y943402D03*
Y949780D03*
X1375516Y956158D03*
Y943402D03*
Y949780D03*
X1369965Y952969D03*
X1373666D03*
X1371815Y962536D03*
Y968914D03*
X1375516Y962536D03*
Y968914D03*
X1369965Y965725D03*
X1373666D03*
X1371815Y975292D03*
X1375516D03*
X1366264Y984859D03*
X1369965Y978481D03*
X1373666D03*
X1371815Y981670D03*
X1379217D03*
X1373666Y984859D03*
Y991237D03*
X1371815Y988048D03*
Y994426D03*
Y1000804D03*
X1366264Y997615D03*
Y991237D03*
X1379217Y988048D03*
Y994426D03*
X1373666Y997615D03*
X1379217Y1000804D03*
X1366264Y1003993D03*
X1379217Y1007182D03*
X1377367Y1010371D03*
X1373666Y1003993D03*
X1369965Y1010371D03*
X1378548Y1028055D03*
X1367445D03*
X1374847Y1040811D03*
X1378548Y1034433D03*
X1372997Y1037622D03*
Y1044000D03*
X1367445Y1040811D03*
Y1034433D03*
X1365595Y1031244D03*
Y1037622D03*
Y1044000D03*
X1372997Y1031244D03*
X1374847Y1047189D03*
Y1053567D03*
X1371146Y1059945D03*
X1372997Y1056756D03*
Y1050378D03*
X1374847Y1059945D03*
X1365595Y1056756D03*
X1367445Y1047189D03*
Y1053567D03*
X1365595Y1050378D03*
X1371146Y1072701D03*
X1374847D03*
Y1085457D03*
X1371146D03*
X1374847Y1098213D03*
X1371146D03*
X1372997Y1101402D03*
X1376697D03*
X1369296D03*
X1365595D03*
X1374847Y1117347D03*
X1371146D03*
Y1130102D03*
X1374847D03*
Y1142858D03*
X1371146D03*
X1378548Y1149236D03*
X1367445D03*
X1369296Y1152425D03*
X1371146Y1161992D03*
X1378548D03*
X1367445D03*
X1371334Y1549970D03*
X1376058D03*
X1366609D03*
X1372909Y1552698D03*
X1377633D03*
X1368184D03*
X1388469Y876434D03*
X1392170D03*
X1381067D03*
X1390320Y879623D03*
X1394021D03*
X1381067Y895568D03*
X1384768D03*
X1390319Y886001D03*
X1392170Y895568D03*
X1388469Y889190D03*
X1394021Y886001D03*
X1386619Y911512D03*
X1394020D03*
X1382918D03*
X1384768Y908324D03*
X1392170D03*
X1381067Y908323D03*
X1386619Y924268D03*
Y917890D03*
X1394020Y924268D03*
Y917890D03*
X1382918Y924268D03*
Y917890D03*
X1384768Y921079D03*
X1381067D03*
X1392170D03*
X1394020Y937024D03*
X1382918Y930646D03*
X1386619D03*
X1384768Y940213D03*
X1381067D03*
X1394020Y930646D03*
X1392170Y940213D03*
X1381067Y933835D03*
X1386619Y937024D03*
X1384768Y933835D03*
X1382918Y937024D03*
X1394020Y956158D03*
Y943402D03*
Y949780D03*
X1382918Y956158D03*
Y943402D03*
Y949780D03*
X1386619Y956158D03*
Y943402D03*
Y949780D03*
X1384768Y952969D03*
X1381067D03*
X1392170D03*
X1394020Y962536D03*
Y968914D03*
X1382918Y962536D03*
Y968914D03*
X1386619Y962536D03*
Y968914D03*
X1384768Y965725D03*
X1381067D03*
X1392170D03*
X1394020Y975292D03*
X1382918D03*
X1386619D03*
X1381067Y978481D03*
X1384768D03*
X1386619Y981670D03*
X1381067Y984859D03*
X1392170Y978481D03*
X1394020Y981670D03*
X1388469Y984859D03*
X1386619Y988048D03*
X1394020D03*
X1381067Y991237D03*
X1388457Y997607D03*
X1388469Y991237D03*
X1382905Y1007174D03*
X1382236Y1028063D03*
X1380398Y1044000D03*
X1382246Y1040819D03*
X1389638D03*
X1382236Y1034441D03*
X1380398Y1037622D03*
Y1031244D03*
X1382249Y1047189D03*
X1389650D03*
X1380398Y1050378D03*
X1382249Y1059945D03*
Y1053567D03*
X1385949Y1059945D03*
X1380398Y1056756D03*
X1387800D03*
X1393351Y1059945D03*
X1387800Y1050378D03*
X1389650Y1053567D03*
X1382249Y1072701D03*
X1385949D03*
X1393351D03*
X1382249Y1085457D03*
X1385949D03*
X1393351D03*
X1382249Y1098213D03*
X1385949D03*
X1393351D03*
X1385949Y1104591D03*
X1384099Y1101402D03*
X1380398D03*
X1382249Y1104591D03*
X1387800Y1101402D03*
X1384099Y1107780D03*
X1382249Y1117347D03*
X1385949D03*
X1387800Y1107780D03*
X1393351Y1117347D03*
X1385949Y1130102D03*
X1382249D03*
X1393351D03*
X1382249Y1142858D03*
X1385949D03*
X1393351D03*
X1389650Y1149236D03*
X1380398Y1152425D03*
X1382249Y1161992D03*
X1391500Y1152425D03*
X1393351Y1161992D03*
X1389650D03*
X1380783Y1549970D03*
X1385507D03*
X1390232D03*
X1382357Y1552698D03*
X1387082D03*
X1391806D03*
X1399571Y876434D03*
X1403272D03*
X1405123Y879623D03*
X1401423D03*
X1401422Y886001D03*
X1395871Y895568D03*
X1399571Y889190D03*
X1408823Y892379D03*
X1405123D03*
X1397722Y886001D03*
X1408824D03*
X1405123D03*
X1397721Y911512D03*
X1395871Y908324D03*
X1408823Y911512D03*
X1405123D03*
X1408823Y898757D03*
X1405123D03*
X1406973Y921079D03*
Y914701D03*
X1397721Y924268D03*
Y917890D03*
X1403272Y921079D03*
Y914701D03*
X1395871Y921079D03*
X1408823Y924268D03*
X1405123D03*
X1403272Y940213D03*
X1406973D03*
X1397721Y937024D03*
X1406973Y927457D03*
X1403272D03*
X1397721Y930646D03*
X1395871Y940213D03*
X1406973Y933835D03*
X1403272D03*
Y952969D03*
Y946591D03*
X1406973Y952969D03*
Y946591D03*
X1397721Y956158D03*
Y943402D03*
Y949780D03*
X1395871Y952969D03*
X1405123Y943402D03*
X1408823D03*
X1405123Y956158D03*
X1408823D03*
X1403272Y959347D03*
Y965725D03*
X1406973Y959347D03*
Y965725D03*
X1397721Y962536D03*
Y968914D03*
X1405123D03*
X1395871Y965725D03*
X1408823Y968914D03*
X1403272Y978481D03*
Y972103D03*
X1406973Y978481D03*
Y972103D03*
X1397721Y975292D03*
X1395871Y978481D03*
X1401422Y981670D03*
X1395871Y984859D03*
X1408823Y981670D03*
X1403272Y984859D03*
X1401422Y988048D03*
X1395858Y997607D03*
X1395871Y991237D03*
X1403260Y997607D03*
X1408823Y988048D03*
X1403272Y991237D03*
X1397039Y1040819D03*
X1404441D03*
X1397052Y1047189D03*
X1404453D03*
X1395201Y1050378D03*
X1402603Y1056756D03*
Y1050378D03*
X1395201Y1056756D03*
X1397052Y1059945D03*
Y1053567D03*
X1404453D03*
X1406304Y1069512D03*
X1397052Y1072701D03*
Y1085457D03*
X1406304Y1082268D03*
X1397052Y1098213D03*
X1406304Y1095024D03*
X1408154Y1104591D03*
X1404453D03*
X1398902Y1107780D03*
X1395201D03*
X1397052Y1117347D03*
X1406304Y1114158D03*
X1397052Y1130102D03*
X1406304Y1126914D03*
X1397052Y1142858D03*
X1400752Y1149236D03*
X1406304Y1139669D03*
Y1146047D03*
X1402603Y1152425D03*
X1400752Y1161992D03*
X1406304Y1152425D03*
X1404453Y1161992D03*
X1408154Y1155614D03*
X1394956Y1549970D03*
X1396531Y1552698D03*
X1399256Y1540355D03*
X1401356D03*
X1402763Y1547073D03*
X1402707Y1549336D03*
X1403058Y1567540D03*
X1403059Y1564618D03*
X1402970Y1561698D03*
X1402473Y1571658D03*
X1423602Y892379D03*
Y911512D03*
Y898757D03*
Y924268D03*
Y943402D03*
Y956158D03*
Y968914D03*
X1410674Y984859D03*
X1410661Y997607D03*
X1410674Y991237D03*
X1411855Y1047189D03*
X1410004Y1050378D03*
X1411855Y1053567D03*
X1410004Y1056756D03*
Y1069512D03*
Y1082268D03*
Y1095024D03*
Y1114158D03*
Y1126914D03*
Y1139669D03*
Y1146047D03*
Y1152425D03*
Y1158803D03*
X1438405Y879623D03*
X1431003Y873245D03*
X1434704Y879623D03*
Y873245D03*
X1438405D03*
X1429153Y876434D03*
X1432854D03*
X1436554Y882812D03*
X1431003Y886001D03*
X1427302D03*
Y892379D03*
X1432854Y889190D03*
X1436554Y895568D03*
X1438405Y886001D03*
X1427302Y911512D03*
X1436554Y908324D03*
X1427302Y898757D03*
Y924268D03*
X1436554Y921079D03*
X1429153Y933835D03*
X1425452D03*
X1434704Y930646D03*
X1438405D03*
X1436554Y940213D03*
X1427302Y943402D03*
Y956158D03*
X1436554Y952969D03*
X1438405Y962536D03*
X1429153Y965725D03*
Y959347D03*
X1438405Y968914D03*
X1434704Y962536D03*
X1425452Y965725D03*
Y959347D03*
X1434704Y968914D03*
X1427302D03*
X1436554Y965725D03*
X1438405Y975292D03*
X1429153Y972103D03*
Y978481D03*
X1434704Y975292D03*
X1425452Y972103D03*
Y978481D03*
X1427302Y981670D03*
X1434704D03*
X1425452Y984859D03*
X1432854D03*
X1436554Y978481D03*
X1434704Y988048D03*
X1425465Y997607D03*
X1432866D03*
X1427302Y988048D03*
X1425452Y991237D03*
X1432854D03*
X1434047Y1040819D03*
X1434035Y1047189D03*
X1426633D03*
X1435885Y1050378D03*
X1428483D03*
X1437735Y1059945D03*
X1435885Y1056756D03*
X1428483D03*
X1426633Y1053567D03*
X1434035D03*
X1428483Y1069512D03*
X1424783D03*
X1437735Y1072701D03*
X1428483Y1082268D03*
X1424783D03*
X1437735Y1085457D03*
X1428483Y1095024D03*
X1424783D03*
X1430334Y1104591D03*
X1426633D03*
X1437735Y1098213D03*
X1428483Y1114158D03*
X1424783D03*
X1435885Y1107780D03*
X1437735Y1117347D03*
X1424783Y1126914D03*
X1428483D03*
X1437735Y1130102D03*
X1428483Y1139669D03*
X1424783D03*
X1434035Y1149236D03*
X1428483Y1146047D03*
X1424783D03*
X1437735Y1142858D03*
X1426633Y1161992D03*
X1424783Y1152425D03*
X1426633Y1155614D03*
X1428483Y1152425D03*
X1432184D03*
X1434035Y1161992D03*
X1430334D03*
X1424783Y1158803D03*
X1432184D03*
X1434035Y1155614D03*
X1428484Y1158803D03*
X1437735Y1155614D03*
X1443956Y876434D03*
X1440255D03*
X1451358D03*
X1449507Y873245D03*
X1453208D03*
X1440255Y882812D03*
X1442106Y886001D03*
X1443956Y889190D03*
X1447657Y895568D03*
X1440255D03*
X1453208Y886001D03*
X1451358Y895568D03*
X1447657Y908324D03*
X1440255D03*
X1451357D03*
X1447657Y921079D03*
X1440255D03*
X1451357D03*
X1445806Y930646D03*
X1449507D03*
X1447657Y940213D03*
X1440255D03*
X1451357D03*
X1442106Y930646D03*
X1453208Y937024D03*
X1445806D03*
X1451357Y933835D03*
X1447657D03*
X1449507Y937024D03*
X1447657Y952969D03*
X1440255D03*
X1451357D03*
X1449507Y968914D03*
Y962536D03*
X1445806Y968914D03*
Y962536D03*
X1440255Y965725D03*
X1447657D03*
X1451357D03*
X1449507Y975292D03*
X1445806D03*
X1440255Y978481D03*
X1447657D03*
X1442106Y981670D03*
X1449507D03*
X1447657Y984859D03*
X1440255D03*
X1451357Y978481D03*
X1449507Y988048D03*
X1440268Y997607D03*
X1447669D03*
X1442106Y988048D03*
X1440255Y991237D03*
X1447657D03*
X1441449Y1040819D03*
X1448850D03*
X1441436Y1047189D03*
X1448838D03*
X1450688Y1050378D03*
Y1056756D03*
X1441436Y1059945D03*
Y1053567D03*
X1443287Y1056756D03*
X1448838Y1053567D03*
X1443287Y1050378D03*
X1448838Y1059945D03*
X1452539D03*
X1441436Y1072701D03*
X1448838D03*
X1452539D03*
X1448838Y1085457D03*
X1441436D03*
X1452539D03*
X1448838Y1098213D03*
X1441436D03*
X1452539D03*
X1448838Y1104591D03*
X1452539D03*
X1446987Y1101402D03*
X1450688D03*
Y1107780D03*
X1446987D03*
X1439586D03*
X1448838Y1117347D03*
X1441436D03*
X1452539D03*
X1448838Y1130102D03*
X1441436D03*
X1452539Y1130103D03*
X1448838Y1142858D03*
X1441436D03*
X1445137Y1149236D03*
X1452539Y1142858D03*
X1446987Y1152425D03*
X1443287Y1165181D03*
X1439586Y1158803D03*
X1443287Y1152425D03*
X1452539Y1161992D03*
X1441436D03*
X1445137D03*
X1448838Y1155614D03*
X1439586Y1152425D03*
X1445137Y1155614D03*
X1443287Y1158803D03*
X1450627Y1540509D03*
X1452827D03*
X1450792Y1546218D03*
X1449133Y1551121D03*
X1449534Y1554612D03*
X1449580Y1568698D03*
Y1570898D03*
X1451027Y1573317D03*
X1462460Y876434D03*
X1455058D03*
X1466161D03*
X1464310Y873245D03*
X1460609D03*
Y879623D03*
X1464310D03*
Y886001D03*
X1458759Y895568D03*
X1462460D03*
X1466161Y889190D03*
X1455058D03*
X1460609Y886001D03*
X1456909D03*
X1468011D03*
X1458759Y908324D03*
X1462460D03*
X1458759Y921079D03*
X1462460D03*
Y940213D03*
X1458759D03*
X1456909Y937024D03*
X1464310D03*
X1460609D03*
X1468011D03*
X1458759Y952969D03*
X1462460D03*
X1460609Y968914D03*
Y962536D03*
X1468011Y968914D03*
Y962536D03*
X1456909Y968914D03*
Y962536D03*
X1462460Y965725D03*
X1458759D03*
X1460609Y975292D03*
X1468011D03*
X1456909D03*
X1462460Y978481D03*
X1458759D03*
X1464310Y981670D03*
X1456909D03*
X1462460Y984859D03*
X1455058D03*
X1464310Y988048D03*
Y994426D03*
X1456909Y988048D03*
Y994426D03*
X1462460Y997615D03*
Y991237D03*
X1455058Y997615D03*
Y991237D03*
X1456909Y1000804D03*
X1464310D03*
Y1007182D03*
X1456909D03*
X1462460Y1010371D03*
Y1003993D03*
X1455058Y1010371D03*
Y1003993D03*
X1459940Y1028055D03*
X1467342D03*
X1458090Y1037622D03*
Y1044000D03*
X1465491Y1037622D03*
Y1044000D03*
X1463641Y1040811D03*
X1456239D03*
X1459940Y1034433D03*
X1461791Y1031244D03*
X1454389D03*
X1467342Y1034433D03*
X1463641Y1047189D03*
X1456239D03*
X1465491Y1050378D03*
X1456239Y1053567D03*
X1463641D03*
X1458090Y1056756D03*
X1463641Y1059945D03*
X1465491Y1056756D03*
X1458090Y1050378D03*
X1459940Y1059945D03*
X1463641Y1072701D03*
X1459940D03*
X1463641Y1085457D03*
X1459940D03*
X1463641Y1098213D03*
X1459940D03*
X1454389Y1101402D03*
X1461791D03*
X1458090D03*
X1465491D03*
X1459940Y1117347D03*
X1463641D03*
X1459940Y1130102D03*
X1463641D03*
Y1142858D03*
X1459940D03*
X1456239Y1149236D03*
X1467342D03*
X1454389Y1158803D03*
X1467342Y1155614D03*
X1465491Y1158803D03*
X1459940Y1155614D03*
X1465491Y1152425D03*
X1454389D03*
X1467342Y1161992D03*
X1463641D03*
X1456239D03*
X1461791Y1165181D03*
X1458090Y1152425D03*
X1461791Y1158803D03*
X1456239Y1155614D03*
X1455098Y1577625D03*
X1475413Y879623D03*
X1482814D03*
X1473562Y876434D03*
X1477263D03*
X1471712Y873245D03*
X1475413D03*
X1480964Y876434D03*
X1475413Y886001D03*
X1477263Y889190D03*
X1473562Y895568D03*
X1469861D03*
X1471712Y886001D03*
X1469861Y908324D03*
X1473562D03*
X1477263Y901946D03*
X1473562Y921079D03*
X1469861D03*
X1477263Y914701D03*
X1469861Y940213D03*
X1473562D03*
X1477263Y927457D03*
X1475413Y937024D03*
X1471712D03*
X1473562Y952969D03*
X1469861D03*
X1477263Y946591D03*
X1471712Y968914D03*
Y962536D03*
X1473562Y965725D03*
X1469861D03*
X1477263Y959347D03*
X1471712Y975292D03*
Y981670D03*
X1473562Y978481D03*
X1469861D03*
Y984859D03*
X1477263Y972103D03*
Y984859D03*
Y991237D03*
X1469861Y997615D03*
Y991237D03*
X1471712Y988048D03*
Y994426D03*
X1477263Y997615D03*
X1471712Y1000804D03*
X1479113Y994426D03*
X1471712Y1007182D03*
X1477263Y1010371D03*
Y1003993D03*
X1469861Y1010371D03*
Y1003993D03*
X1480964Y1010371D03*
X1474743Y1028055D03*
X1482145D03*
X1478444Y1040811D03*
X1471043D03*
X1472893Y1037622D03*
Y1044000D03*
X1474743Y1034433D03*
X1476594Y1031244D03*
X1469192D03*
X1472893Y1050378D03*
X1478444Y1047189D03*
X1471043D03*
X1478444Y1053567D03*
X1472893Y1056756D03*
X1471043Y1053567D03*
X1474743Y1059945D03*
X1471043D03*
X1482145Y1053567D03*
X1478444Y1066323D03*
X1471043Y1072701D03*
X1474743D03*
X1478444Y1079079D03*
X1474743Y1085457D03*
X1471043D03*
X1478444Y1091835D03*
X1476594Y1101402D03*
X1474743Y1098213D03*
X1471043D03*
X1469192Y1101402D03*
X1478444Y1110969D03*
X1474743Y1117347D03*
X1471043D03*
X1478444Y1123725D03*
X1474743Y1130102D03*
X1471043D03*
X1478444Y1136480D03*
X1474743Y1142858D03*
X1471043D03*
X1478444Y1149236D03*
X1472893Y1158803D03*
X1471043Y1155614D03*
Y1161992D03*
X1469192Y1152425D03*
X1476594D03*
X1478444Y1161992D03*
X1474743D03*
X1476594Y1158803D03*
X1476778Y1165778D03*
X1486515Y879623D03*
X1490216D03*
X1484665Y876434D03*
X1488365D03*
Y895568D03*
X1492066Y882812D03*
X1490216Y905134D03*
X1488365Y914701D03*
X1490216Y924268D03*
X1488365Y933835D03*
X1490216Y943402D03*
X1488365Y952969D03*
X1490216Y962536D03*
Y981670D03*
X1488365Y972103D03*
Y991237D03*
X1490216Y1000804D03*
X1493917Y994426D03*
X1484665Y991237D03*
X1488365Y1010371D03*
X1492066D03*
X1493247Y1028055D03*
X1485846D03*
X1491397Y1037622D03*
X1498798Y1044000D03*
Y1031244D03*
X1487696Y1044000D03*
Y1031244D03*
X1489547Y1047189D03*
X1491397Y1056756D03*
X1498798D03*
X1493247Y1053567D03*
X1487696Y1056756D03*
X1485846Y1047189D03*
X1489547Y1066323D03*
X1491397Y1075890D03*
X1489547Y1085457D03*
X1491397Y1095024D03*
X1489547Y1104591D03*
X1491397Y1114158D03*
Y1133292D03*
X1489547Y1123725D03*
Y1142858D03*
X1491397Y1152425D03*
X1489547Y1161992D03*
X1485846D03*
X1487696Y1158803D03*
X1506869Y876434D03*
X1512421Y879623D03*
X1505019D03*
X1512421Y886001D03*
X1506869Y889190D03*
X1510570D03*
X1505019Y892379D03*
X1510570Y895568D03*
X1506869D03*
X1512421Y892379D03*
X1506869Y882812D03*
X1510570Y908324D03*
X1505019Y911512D03*
X1512421Y898757D03*
X1506869Y901946D03*
X1510570D03*
X1505019Y905134D03*
X1512421D03*
X1506869Y908324D03*
X1512421Y911512D03*
X1505019Y898757D03*
X1512421Y917890D03*
X1506869Y921079D03*
X1510570D03*
X1505019Y924268D03*
X1512421D03*
X1510570Y914701D03*
X1506869D03*
X1505019Y917890D03*
X1506869Y927457D03*
X1510570D03*
X1505019Y930646D03*
X1512421Y937024D03*
X1506869Y940213D03*
X1510570D03*
Y933835D03*
X1506869D03*
X1512421Y930646D03*
X1505019Y937024D03*
Y943402D03*
X1512421D03*
X1506869Y946591D03*
X1510570D03*
X1505019Y949780D03*
X1512421Y956158D03*
X1510570Y952969D03*
X1506869D03*
X1512421Y949780D03*
X1505019Y956158D03*
X1512421Y962536D03*
X1506869Y965725D03*
X1510570D03*
X1505019Y968914D03*
X1506869Y959347D03*
X1510570D03*
X1505019Y962536D03*
X1512421Y968914D03*
X1506869Y984859D03*
X1512421Y975292D03*
X1506869Y978481D03*
X1510570D03*
X1505019Y981670D03*
X1510570Y972103D03*
X1506869D03*
X1505019Y975292D03*
Y988048D03*
X1512421Y994426D03*
X1510570Y997615D03*
X1506869D03*
X1505019Y1000804D03*
X1512421D03*
Y988048D03*
X1506869Y991237D03*
X1499468D03*
X1505019Y994426D03*
X1510570Y991237D03*
Y1010371D03*
X1512421Y1007182D03*
X1510570Y1003993D03*
X1506869D03*
X1505019Y1007182D03*
X1506869Y1010371D03*
X1508050Y1028055D03*
X1500649D03*
X1511751D03*
X1506200Y1031244D03*
X1508050Y1034433D03*
X1511751D03*
X1513602Y1037622D03*
X1506200D03*
X1508050Y1040811D03*
X1511751D03*
X1506200Y1044000D03*
X1513602D03*
Y1031244D03*
X1506200Y1050378D03*
X1511751Y1059945D03*
X1508050Y1047189D03*
X1513602Y1050378D03*
X1511751Y1053567D03*
X1500649Y1047189D03*
X1513602Y1056756D03*
X1511751Y1047189D03*
X1508050Y1053567D03*
X1511751Y1072701D03*
X1506200Y1063134D03*
X1513602D03*
X1508050Y1066323D03*
X1506200Y1069512D03*
X1513602D03*
X1508050Y1072701D03*
X1511751Y1066323D03*
X1506200Y1075890D03*
X1513602D03*
X1508050Y1079079D03*
X1511751D03*
X1506200Y1082268D03*
X1513602D03*
X1508050Y1085457D03*
X1513602Y1088646D03*
X1506200D03*
X1511751Y1085457D03*
X1513602Y1101402D03*
X1508050Y1104591D03*
X1511751Y1091835D03*
X1506200Y1095024D03*
X1513602D03*
X1508050Y1098213D03*
X1511751D03*
X1506200Y1101402D03*
X1511751Y1104591D03*
X1508050Y1091835D03*
X1511751Y1110969D03*
X1506200Y1114158D03*
X1513602D03*
X1508050Y1117347D03*
X1511751D03*
X1513602Y1107780D03*
X1506200D03*
X1508050Y1110969D03*
X1506200Y1120536D03*
X1513602D03*
X1508050Y1123725D03*
X1511751Y1130102D03*
X1506200Y1133292D03*
X1513602D03*
Y1126914D03*
X1506200D03*
X1511751Y1123725D03*
X1508050Y1130102D03*
Y1136480D03*
X1511751D03*
X1506200Y1139669D03*
X1513602D03*
X1508050Y1142858D03*
X1511751Y1149236D03*
X1513602Y1146047D03*
X1506200D03*
X1511751Y1142858D03*
X1508050Y1149236D03*
X1506200Y1152425D03*
X1513602D03*
X1508050Y1155614D03*
X1513602Y1158803D03*
X1500649Y1161992D03*
X1504350D03*
X1527224Y873245D03*
X1516121D03*
X1519822D03*
X1514271Y876434D03*
X1523523Y879623D03*
X1525373Y876434D03*
X1523523Y886001D03*
X1517972Y889190D03*
X1525373D03*
X1519822Y892379D03*
X1525373Y895568D03*
X1517972D03*
X1523523Y892379D03*
X1516121Y886001D03*
X1514271Y895568D03*
X1525373Y908324D03*
X1519822Y911512D03*
X1523523Y898757D03*
X1517972Y901946D03*
X1525373D03*
X1519822Y905134D03*
X1523523D03*
X1517972Y908324D03*
X1523523Y911512D03*
X1519822Y898757D03*
X1516121Y905134D03*
X1523523Y917890D03*
X1517972Y921079D03*
X1525373D03*
X1519822Y924268D03*
X1523523D03*
X1525373Y914701D03*
X1517972D03*
X1519822Y917890D03*
X1516121Y924268D03*
X1514271Y914701D03*
X1517972Y927457D03*
X1525373D03*
X1519822Y930646D03*
X1523523Y937024D03*
X1517972Y940213D03*
X1525373D03*
Y933835D03*
X1517972D03*
X1523523Y930646D03*
X1519822Y937024D03*
X1514271Y933835D03*
X1519822Y943402D03*
X1523523D03*
X1517972Y946591D03*
X1525373D03*
X1519822Y949780D03*
X1523523Y956158D03*
X1525373Y952969D03*
X1517972D03*
X1523523Y949780D03*
X1519822Y956158D03*
X1516121Y943402D03*
X1514271Y952969D03*
X1523523Y962536D03*
X1517972Y965725D03*
X1525373D03*
X1519822Y968914D03*
X1517972Y959347D03*
X1525373D03*
X1519822Y962536D03*
X1523523Y968914D03*
X1516121Y962536D03*
X1517972Y984859D03*
X1523523Y975292D03*
X1517972Y978481D03*
X1525373D03*
X1519822Y981670D03*
X1525373Y972103D03*
X1517972D03*
X1519822Y975292D03*
X1516121Y981670D03*
X1514271Y972103D03*
X1519822Y988048D03*
X1523523Y994426D03*
X1525373Y997615D03*
X1517972D03*
X1519822Y1000804D03*
X1523523D03*
Y988048D03*
X1517972Y991237D03*
X1516121Y1000804D03*
X1514271Y991237D03*
X1519822Y994426D03*
X1525373Y991237D03*
Y1010371D03*
X1523523Y1007182D03*
X1525373Y1003993D03*
X1517972D03*
X1519822Y1007182D03*
X1514271Y1010371D03*
X1517972D03*
X1519153Y1028055D03*
X1526554D03*
X1521003Y1031244D03*
X1519153Y1034433D03*
X1526554D03*
X1524704Y1037622D03*
X1521003D03*
X1519153Y1040811D03*
X1526554D03*
X1521003Y1044000D03*
X1517302Y1037622D03*
X1524704Y1044000D03*
Y1031244D03*
X1521003Y1050378D03*
X1526554Y1059945D03*
X1519153Y1047189D03*
X1524704Y1050378D03*
X1526554Y1053567D03*
X1517302Y1056756D03*
X1515452Y1047189D03*
X1524704Y1056756D03*
X1526554Y1047189D03*
X1519153Y1053567D03*
X1526554Y1072701D03*
X1521003Y1063134D03*
X1524704D03*
X1519153Y1066323D03*
X1521003Y1069512D03*
X1524704D03*
X1519153Y1072701D03*
X1526554Y1066323D03*
X1515452D03*
X1521003Y1075890D03*
X1524704D03*
X1519153Y1079079D03*
X1526554D03*
X1521003Y1082268D03*
X1524704D03*
X1519153Y1085457D03*
X1524704Y1088646D03*
X1521003D03*
X1526554Y1085457D03*
X1515452D03*
X1517302Y1075890D03*
X1524704Y1101402D03*
X1519153Y1104591D03*
X1526554Y1091835D03*
X1521003Y1095024D03*
X1524704D03*
X1519153Y1098213D03*
X1526554D03*
X1521003Y1101402D03*
X1526554Y1104591D03*
X1519153Y1091835D03*
X1515452Y1104591D03*
X1517302Y1095024D03*
X1526554Y1110969D03*
X1521003Y1114158D03*
X1524704D03*
X1519153Y1117347D03*
X1526554D03*
X1524704Y1107780D03*
X1521003D03*
X1519153Y1110969D03*
X1517302Y1114158D03*
X1521003Y1120536D03*
X1524704D03*
X1519153Y1123725D03*
X1526554Y1130102D03*
X1521003Y1133292D03*
X1524704D03*
Y1126914D03*
X1521003D03*
X1526554Y1123725D03*
X1519153Y1130102D03*
X1517302Y1133292D03*
X1515452Y1123725D03*
X1519153Y1136480D03*
X1526554D03*
X1521003Y1139669D03*
X1524704D03*
X1519153Y1142858D03*
X1526554Y1149236D03*
X1524704Y1146047D03*
X1521003D03*
X1526554Y1142858D03*
X1519153Y1149236D03*
X1515452Y1142858D03*
X1521003Y1152425D03*
X1524704D03*
X1526554Y1155614D03*
X1517302Y1152425D03*
X1521003Y1158803D03*
X1515452Y1161992D03*
X1542027Y879623D03*
X1540176Y876434D03*
X1530924Y873245D03*
X1534625Y879623D03*
X1536476Y876434D03*
X1540176Y895568D03*
X1542027Y886001D03*
X1532775Y882812D03*
X1542027Y905134D03*
Y924268D03*
X1540176Y914701D03*
Y933835D03*
Y952969D03*
X1542027Y943402D03*
Y962536D03*
Y981670D03*
X1540176Y972103D03*
X1542027Y1000804D03*
X1540176Y991237D03*
X1530924Y994426D03*
X1536476Y991237D03*
X1540176Y1010371D03*
X1532775D03*
X1533956Y1028055D03*
X1537657D03*
X1543208Y1037622D03*
X1539507Y1044000D03*
Y1031244D03*
X1543208Y1056756D03*
X1541357Y1047189D03*
X1539507Y1056756D03*
X1537657Y1047189D03*
X1533956Y1053567D03*
X1541357Y1066323D03*
Y1085457D03*
X1543208Y1075890D03*
X1541357Y1104591D03*
X1543208Y1095024D03*
Y1114158D03*
Y1133292D03*
X1541357Y1123725D03*
Y1142858D03*
X1533956Y1161992D03*
X1543208Y1158803D03*
X1539507D03*
X1543208Y1152425D03*
X1537657Y1161992D03*
X1530255D03*
X1535368Y1540355D03*
X1537468D03*
X1538875Y1547073D03*
X1538819Y1549336D03*
X1539170Y1567540D03*
X1539171Y1564618D03*
X1539082Y1561698D03*
X1538585Y1571658D03*
X1539170Y1569640D03*
X1549428Y879623D03*
X1545728D03*
X1543877Y1010371D03*
X1545058Y1028055D03*
X1548759Y1161992D03*
X1546909Y1165181D03*
X1580940Y1540460D03*
X1578689Y1540509D03*
X1578854Y1546218D03*
X1577195Y1551121D03*
X1577596Y1554612D03*
X1577642Y1568698D03*
Y1570898D03*
X1583160Y1577625D03*
X1579089Y1573317D03*
X1663430Y1540355D03*
X1665530D03*
X1666937Y1547073D03*
X1666881Y1549336D03*
X1667231Y1567540D03*
X1667232Y1564618D03*
X1667143Y1561698D03*
X1670227Y1567413D03*
X1668750Y1563158D03*
X1666647Y1571658D03*
X1667231Y1569640D03*
G54D40*
X326731Y653394D03*
X363731D03*
X433624Y594259D03*
X754645Y1426892D03*
X766889Y1486756D03*
Y1530256D03*
X1166535Y1412479D03*
X1291146Y1375715D03*
X1320516D03*
X1415690Y601230D03*
X1487677Y640145D03*
X1524437Y640365D03*
X1701285Y198612D03*
X1700840Y1424519D03*
X1731660Y198612D03*
X1770442Y284934D03*
X1800002D03*
G54D25*
X79729Y289822D03*
Y310256D03*
X89729Y289822D03*
X99729D03*
X89729Y310256D03*
X99729D03*
X757184Y1712772D03*
Y1722772D03*
X1072863Y1419176D03*
Y1429176D03*
X1080970Y1650958D03*
Y1660958D03*
X1299439Y92812D03*
Y102812D03*
X1530377Y581353D03*
X1540377D03*
G54D67*
X1233404Y60384D03*
X1241278D03*
X1249152D03*
X1439049Y87432D03*
X1431175D03*
X1446923D03*
G54D23*
X64823Y756832D03*
Y760178D03*
X73933Y768706D03*
X73960Y766090D03*
X69323Y780257D03*
Y786950D03*
Y803682D03*
Y793643D03*
Y796989D03*
Y817068D03*
Y810375D03*
Y823761D03*
Y830454D03*
Y833800D03*
Y840493D03*
Y847186D03*
Y853879D03*
Y860572D03*
Y877304D03*
Y867265D03*
Y870611D03*
Y883997D03*
Y890690D03*
Y897383D03*
Y904076D03*
Y907423D03*
Y914115D03*
Y920808D03*
Y927501D03*
Y934194D03*
Y940887D03*
Y950926D03*
Y944234D03*
Y964312D03*
Y957619D03*
Y971005D03*
Y977698D03*
Y984391D03*
Y1001123D03*
Y997777D03*
Y991084D03*
Y1031241D03*
Y1037934D03*
Y1044627D03*
Y1058013D03*
Y1051320D03*
Y1074745D03*
Y1068052D03*
Y1064706D03*
Y1081438D03*
Y1088131D03*
Y1098171D03*
Y1104863D03*
Y1091478D03*
Y1111556D03*
Y1118249D03*
Y1134982D03*
Y1124942D03*
Y1128289D03*
Y1148367D03*
Y1141675D03*
Y1155060D03*
Y1161753D03*
Y1165100D03*
Y1171793D03*
Y1178486D03*
Y1185178D03*
Y1191871D03*
Y1208604D03*
Y1198564D03*
Y1201911D03*
Y1215297D03*
Y1221989D03*
Y1228682D03*
Y1235375D03*
Y1238722D03*
Y1245415D03*
Y1252108D03*
X94524Y760178D03*
Y756832D03*
X89965D03*
X90015Y766871D03*
X85465Y776911D03*
X89965Y763525D03*
X94474D03*
X90015Y770218D03*
X85465Y783604D03*
Y790297D03*
Y800336D03*
Y807029D03*
Y793643D03*
Y813722D03*
Y820415D03*
Y837147D03*
Y830454D03*
Y827108D03*
Y843840D03*
Y850533D03*
Y857226D03*
Y863919D03*
Y873958D03*
Y880651D03*
Y867265D03*
Y887344D03*
Y894037D03*
Y910769D03*
Y904076D03*
Y900730D03*
Y924155D03*
Y917462D03*
Y930848D03*
Y940887D03*
Y937541D03*
Y947580D03*
Y954273D03*
Y960966D03*
Y967659D03*
Y974352D03*
Y981045D03*
Y987737D03*
Y994430D03*
Y1001123D03*
Y1027895D03*
Y1034588D03*
Y1041281D03*
Y1047974D03*
Y1054667D03*
Y1061360D03*
Y1071399D03*
Y1064706D03*
Y1078092D03*
Y1088131D03*
Y1084785D03*
Y1094824D03*
Y1101517D03*
Y1108210D03*
Y1114903D03*
Y1131635D03*
Y1124942D03*
Y1121596D03*
Y1138328D03*
Y1145021D03*
Y1151714D03*
Y1161753D03*
Y1158407D03*
Y1168446D03*
Y1175139D03*
Y1181832D03*
Y1188525D03*
Y1205257D03*
Y1198564D03*
Y1195218D03*
Y1211950D03*
Y1218643D03*
Y1225336D03*
Y1235375D03*
Y1232029D03*
Y1242068D03*
Y1248761D03*
X103574Y763766D03*
X99024Y1068052D03*
Y1064706D03*
X124224Y760178D03*
Y756832D03*
X119666D03*
X119616Y767166D03*
X119666Y763525D03*
X124174D03*
X119716Y770218D03*
X115166Y960966D03*
X120666D03*
X133124Y763766D03*
X128724Y1068052D03*
Y1064706D03*
X153925Y760178D03*
Y756832D03*
X149366D03*
X149416Y766871D03*
X149366Y763525D03*
X153875D03*
X149416Y770218D03*
X144866Y960966D03*
X150366D03*
X162975Y763766D03*
X158425Y1068052D03*
Y1064706D03*
X183626Y760178D03*
Y756832D03*
X179067D03*
X179117Y766871D03*
X179067Y763525D03*
X183576D03*
X179117Y770218D03*
X174567Y960966D03*
X180067D03*
X186530Y1523953D03*
X192676Y763766D03*
X188126Y780257D03*
Y786950D03*
Y803682D03*
Y793643D03*
Y796989D03*
Y817068D03*
Y810375D03*
Y823761D03*
Y830454D03*
Y833800D03*
Y840493D03*
Y847186D03*
Y853879D03*
Y860572D03*
Y877304D03*
Y867265D03*
Y870611D03*
Y883997D03*
Y890690D03*
Y897383D03*
Y904076D03*
Y907423D03*
Y914115D03*
Y920808D03*
Y927501D03*
Y934194D03*
Y940887D03*
Y950926D03*
Y944234D03*
Y964312D03*
Y957619D03*
Y971005D03*
Y977698D03*
Y984391D03*
Y1001123D03*
Y997777D03*
Y991084D03*
Y1031241D03*
Y1037934D03*
Y1044627D03*
Y1058013D03*
Y1051320D03*
Y1074745D03*
Y1068052D03*
Y1064706D03*
Y1081438D03*
Y1088131D03*
Y1098171D03*
Y1104863D03*
Y1091478D03*
Y1111556D03*
Y1118249D03*
Y1134982D03*
Y1124942D03*
Y1128289D03*
Y1148367D03*
Y1141675D03*
Y1155060D03*
Y1161753D03*
Y1165100D03*
Y1171793D03*
Y1178486D03*
Y1185178D03*
Y1191871D03*
Y1208604D03*
Y1198564D03*
Y1201911D03*
Y1215297D03*
Y1221989D03*
Y1228682D03*
Y1235375D03*
Y1238722D03*
Y1245415D03*
Y1252108D03*
X195979Y1523953D03*
X196530Y1526353D03*
X191805D03*
X187081D03*
X200703Y1523953D03*
X201254Y1526353D03*
X191254Y1523953D03*
X188254Y1544997D03*
X192978D03*
X197703D03*
X188254Y1548397D03*
X192978D03*
X197703D03*
X188166Y1624292D03*
X200226D03*
X191566D03*
X194196Y1614292D03*
X197596D03*
X213327Y760178D03*
Y756832D03*
X208768D03*
X204268Y776911D03*
X208768Y763525D03*
X212772Y766871D03*
X213277Y763525D03*
X208818Y770218D03*
X204268Y783604D03*
Y790297D03*
Y800336D03*
Y807029D03*
Y793643D03*
Y813722D03*
Y820415D03*
Y837147D03*
Y830454D03*
Y827108D03*
Y843840D03*
Y850533D03*
Y857226D03*
Y863919D03*
Y873958D03*
Y880651D03*
Y867265D03*
Y887344D03*
Y894037D03*
Y910769D03*
Y904076D03*
Y900730D03*
Y924155D03*
Y917462D03*
Y930848D03*
Y940887D03*
Y937541D03*
Y947580D03*
Y954273D03*
Y960966D03*
Y967659D03*
Y974352D03*
Y981045D03*
Y987737D03*
Y994430D03*
Y1001123D03*
Y1027895D03*
Y1034588D03*
Y1041281D03*
Y1047974D03*
Y1054667D03*
Y1061360D03*
Y1071399D03*
Y1064706D03*
Y1078092D03*
Y1088131D03*
Y1084785D03*
Y1094824D03*
Y1101517D03*
Y1108210D03*
Y1114903D03*
Y1131635D03*
Y1124942D03*
Y1121596D03*
Y1138328D03*
Y1145021D03*
Y1151714D03*
Y1161753D03*
Y1158407D03*
Y1168446D03*
Y1175139D03*
Y1181832D03*
Y1188525D03*
Y1205257D03*
Y1198564D03*
Y1195218D03*
Y1211950D03*
Y1218643D03*
Y1225336D03*
Y1235375D03*
Y1232029D03*
Y1242068D03*
Y1248761D03*
X205427Y1523953D03*
X205978Y1526353D03*
X210703D03*
X210152Y1523953D03*
X214876D03*
X215427Y1526353D03*
X202427Y1544997D03*
X207152D03*
X211876D03*
X216601D03*
X202427Y1548397D03*
X207152D03*
X211876D03*
X216601D03*
X212286Y1624292D03*
X203626D03*
X215686D03*
X206256Y1614292D03*
X209656D03*
X222377Y763766D03*
X227540Y960966D03*
X220152Y1526353D03*
X224876D03*
X224325Y1523953D03*
X219601D03*
X229049D03*
X229600Y1526353D03*
X221325Y1544997D03*
X226050D03*
X230774D03*
X221325Y1548397D03*
X226050D03*
X230774D03*
X224346Y1624292D03*
X227746D03*
X218316Y1614292D03*
X230376D03*
X221716D03*
X238469Y756832D03*
Y763525D03*
X238519Y770218D03*
X233969Y960966D03*
X243223Y1523953D03*
X243774Y1526353D03*
X238498Y1523953D03*
X239049Y1526353D03*
X233774Y1523953D03*
X234325Y1526353D03*
X235499Y1544997D03*
X240223D03*
X244947D03*
X235499Y1548397D03*
X240223D03*
X244947D03*
X236406Y1624292D03*
X239806D03*
X242436Y1614292D03*
X233776D03*
X245836D03*
X257396Y1523953D03*
X253223Y1526353D03*
X252672Y1523953D03*
X257947Y1526353D03*
X248498D03*
X247947Y1523953D03*
X249671Y1544997D03*
X254396D03*
X259120D03*
X249671Y1548397D03*
X254396D03*
X259120D03*
X248466Y1624292D03*
X260526D03*
X251866D03*
X254496Y1614292D03*
X257896D03*
X272525Y108556D03*
X268981D03*
Y111056D03*
X265438Y108556D03*
X261895D03*
Y111056D03*
X265438D03*
X272525D03*
X272586Y1624292D03*
X263926D03*
X275986D03*
X266556Y1614292D03*
X269956D03*
X284646Y1624292D03*
X288046D03*
X278616Y1614292D03*
X290676D03*
X282016D03*
X296706Y1624292D03*
X300106D03*
X302736Y1614292D03*
X294076D03*
X306136D03*
X306694Y1507279D03*
X319867Y1526353D03*
X315143D03*
X319316Y1523953D03*
X314592D03*
X316316Y1544997D03*
X321040D03*
X316316Y1548397D03*
X321040D03*
X308766Y1624292D03*
X320826D03*
X312166D03*
X314796Y1614292D03*
X318196D03*
X324041Y1523953D03*
X324592Y1526353D03*
X328765Y1523953D03*
X329316Y1526353D03*
X334040D03*
X333489Y1523953D03*
X325765Y1544997D03*
X330489D03*
X335214D03*
X325765Y1548397D03*
X330489D03*
X335214D03*
X332886Y1624292D03*
X324226D03*
X326856Y1614292D03*
X330256D03*
X338765Y1526353D03*
X338214Y1523953D03*
X347663D03*
X348214Y1526353D03*
X343489D03*
X342938Y1523953D03*
X339938Y1544997D03*
X344663D03*
X349387D03*
X339938Y1548397D03*
X344663D03*
X349387D03*
X344946Y1624292D03*
X336286D03*
X348346D03*
X338916Y1614292D03*
X350976D03*
X342316D03*
X362387Y1526353D03*
X361836Y1523953D03*
X352387D03*
X352938Y1526353D03*
X357662D03*
X357111Y1523953D03*
X363561Y1544997D03*
X354112D03*
X358836D03*
X363561Y1548397D03*
X354112D03*
X358836D03*
X357006Y1624292D03*
X360406D03*
X363036Y1614292D03*
X354376D03*
X380734Y1523953D03*
X376560Y1526353D03*
X376009Y1523953D03*
X371285D03*
X371836Y1526353D03*
X367111D03*
X366560Y1523953D03*
X368285Y1544997D03*
X373009D03*
X377733D03*
X368285Y1548397D03*
X373009D03*
X377733D03*
X369066Y1624292D03*
X372466D03*
X375096Y1614292D03*
X366436D03*
X378496D03*
X385458Y1523953D03*
X381285Y1526353D03*
X386009D03*
X382458Y1544997D03*
X387182D03*
X382458Y1548397D03*
X387182D03*
X450703Y1523953D03*
X451254Y1526353D03*
X452427Y1544997D03*
Y1548397D03*
X452339Y1624292D03*
X464876Y1523953D03*
X460703Y1526353D03*
X455978D03*
X465427D03*
X455427Y1523953D03*
X460152D03*
X469600D03*
X470151Y1526353D03*
X457151Y1544997D03*
X461876D03*
X466600D03*
X457151Y1548397D03*
X461876D03*
X466600D03*
X458369Y1602380D03*
X461769D03*
X464399Y1624292D03*
X455739D03*
X467799D03*
X458369Y1614292D03*
X461769D03*
X474325Y1523953D03*
X474876Y1526353D03*
X483774Y1523953D03*
X484325Y1526353D03*
X479049Y1523953D03*
X479600Y1526353D03*
X471325Y1544997D03*
X476049D03*
X480774D03*
X471325Y1548397D03*
X476049D03*
X480774D03*
X470429Y1602380D03*
X482489D03*
X473829D03*
X476459Y1624292D03*
X479859D03*
X470429Y1614292D03*
X482489D03*
X473829D03*
X497947Y1523953D03*
X498498Y1526353D03*
X488498Y1523953D03*
X489049Y1526353D03*
X493222Y1523953D03*
X493773Y1526353D03*
X499672Y1544997D03*
X485498D03*
X490223D03*
X494947D03*
X499672Y1548397D03*
X485498D03*
X490223D03*
X494947D03*
X494549Y1602380D03*
X485889D03*
X497949D03*
X488519Y1624292D03*
X491919D03*
X494549Y1614292D03*
X485889D03*
X497949D03*
X507947Y1526353D03*
X507396Y1523953D03*
X512120D03*
X512671Y1526353D03*
X503222D03*
X502671Y1523953D03*
X504396Y1544997D03*
X509120D03*
X513844D03*
X504396Y1548397D03*
X509120D03*
X513844D03*
X506609Y1602380D03*
X510009D03*
X500579Y1624292D03*
X512639D03*
X503979D03*
X506609Y1614292D03*
X510009D03*
X521569Y1523953D03*
X522120Y1526353D03*
X517396D03*
X516845Y1523953D03*
X518569Y1544997D03*
X523293D03*
X518569Y1548397D03*
X523293D03*
X518669Y1602380D03*
X522069D03*
X524699Y1624292D03*
X516039D03*
X528099D03*
X518669Y1614292D03*
X522069D03*
X530729Y1602380D03*
X542789D03*
X534129D03*
X536759Y1624292D03*
X540159D03*
X530729Y1614292D03*
X542789D03*
X534129D03*
X554849Y1602380D03*
X546189D03*
X558249D03*
X548819Y1624292D03*
X552219D03*
X554849Y1614292D03*
X546189D03*
X558249D03*
X566909Y1602380D03*
X570309D03*
X572939Y1624292D03*
X560879D03*
X564279D03*
X566909Y1614292D03*
X570309D03*
X588765Y1526353D03*
X588214Y1523953D03*
X578765D03*
X583489D03*
X579316Y1526353D03*
X584040D03*
X580489Y1544997D03*
X585213D03*
X580489Y1548397D03*
X585213D03*
X578969Y1602380D03*
X582369D03*
X584999Y1624292D03*
X576339D03*
X588399D03*
X578969Y1614292D03*
X582369D03*
X602387Y1523953D03*
X602938Y1526353D03*
X592938Y1523953D03*
X593489Y1526353D03*
X598213D03*
X597662Y1523953D03*
X589938Y1544997D03*
X594662D03*
X599387D03*
X604111D03*
X589938Y1548397D03*
X594662D03*
X599387D03*
X604111D03*
X591029Y1602380D03*
X603089D03*
X594429D03*
X597059Y1624292D03*
X600459D03*
X591029Y1614292D03*
X603089D03*
X594429D03*
X616560Y1523953D03*
X617111Y1526353D03*
X607111Y1523953D03*
X607662Y1526353D03*
X612387D03*
X611836Y1523953D03*
X608836Y1544997D03*
X613560D03*
X618285D03*
X608836Y1548397D03*
X613560D03*
X618285D03*
X615149Y1602380D03*
X606489D03*
X618549D03*
X609119Y1624292D03*
X612519D03*
X615149Y1614292D03*
X606489D03*
X618549D03*
X626009Y1523953D03*
X626560Y1526353D03*
X631284D03*
X630733Y1523953D03*
X621835Y1526353D03*
X621284Y1523953D03*
X627734Y1544997D03*
X632458D03*
X623009D03*
X627734Y1548397D03*
X632458D03*
X623009D03*
X627209Y1602380D03*
X630609D03*
X621179Y1624292D03*
X633239D03*
X624579D03*
X627209Y1614292D03*
X630609D03*
X642854Y760178D03*
Y756832D03*
X642804Y763525D03*
X644907Y1523953D03*
X640733Y1526353D03*
X640182Y1523953D03*
X635458D03*
X636009Y1526353D03*
X645458D03*
X637182Y1544997D03*
X641906D03*
X646631D03*
X637182Y1548397D03*
X641906D03*
X646631D03*
X639269Y1602380D03*
X642669D03*
X636639Y1624292D03*
X639269Y1614292D03*
X642669D03*
X651905Y763766D03*
X663496Y960966D03*
X657996D03*
X650182Y1526353D03*
X649631Y1523953D03*
X651355Y1544997D03*
Y1548397D03*
X664634Y449952D03*
X667996Y756832D03*
X672555D03*
Y760178D03*
X668046Y766871D03*
X667996Y763525D03*
X672505D03*
X668046Y770218D03*
X677055Y780257D03*
Y786950D03*
Y803682D03*
Y793643D03*
Y796989D03*
Y817068D03*
Y810375D03*
Y823761D03*
Y830454D03*
Y833800D03*
Y840493D03*
Y847186D03*
Y853879D03*
Y860572D03*
Y877304D03*
Y867265D03*
Y870611D03*
Y883997D03*
Y890690D03*
Y897383D03*
Y904076D03*
Y907423D03*
Y914115D03*
Y920808D03*
Y927501D03*
Y934194D03*
Y940887D03*
Y950926D03*
Y944234D03*
Y964312D03*
Y957619D03*
Y971005D03*
Y977698D03*
Y984391D03*
Y1001123D03*
Y997777D03*
Y991084D03*
Y1031241D03*
Y1037934D03*
Y1044627D03*
Y1058013D03*
Y1051320D03*
Y1074745D03*
Y1068052D03*
Y1064706D03*
Y1081438D03*
Y1088131D03*
Y1098171D03*
Y1104863D03*
Y1091478D03*
Y1111556D03*
Y1118249D03*
Y1134982D03*
Y1124942D03*
Y1128289D03*
Y1148367D03*
Y1141675D03*
Y1155060D03*
Y1161753D03*
Y1165100D03*
Y1171793D03*
Y1178486D03*
Y1185178D03*
Y1191871D03*
Y1208604D03*
Y1198564D03*
Y1201911D03*
Y1215297D03*
Y1221989D03*
Y1228682D03*
Y1235375D03*
Y1238722D03*
Y1245415D03*
Y1252108D03*
X695796Y430957D03*
Y437256D03*
Y468672D03*
X693197Y776911D03*
X681606Y763766D03*
X693197Y783604D03*
Y790297D03*
Y800336D03*
Y807029D03*
Y793643D03*
Y813722D03*
Y820415D03*
Y837147D03*
Y830454D03*
Y827108D03*
Y843840D03*
Y850533D03*
Y857226D03*
Y863919D03*
Y873958D03*
Y880651D03*
Y867265D03*
Y887344D03*
Y894037D03*
Y910769D03*
Y904076D03*
Y900730D03*
Y924155D03*
Y917462D03*
Y930848D03*
Y940887D03*
Y937541D03*
Y947580D03*
Y954273D03*
Y960966D03*
Y967659D03*
Y974352D03*
Y981045D03*
Y987737D03*
Y994430D03*
Y1001123D03*
Y1027895D03*
Y1034588D03*
Y1041281D03*
Y1047974D03*
Y1054667D03*
Y1061360D03*
Y1071399D03*
Y1064706D03*
Y1078092D03*
Y1088131D03*
Y1084785D03*
Y1094824D03*
Y1101517D03*
Y1108210D03*
Y1114903D03*
Y1131635D03*
Y1124942D03*
Y1121596D03*
Y1138328D03*
Y1145021D03*
Y1151714D03*
Y1161753D03*
Y1158407D03*
Y1168446D03*
Y1175139D03*
Y1181832D03*
Y1188525D03*
Y1205257D03*
Y1198564D03*
Y1195218D03*
Y1211950D03*
Y1218643D03*
Y1225336D03*
Y1235375D03*
Y1232029D03*
Y1242068D03*
Y1248761D03*
X698599Y115178D03*
X705686D03*
X702142D03*
X698599Y112678D03*
X705686D03*
X702142D03*
X695056D03*
Y115178D03*
X708395Y427807D03*
Y424657D03*
X705245D03*
Y427807D03*
X702095D03*
X708395Y434106D03*
X705245Y430957D03*
X702095Y434106D03*
X698946Y427807D03*
X705245Y437256D03*
X698946Y430957D03*
X705245Y434106D03*
X702095Y430957D03*
X705245Y446705D03*
X708395Y440405D03*
Y443555D03*
X702095Y446705D03*
X705245Y443555D03*
X702095Y437256D03*
Y440405D03*
Y443555D03*
X705245Y440405D03*
X708395Y437256D03*
X698946Y446705D03*
X708395D03*
X698946Y449854D03*
X708395Y462373D03*
Y449854D03*
X705245Y459223D03*
X702095Y456074D03*
Y459223D03*
X708395Y456074D03*
X705245Y462373D03*
X702095D03*
X705245Y456074D03*
X695796Y449854D03*
X708395Y459223D03*
Y465523D03*
X705245Y468672D03*
X702095D03*
X698946Y471822D03*
X702095Y465523D03*
X695796Y471822D03*
X708395Y478121D03*
X705245Y471822D03*
X695796Y465523D03*
X702095Y478121D03*
X705245Y474971D03*
X708395Y471822D03*
Y468672D03*
X705245Y465523D03*
X702095Y471822D03*
X698946Y465523D03*
X705245Y478121D03*
X702095Y474971D03*
X698946Y487570D03*
Y481271D03*
Y484420D03*
X705245Y481271D03*
X702095D03*
X695796Y484420D03*
X708395D03*
Y481271D03*
X697697Y756832D03*
X702256D03*
Y760178D03*
X697747Y766871D03*
X697697Y763525D03*
X702206D03*
X697747Y770218D03*
X706756Y1068052D03*
Y1064706D03*
X720993Y418358D03*
X717843D03*
Y421508D03*
X720993Y430957D03*
X711544D03*
X714694D03*
X717843Y434106D03*
X720993D03*
X717843Y430957D03*
X720993Y421508D03*
X711544Y434106D03*
X714694D03*
X720993Y424657D03*
X717843D03*
Y427807D03*
X714694Y424657D03*
Y427807D03*
X711544Y424657D03*
Y427807D03*
X720993D03*
X717843Y437256D03*
X720993D03*
X714694D03*
X711544D03*
Y443555D03*
X717843D03*
X714694Y446705D03*
Y440405D03*
X720993D03*
X711544D03*
X714694Y443555D03*
X711544Y446705D03*
Y459223D03*
X714694D03*
X717843Y462373D03*
Y456074D03*
Y449854D03*
X714694Y462373D03*
X711544D03*
X714694Y449854D03*
X711544D03*
X714694Y456074D03*
X711544D03*
X720993Y471822D03*
Y468672D03*
X711544Y478121D03*
X717843Y474971D03*
X724143Y471822D03*
X720993Y478121D03*
X717843D03*
X720993Y474971D03*
X714694Y465523D03*
X717843Y471822D03*
Y468672D03*
X714694Y471822D03*
X711544D03*
X714694Y468672D03*
X711544D03*
X720993Y465523D03*
X711544Y474971D03*
X714694Y478121D03*
Y474971D03*
X724143Y481271D03*
X711544Y465523D03*
X717843Y481271D03*
X714694D03*
X720993D03*
X711544D03*
X720993Y484420D03*
X711307Y763766D03*
X722898Y960966D03*
X717398D03*
X731208Y398737D03*
X733512Y418358D03*
X727292D03*
X724143D03*
X736661Y424657D03*
Y430957D03*
Y434106D03*
X733512D03*
Y421508D03*
Y424657D03*
Y430957D03*
X727292D03*
Y434106D03*
X724143Y430957D03*
X727292Y427807D03*
X736661D03*
X727292Y424657D03*
X724143Y434106D03*
Y421508D03*
X739811Y430957D03*
X724143Y427807D03*
Y424657D03*
X733512Y437256D03*
X727292Y440405D03*
X724143Y446705D03*
X736661D03*
X733512Y440405D03*
X736661D03*
X727292Y437256D03*
X724143Y440405D03*
Y437256D03*
X736661D03*
Y459223D03*
Y456074D03*
X733512D03*
Y449854D03*
X736661D03*
X727292Y456074D03*
X724143Y459223D03*
Y456074D03*
X727292Y449854D03*
X724143D03*
X727292Y471822D03*
X724143Y468672D03*
X727292D03*
X736661D03*
X724143Y474971D03*
X733512Y478121D03*
X724143Y465523D03*
X727292D03*
X733512D03*
X736661D03*
X733512Y474971D03*
Y468672D03*
X736661Y478121D03*
Y471822D03*
X724143Y478121D03*
X727292D03*
X733512Y471822D03*
X736661Y474971D03*
Y487570D03*
Y481271D03*
X733512D03*
X727292D03*
X724143Y487570D03*
X727292Y484420D03*
Y487570D03*
X727398Y756832D03*
X731957D03*
Y760178D03*
X727398Y763525D03*
X731462Y766871D03*
X731907Y763525D03*
X727448Y770218D03*
X736457Y1068052D03*
Y1064706D03*
X755559Y421508D03*
X739811Y424657D03*
Y427807D03*
X742961Y424657D03*
Y427807D03*
X746110Y424657D03*
Y427807D03*
X752409Y430957D03*
Y434106D03*
X749260D03*
X752409Y424657D03*
X749260D03*
X746110Y430957D03*
X749260D03*
X742961D03*
X752409Y427807D03*
X749260D03*
X739811Y434106D03*
X742961D03*
X746110D03*
X752409Y443555D03*
X739811Y437256D03*
X746110D03*
X742961D03*
X746110Y440405D03*
X749260Y437256D03*
X739811Y440405D03*
X742961Y443555D03*
Y446705D03*
X752409Y440405D03*
X749260D03*
Y446705D03*
X752409Y437256D03*
Y446705D03*
X746110D03*
Y443555D03*
X749260D03*
X742961Y459223D03*
Y462373D03*
Y456074D03*
Y449854D03*
X752409Y456074D03*
X749260Y449854D03*
X746110Y459223D03*
X752409Y462373D03*
Y459223D03*
X749260D03*
X746110Y456074D03*
Y449854D03*
Y462373D03*
X749260D03*
X752409Y449854D03*
X749260Y456074D03*
X742961Y474971D03*
Y468672D03*
X739811Y478121D03*
Y474971D03*
Y471822D03*
X749260D03*
X739811Y468672D03*
X749260D03*
Y474971D03*
X742961Y471822D03*
X749260Y478121D03*
X746110Y474971D03*
X752409Y468672D03*
X742961Y478121D03*
X746110Y468672D03*
X739811Y465523D03*
X752409Y478121D03*
Y471822D03*
Y465523D03*
X746110D03*
X749260D03*
X752409Y474971D03*
X746110Y478121D03*
Y471822D03*
X749260Y481271D03*
X742961Y484420D03*
X739811Y481271D03*
X746110Y484420D03*
X749260D03*
X752409Y487570D03*
X742961D03*
Y490070D03*
X746110Y481271D03*
X752409D03*
X742961D03*
X741007Y763766D03*
X752599Y960966D03*
X747099D03*
X755559Y418358D03*
X758709D03*
X761858D03*
X755559Y427807D03*
Y430957D03*
X758709Y427807D03*
Y430957D03*
X765008Y424657D03*
X755559D03*
X758709D03*
Y421508D03*
X761858Y424657D03*
X765008Y430957D03*
X755559Y434106D03*
X761858Y430957D03*
Y427807D03*
X758709Y434106D03*
X765008Y427807D03*
Y446705D03*
X758709D03*
X755559Y443555D03*
Y446705D03*
Y437256D03*
X758709Y440405D03*
X755559D03*
X758709Y443555D03*
X761858Y446705D03*
X755559Y449854D03*
Y459223D03*
X765008Y456074D03*
X758709Y465523D03*
X755559Y462373D03*
X758709Y459223D03*
Y462373D03*
Y456074D03*
Y449854D03*
X755559Y478121D03*
Y468672D03*
Y471822D03*
X758709D03*
X761858Y478121D03*
Y474971D03*
Y471822D03*
X758709Y474971D03*
X765008Y471822D03*
Y474971D03*
Y465523D03*
X758709Y478121D03*
X761858Y468672D03*
Y465523D03*
X765008Y468672D03*
X755559Y465523D03*
Y474971D03*
Y481271D03*
Y484420D03*
X765008Y481271D03*
X761858D03*
X758709D03*
X757099Y756832D03*
X761658D03*
Y760178D03*
X757149Y766871D03*
X757099Y763525D03*
X761608D03*
X757149Y770218D03*
X766158Y1068052D03*
Y1064706D03*
X770708Y763766D03*
X782300Y960966D03*
X776800D03*
X786800Y756832D03*
X791358Y760178D03*
Y756832D03*
X786850Y766871D03*
X786800Y763525D03*
X791308D03*
X786850Y770218D03*
X795858Y780257D03*
Y786950D03*
Y803682D03*
Y793643D03*
Y796989D03*
Y817068D03*
Y810375D03*
Y823761D03*
Y830454D03*
Y833800D03*
Y840493D03*
Y847186D03*
Y853879D03*
Y860572D03*
Y877304D03*
Y867265D03*
Y870611D03*
Y883997D03*
Y890690D03*
Y897383D03*
Y904076D03*
Y907423D03*
Y914115D03*
Y920808D03*
Y927501D03*
Y934194D03*
Y940887D03*
Y950926D03*
Y944234D03*
Y964312D03*
Y957619D03*
Y971005D03*
Y977698D03*
Y984391D03*
Y1001123D03*
Y997777D03*
Y991084D03*
Y1031241D03*
Y1037934D03*
Y1044627D03*
Y1058013D03*
Y1051320D03*
Y1074745D03*
Y1068052D03*
Y1064706D03*
Y1081438D03*
Y1088131D03*
Y1098171D03*
Y1104863D03*
Y1091478D03*
Y1111556D03*
Y1118249D03*
Y1134982D03*
Y1124942D03*
Y1128289D03*
Y1148367D03*
Y1141675D03*
Y1155060D03*
Y1161753D03*
Y1165100D03*
Y1171793D03*
Y1178486D03*
Y1185178D03*
Y1191871D03*
Y1208604D03*
Y1198564D03*
Y1201911D03*
Y1215297D03*
Y1221989D03*
Y1228682D03*
Y1235375D03*
Y1238722D03*
Y1245415D03*
Y1252108D03*
X812000Y776911D03*
X800409Y763765D03*
X812000Y783604D03*
Y790297D03*
Y800336D03*
Y807029D03*
Y793643D03*
Y813722D03*
Y820415D03*
Y837147D03*
Y830454D03*
Y827108D03*
Y843840D03*
Y850533D03*
Y857226D03*
Y863919D03*
Y873958D03*
Y880651D03*
Y867265D03*
Y887344D03*
Y894037D03*
Y910769D03*
Y904076D03*
Y900730D03*
Y924155D03*
Y917462D03*
Y930848D03*
Y940887D03*
Y937541D03*
Y947580D03*
Y954273D03*
Y960966D03*
Y967659D03*
Y974352D03*
Y981045D03*
Y987737D03*
Y994430D03*
Y1001123D03*
Y1027895D03*
Y1034588D03*
Y1041281D03*
Y1047974D03*
Y1054667D03*
Y1061360D03*
Y1071399D03*
Y1064706D03*
Y1078092D03*
Y1088131D03*
Y1084785D03*
Y1094824D03*
Y1101517D03*
Y1108210D03*
Y1114903D03*
Y1131635D03*
Y1124942D03*
Y1121596D03*
Y1138328D03*
Y1145021D03*
Y1151714D03*
Y1161753D03*
Y1158407D03*
Y1168446D03*
Y1175139D03*
Y1181832D03*
Y1188525D03*
Y1205257D03*
Y1198564D03*
Y1195218D03*
Y1211950D03*
Y1218643D03*
Y1225336D03*
Y1235375D03*
Y1232029D03*
Y1242068D03*
Y1248761D03*
X816500Y756832D03*
X816550Y770218D03*
X816500Y763525D03*
X998206Y196191D03*
X1000706D03*
X998206Y199735D03*
X1000706D03*
X998206Y206821D03*
X1000706D03*
X998206Y203278D03*
X1000706D03*
X1040965Y756831D03*
Y760177D03*
X1050015Y763765D03*
X1040915Y763524D03*
X1045465Y780256D03*
Y786949D03*
Y803681D03*
Y793642D03*
Y796988D03*
Y817067D03*
Y810374D03*
Y823760D03*
Y830453D03*
Y833799D03*
Y840492D03*
Y847185D03*
Y853878D03*
Y860571D03*
Y877303D03*
Y867264D03*
Y870610D03*
Y883996D03*
Y890689D03*
Y897382D03*
Y904075D03*
Y907422D03*
Y914114D03*
Y920807D03*
Y927500D03*
Y934193D03*
Y940886D03*
Y950925D03*
Y944233D03*
Y964311D03*
Y957618D03*
Y971004D03*
Y977697D03*
Y984390D03*
Y1001122D03*
Y997776D03*
Y991083D03*
Y1031240D03*
Y1037933D03*
Y1044626D03*
Y1058012D03*
Y1051319D03*
Y1074744D03*
Y1068051D03*
Y1064705D03*
Y1081437D03*
Y1088130D03*
Y1098170D03*
Y1104862D03*
Y1091477D03*
Y1111555D03*
Y1118248D03*
Y1134981D03*
Y1124941D03*
Y1128288D03*
Y1148366D03*
Y1141674D03*
Y1155059D03*
Y1161752D03*
Y1165099D03*
Y1171792D03*
Y1178485D03*
Y1185177D03*
Y1191870D03*
Y1208603D03*
Y1198563D03*
Y1201910D03*
Y1215296D03*
Y1221988D03*
Y1228681D03*
Y1235374D03*
Y1238721D03*
Y1245414D03*
Y1252107D03*
X1066107Y756831D03*
X1066157Y766870D03*
X1061607Y776910D03*
X1066107Y763524D03*
X1066157Y770217D03*
X1061607Y783603D03*
Y790296D03*
Y800335D03*
Y807028D03*
Y793642D03*
Y813721D03*
Y820414D03*
Y837146D03*
Y830453D03*
Y827107D03*
Y843839D03*
Y850532D03*
Y857225D03*
Y863918D03*
Y873957D03*
Y880650D03*
Y867264D03*
Y887343D03*
Y894036D03*
Y910768D03*
Y904075D03*
Y900729D03*
Y924154D03*
Y917461D03*
Y930847D03*
Y940886D03*
Y937540D03*
Y947579D03*
Y954272D03*
Y960965D03*
Y967658D03*
Y974351D03*
Y981044D03*
Y987736D03*
Y994429D03*
Y1001122D03*
Y1027894D03*
Y1034587D03*
Y1041280D03*
Y1047973D03*
Y1054666D03*
Y1061359D03*
Y1071398D03*
Y1064705D03*
Y1078091D03*
Y1088130D03*
Y1084784D03*
Y1094823D03*
Y1101516D03*
Y1108209D03*
Y1114902D03*
Y1131634D03*
Y1124941D03*
Y1121595D03*
Y1138327D03*
Y1145020D03*
Y1151713D03*
Y1161752D03*
Y1158406D03*
Y1168445D03*
Y1175138D03*
Y1181831D03*
Y1188524D03*
Y1205256D03*
Y1198563D03*
Y1195217D03*
Y1211949D03*
Y1218642D03*
Y1225335D03*
Y1235374D03*
Y1232028D03*
Y1242067D03*
Y1248760D03*
X1070666Y756831D03*
Y760177D03*
X1079716Y763765D03*
X1070616Y763524D03*
X1075166Y1068051D03*
Y1064705D03*
X1095808Y756831D03*
X1095858Y766870D03*
X1095808Y763524D03*
X1095858Y770217D03*
X1091308Y960965D03*
X1100366Y756831D03*
Y760177D03*
X1109416Y763765D03*
X1100316Y763524D03*
X1096808Y960965D03*
X1104866Y1068051D03*
Y1064705D03*
X1125508Y756831D03*
X1125558Y766870D03*
X1125508Y763524D03*
X1125558Y770217D03*
X1121008Y960965D03*
X1130067Y756831D03*
Y760177D03*
X1139117Y763765D03*
X1130017Y763524D03*
X1126508Y960965D03*
X1134567Y1068051D03*
Y1064705D03*
X1155209Y756831D03*
Y763524D03*
X1155259Y770217D03*
X1150709Y960965D03*
X1159768Y756831D03*
Y760177D03*
X1168818Y763765D03*
X1159718Y763524D03*
X1164268Y780256D03*
Y786949D03*
Y803681D03*
Y793642D03*
Y796988D03*
Y817067D03*
Y810374D03*
Y823760D03*
Y830453D03*
Y833799D03*
Y840492D03*
Y847185D03*
Y853878D03*
Y860571D03*
Y877303D03*
Y867264D03*
Y870610D03*
Y883996D03*
Y890689D03*
Y897382D03*
Y904075D03*
Y907422D03*
Y914114D03*
Y920807D03*
Y927500D03*
Y934193D03*
Y940886D03*
Y950925D03*
Y944233D03*
Y964311D03*
Y957618D03*
Y971004D03*
X1156209Y960965D03*
X1164268Y977697D03*
Y984390D03*
Y1001122D03*
Y997776D03*
Y991083D03*
Y1031240D03*
Y1037933D03*
Y1044626D03*
Y1058012D03*
Y1051319D03*
Y1074744D03*
Y1068051D03*
Y1064705D03*
Y1081437D03*
Y1088130D03*
Y1098170D03*
Y1104862D03*
Y1091477D03*
Y1111555D03*
Y1118248D03*
Y1134981D03*
Y1124941D03*
Y1128288D03*
Y1148366D03*
Y1141674D03*
Y1155059D03*
Y1161752D03*
Y1165099D03*
Y1171792D03*
Y1178485D03*
Y1185177D03*
Y1191870D03*
Y1208603D03*
Y1198563D03*
Y1201910D03*
Y1215296D03*
Y1221988D03*
Y1228681D03*
Y1235374D03*
Y1238721D03*
Y1245414D03*
Y1252107D03*
X1184910Y756831D03*
X1180410Y776910D03*
X1184910Y763524D03*
X1184960Y770217D03*
X1180410Y783603D03*
Y790296D03*
Y800335D03*
Y807028D03*
Y793642D03*
Y813721D03*
Y820414D03*
Y837146D03*
Y830453D03*
Y827107D03*
Y843839D03*
Y850532D03*
Y857225D03*
Y863918D03*
Y873957D03*
Y880650D03*
Y867264D03*
Y887343D03*
Y894036D03*
Y910768D03*
Y904075D03*
Y900729D03*
Y924154D03*
Y917461D03*
Y930847D03*
Y940886D03*
Y937540D03*
Y947579D03*
Y954272D03*
Y960965D03*
Y967658D03*
Y974351D03*
Y981044D03*
Y987736D03*
Y994429D03*
Y1001122D03*
Y1027894D03*
Y1034587D03*
Y1041280D03*
Y1047973D03*
Y1054666D03*
Y1061359D03*
Y1071398D03*
Y1064705D03*
Y1078091D03*
Y1088130D03*
Y1084784D03*
Y1094823D03*
Y1101516D03*
Y1108209D03*
Y1114902D03*
Y1131634D03*
Y1124941D03*
Y1121595D03*
Y1138327D03*
Y1145020D03*
Y1151713D03*
Y1161752D03*
Y1158406D03*
Y1168445D03*
Y1175138D03*
Y1181831D03*
Y1188524D03*
Y1205256D03*
Y1198563D03*
Y1195217D03*
Y1211949D03*
Y1218642D03*
Y1225335D03*
Y1235374D03*
Y1232028D03*
Y1242067D03*
Y1248760D03*
X1189469Y760177D03*
Y756831D03*
X1198519Y763765D03*
X1188805Y766870D03*
X1189419Y763524D03*
X1194403Y1556953D03*
X1199678Y1559353D03*
X1194954D03*
X1199127Y1556953D03*
X1196127Y1577997D03*
Y1581397D03*
X1196039Y1657292D03*
X1199439D03*
X1214600Y759562D03*
X1205448Y769914D03*
X1214661Y766870D03*
X1214611Y763524D03*
X1214841Y772277D03*
X1210111Y960965D03*
X1203682D03*
X1208576Y1556953D03*
X1204403Y1559353D03*
X1209127D03*
X1203852Y1556953D03*
X1213300D03*
X1213851Y1559353D03*
X1200851Y1577997D03*
X1205576D03*
X1210300D03*
X1215025D03*
X1200851Y1581397D03*
X1205576D03*
X1210300D03*
X1215025D03*
X1202069Y1635380D03*
X1214129D03*
X1205469D03*
X1202069Y1647292D03*
X1214129D03*
X1205469D03*
X1208099Y1657292D03*
X1211499D03*
X1218025Y1556953D03*
X1218576Y1559353D03*
X1227474Y1556953D03*
X1228025Y1559353D03*
X1222749Y1556953D03*
X1223300Y1559353D03*
X1219749Y1577997D03*
X1224474D03*
X1229198D03*
X1219749Y1581397D03*
X1224474D03*
X1229198D03*
X1226189Y1635380D03*
X1217529D03*
X1229589D03*
X1226189Y1647292D03*
X1217529D03*
X1229589D03*
X1220159Y1657292D03*
X1223559D03*
X1241647Y1556953D03*
X1242198Y1559353D03*
X1232198Y1556953D03*
X1232749Y1559353D03*
X1236922Y1556953D03*
X1237473Y1559353D03*
X1243372Y1577997D03*
X1233923D03*
X1238647D03*
X1243372Y1581397D03*
X1233923D03*
X1238647D03*
X1238249Y1635380D03*
X1241649D03*
X1238249Y1647292D03*
X1241649D03*
X1232219Y1657292D03*
X1244279D03*
X1235619D03*
X1251647Y1559353D03*
X1251096Y1556953D03*
X1255820D03*
X1256371Y1559353D03*
X1246371Y1556953D03*
X1246922Y1559353D03*
X1248096Y1577997D03*
X1252820D03*
X1257544D03*
X1248096Y1581397D03*
X1252820D03*
X1257544D03*
X1250309Y1635380D03*
X1253709D03*
X1250309Y1647292D03*
X1253709D03*
X1256339Y1657292D03*
X1247679D03*
X1259739D03*
X1265269Y1556953D03*
X1265820Y1559353D03*
X1261096D03*
X1260545Y1556953D03*
X1262269Y1577997D03*
X1266993D03*
X1262269Y1581397D03*
X1266993D03*
X1262369Y1635380D03*
X1274429D03*
X1265769D03*
X1262369Y1647292D03*
X1274429D03*
X1265769D03*
X1268399Y1657292D03*
X1271799D03*
X1286489Y1635380D03*
X1277829D03*
X1289889D03*
X1286489Y1647292D03*
X1277829D03*
X1289889D03*
X1280459Y1657292D03*
X1283859D03*
X1298549Y1635380D03*
X1301949D03*
X1298549Y1647292D03*
X1301949D03*
X1292519Y1657292D03*
X1304579D03*
X1295919D03*
X1310609Y1635380D03*
X1314009D03*
X1310609Y1647292D03*
X1314009D03*
X1316639Y1657292D03*
X1320039D03*
X1307979D03*
X1332465Y1559353D03*
X1331914Y1556953D03*
X1322465D03*
X1327189D03*
X1323016Y1559353D03*
X1327740D03*
X1324189Y1577997D03*
X1328913D03*
X1333638D03*
X1324189Y1581397D03*
X1328913D03*
X1333638D03*
X1322669Y1635380D03*
X1334729D03*
X1326069D03*
X1322669Y1647292D03*
X1334729D03*
X1326069D03*
X1328699Y1657292D03*
X1332099D03*
X1346087Y1556953D03*
X1346638Y1559353D03*
X1336638Y1556953D03*
X1337189Y1559353D03*
X1341913D03*
X1341362Y1556953D03*
X1338362Y1577997D03*
X1343087D03*
X1347811D03*
X1338362Y1581397D03*
X1343087D03*
X1347811D03*
X1346789Y1635380D03*
X1338129D03*
X1346789Y1647292D03*
X1338129D03*
X1340759Y1657292D03*
X1344159D03*
X1360260Y1556953D03*
X1360811Y1559353D03*
X1350811Y1556953D03*
X1351362Y1559353D03*
X1356087D03*
X1355536Y1556953D03*
X1352536Y1577997D03*
X1357260D03*
X1361985D03*
X1352536Y1581397D03*
X1357260D03*
X1361985D03*
X1358849Y1635380D03*
X1350189D03*
X1362249D03*
X1358849Y1647292D03*
X1350189D03*
X1362249D03*
X1352819Y1657292D03*
X1356219D03*
X1369709Y1556953D03*
X1370260Y1559353D03*
X1379158Y1556953D03*
X1374984Y1559353D03*
X1374433Y1556953D03*
X1365535Y1559353D03*
X1364984Y1556953D03*
X1371434Y1577997D03*
X1376158D03*
X1366709D03*
X1371434Y1581397D03*
X1376158D03*
X1366709D03*
X1370909Y1635380D03*
X1374309D03*
X1370909Y1647292D03*
X1374309D03*
X1364879Y1657292D03*
X1376939D03*
X1368279D03*
X1388607Y1556953D03*
X1384433Y1559353D03*
X1383882Y1556953D03*
X1379709Y1559353D03*
X1393882D03*
X1389158D03*
X1393331Y1556953D03*
X1380882Y1577997D03*
X1385606D03*
X1390331D03*
X1380882Y1581397D03*
X1385606D03*
X1390331D03*
X1382969Y1635380D03*
X1386369D03*
X1382969Y1647292D03*
X1386369D03*
X1380339Y1657292D03*
X1395055Y1577997D03*
Y1581397D03*
X1458577Y1556953D03*
X1468577Y1559353D03*
X1463852D03*
X1459128D03*
X1463301Y1556953D03*
X1468026D03*
X1460301Y1577997D03*
X1465025D03*
X1460301Y1581397D03*
X1465025D03*
X1466243Y1635380D03*
Y1647292D03*
X1460213Y1657292D03*
X1463613D03*
X1482199Y1556953D03*
X1482750Y1559353D03*
X1472750Y1556953D03*
X1473301Y1559353D03*
X1477474Y1556953D03*
X1478025Y1559353D03*
X1469750Y1577997D03*
X1474474D03*
X1479199D03*
X1483923D03*
X1469750Y1581397D03*
X1474474D03*
X1479199D03*
X1483923D03*
X1478303Y1635380D03*
X1469643D03*
X1481703D03*
X1478303Y1647292D03*
X1469643D03*
X1481703D03*
X1472273Y1657292D03*
X1475673D03*
X1496372Y1556953D03*
X1491648D03*
X1496923Y1559353D03*
X1492199D03*
X1486923Y1556953D03*
X1487474Y1559353D03*
X1488648Y1577997D03*
X1493372D03*
X1498097D03*
X1488648Y1581397D03*
X1493372D03*
X1498097D03*
X1490363Y1635380D03*
X1493763D03*
X1490363Y1647292D03*
X1493763D03*
X1484333Y1657292D03*
X1496393D03*
X1487733D03*
X1505821Y1556953D03*
X1506372Y1559353D03*
X1511096D03*
X1510545Y1556953D03*
X1501096D03*
X1501647Y1559353D03*
X1507546Y1577997D03*
X1512270D03*
X1502821D03*
X1507546Y1581397D03*
X1512270D03*
X1502821D03*
X1502423Y1635380D03*
X1505823D03*
X1502423Y1647292D03*
X1505823D03*
X1508453Y1657292D03*
X1499793D03*
X1511853D03*
X1515821Y1559353D03*
X1515270Y1556953D03*
X1519994D03*
X1520545Y1559353D03*
X1525270D03*
X1524719Y1556953D03*
X1516994Y1577997D03*
X1521718D03*
X1526443D03*
X1516994Y1581397D03*
X1521718D03*
X1526443D03*
X1514483Y1635380D03*
X1526543D03*
X1517883D03*
X1514483Y1647292D03*
X1526543D03*
X1517883D03*
X1520513Y1657292D03*
X1523913D03*
X1529443Y1556953D03*
X1529994Y1559353D03*
X1531167Y1577997D03*
Y1581397D03*
X1538603Y1635380D03*
X1529943D03*
X1542003D03*
X1538603Y1647292D03*
X1529943D03*
X1542003D03*
X1532573Y1657292D03*
X1535973D03*
X1550663Y1635380D03*
X1554063D03*
X1550663Y1647292D03*
X1554063D03*
X1544633Y1657292D03*
X1556693D03*
X1548033D03*
X1562723Y1635380D03*
X1566123D03*
X1562723Y1647292D03*
X1566123D03*
X1568753Y1657292D03*
X1560093D03*
X1572153D03*
X1586639Y1556953D03*
X1587190Y1559353D03*
X1588363Y1577997D03*
Y1581397D03*
X1586843Y1635380D03*
X1574783D03*
X1578183D03*
X1586843Y1647292D03*
X1574783D03*
X1578183D03*
X1580813Y1657292D03*
X1584213D03*
X1600812Y1556953D03*
X1596639Y1559353D03*
X1596088Y1556953D03*
X1601363Y1559353D03*
X1591363Y1556953D03*
X1591914Y1559353D03*
X1593087Y1577997D03*
X1597812D03*
X1602536D03*
X1593087Y1581397D03*
X1597812D03*
X1602536D03*
X1598903Y1635380D03*
X1590243D03*
X1602303D03*
X1598903Y1647292D03*
X1590243D03*
X1602303D03*
X1592873Y1657292D03*
X1596273D03*
X1610261Y1556953D03*
X1610812Y1559353D03*
X1606087D03*
X1605536Y1556953D03*
X1614985D03*
X1615536Y1559353D03*
X1607261Y1577997D03*
X1611985D03*
X1616710D03*
X1607261Y1581397D03*
X1611985D03*
X1616710D03*
X1610963Y1635380D03*
X1614363D03*
X1610963Y1647292D03*
X1614363D03*
X1604933Y1657292D03*
X1616993D03*
X1608333D03*
X1618996Y760177D03*
Y756831D03*
X1618946Y763524D03*
X1624434Y1556953D03*
X1624985Y1559353D03*
X1620261D03*
X1619710Y1556953D03*
X1629709Y1559353D03*
X1629158Y1556953D03*
X1621434Y1577997D03*
X1626159D03*
X1630883D03*
X1621434Y1581397D03*
X1626159D03*
X1630883D03*
X1623023Y1635380D03*
X1626423D03*
X1623023Y1647292D03*
X1626423D03*
X1629053Y1657292D03*
X1620393D03*
X1632453D03*
X1644138Y756831D03*
Y763524D03*
X1644188Y770217D03*
X1639638Y960965D03*
X1634138D03*
X1633883Y1556953D03*
X1634434Y1559353D03*
X1643332Y1556953D03*
X1643883Y1559353D03*
X1639158D03*
X1638607Y1556953D03*
X1635608Y1577997D03*
X1640332D03*
X1645056D03*
X1635608Y1581397D03*
X1640332D03*
X1645056D03*
X1635083Y1635380D03*
X1647143D03*
X1638483D03*
X1635083Y1647292D03*
X1647143D03*
X1638483D03*
X1641113Y1657292D03*
X1644513D03*
X1648697Y760177D03*
Y756831D03*
X1657747Y763765D03*
X1648647Y766870D03*
Y763524D03*
X1653197Y780256D03*
Y786949D03*
Y803681D03*
Y793642D03*
Y796988D03*
Y817067D03*
Y810374D03*
Y823760D03*
Y830453D03*
Y833799D03*
Y840492D03*
Y847185D03*
Y853878D03*
Y860571D03*
Y877303D03*
Y867264D03*
Y870610D03*
Y883996D03*
Y890689D03*
Y897382D03*
Y904075D03*
Y907422D03*
Y914114D03*
Y920807D03*
Y927500D03*
Y934193D03*
Y940886D03*
Y950925D03*
Y944233D03*
Y964311D03*
Y957618D03*
Y971004D03*
Y977697D03*
Y984390D03*
Y1001122D03*
Y997776D03*
Y991083D03*
Y1031240D03*
Y1037933D03*
Y1044626D03*
Y1058012D03*
Y1051319D03*
Y1074744D03*
Y1068051D03*
Y1064705D03*
Y1081437D03*
Y1088130D03*
Y1098170D03*
Y1104862D03*
Y1091477D03*
Y1111555D03*
Y1118248D03*
Y1134981D03*
Y1124941D03*
Y1128288D03*
Y1148366D03*
Y1141674D03*
Y1155059D03*
Y1161752D03*
Y1165099D03*
Y1171792D03*
Y1178485D03*
Y1185177D03*
Y1191870D03*
Y1208603D03*
Y1198563D03*
Y1201910D03*
Y1215296D03*
Y1221988D03*
Y1228681D03*
Y1235374D03*
Y1238721D03*
Y1245414D03*
Y1252107D03*
X1652781Y1556953D03*
X1648607Y1559353D03*
X1648056Y1556953D03*
X1658056Y1559353D03*
X1653332D03*
X1657505Y1556953D03*
X1649780Y1577997D03*
X1654505D03*
X1659229D03*
X1649780Y1581397D03*
X1654505D03*
X1659229D03*
X1650543Y1635380D03*
Y1647292D03*
X1673839Y756831D03*
X1669339Y776910D03*
X1673839Y763524D03*
X1673889Y770217D03*
X1669339Y783603D03*
Y790296D03*
Y800335D03*
Y807028D03*
Y793642D03*
Y813721D03*
Y820414D03*
Y837146D03*
Y830453D03*
Y827107D03*
Y843839D03*
Y850532D03*
Y857225D03*
Y863918D03*
Y873957D03*
Y880650D03*
Y867264D03*
Y887343D03*
Y894036D03*
Y910768D03*
Y904075D03*
Y900729D03*
Y924154D03*
Y917461D03*
Y930847D03*
Y940886D03*
Y937540D03*
Y947579D03*
Y954272D03*
Y960965D03*
Y967658D03*
Y974351D03*
Y981044D03*
Y987736D03*
Y994429D03*
Y1001122D03*
Y1027894D03*
Y1034587D03*
Y1041280D03*
Y1047973D03*
Y1054666D03*
Y1061359D03*
Y1071398D03*
Y1064705D03*
Y1078091D03*
Y1088130D03*
Y1084784D03*
Y1094823D03*
Y1101516D03*
Y1108209D03*
Y1114902D03*
Y1131634D03*
Y1124941D03*
Y1121595D03*
Y1138327D03*
Y1145020D03*
Y1151713D03*
Y1161752D03*
Y1158406D03*
Y1168445D03*
Y1175138D03*
Y1181831D03*
Y1188524D03*
Y1205256D03*
Y1198563D03*
Y1195217D03*
Y1211949D03*
Y1218642D03*
Y1225335D03*
Y1235374D03*
Y1232028D03*
Y1242067D03*
Y1248760D03*
X1678398Y760177D03*
Y756831D03*
X1687448Y763765D03*
X1678348Y766870D03*
Y763524D03*
X1682898Y1068051D03*
Y1064705D03*
X1703540Y756831D03*
X1703590Y766870D03*
X1703540Y763524D03*
X1703590Y770217D03*
X1699040Y960965D03*
X1693540D03*
X1708099Y760177D03*
Y756831D03*
X1717149Y763765D03*
X1708049Y763524D03*
X1712599Y1068051D03*
Y1064705D03*
X1736986Y109723D03*
Y112223D03*
X1733241Y756831D03*
X1733727Y766870D03*
X1733241Y763524D03*
X1733291Y770217D03*
X1728741Y960965D03*
X1723241D03*
X1740529Y112223D03*
Y109723D03*
X1744072Y112223D03*
Y109723D03*
X1747616Y112223D03*
Y109723D03*
X1737800Y756831D03*
Y760177D03*
X1746850Y763765D03*
X1737750Y763524D03*
X1742300Y1068051D03*
Y1064705D03*
X1762942Y756831D03*
X1762992Y766870D03*
X1762942Y763524D03*
X1762992Y770217D03*
X1758442Y960965D03*
X1752942D03*
X1767500Y760177D03*
Y756831D03*
X1767450Y763524D03*
X1772000Y780256D03*
Y786949D03*
Y803681D03*
Y793642D03*
Y796988D03*
Y817067D03*
Y810374D03*
Y823760D03*
Y830453D03*
Y833799D03*
Y840492D03*
Y847185D03*
Y853878D03*
Y860571D03*
Y877303D03*
Y867264D03*
Y870610D03*
Y883996D03*
Y890689D03*
Y897382D03*
Y904075D03*
Y907422D03*
Y914114D03*
Y920807D03*
Y927500D03*
Y934193D03*
Y940886D03*
Y950925D03*
Y944233D03*
Y964311D03*
Y957618D03*
Y971004D03*
Y977697D03*
Y984390D03*
Y1001122D03*
Y997776D03*
Y991083D03*
Y1031240D03*
Y1037933D03*
Y1044626D03*
Y1058012D03*
Y1051319D03*
Y1074744D03*
Y1068051D03*
Y1064705D03*
Y1081437D03*
Y1088130D03*
Y1098170D03*
Y1104862D03*
Y1091477D03*
Y1111555D03*
Y1118248D03*
Y1134981D03*
Y1124941D03*
Y1128288D03*
Y1148366D03*
Y1141674D03*
Y1155059D03*
Y1161752D03*
Y1165099D03*
Y1171792D03*
Y1178485D03*
Y1185177D03*
Y1191870D03*
Y1208603D03*
Y1198563D03*
Y1201910D03*
Y1215296D03*
Y1221988D03*
Y1228681D03*
Y1235374D03*
Y1238721D03*
Y1245414D03*
Y1252107D03*
X1792642Y756831D03*
X1788142Y776910D03*
X1792642Y763524D03*
X1792692Y770217D03*
X1788142Y783603D03*
Y790296D03*
Y800335D03*
Y807028D03*
Y793642D03*
Y813721D03*
Y820414D03*
Y837146D03*
Y830453D03*
Y827107D03*
Y843839D03*
Y850532D03*
Y857225D03*
Y863918D03*
Y873957D03*
Y880650D03*
Y867264D03*
Y887343D03*
Y894036D03*
Y910768D03*
Y904075D03*
Y900729D03*
Y924154D03*
Y917461D03*
Y930847D03*
Y940886D03*
Y937540D03*
Y947579D03*
Y954272D03*
Y960965D03*
Y967658D03*
Y974351D03*
Y981044D03*
Y987736D03*
Y994429D03*
Y1001122D03*
Y1027894D03*
Y1034587D03*
Y1041280D03*
Y1047973D03*
Y1054666D03*
Y1061359D03*
Y1071398D03*
Y1064705D03*
Y1078091D03*
Y1088130D03*
Y1084784D03*
Y1094823D03*
Y1101516D03*
Y1108209D03*
Y1114902D03*
Y1131634D03*
Y1124941D03*
Y1121595D03*
Y1138327D03*
Y1145020D03*
Y1151713D03*
Y1161752D03*
Y1158406D03*
Y1168445D03*
Y1175138D03*
Y1181831D03*
Y1188524D03*
Y1205256D03*
Y1198563D03*
Y1195217D03*
Y1211949D03*
Y1218642D03*
Y1225335D03*
Y1235374D03*
Y1232028D03*
Y1242067D03*
Y1248760D03*
G54D42*
X373673Y-28871D03*
Y-18871D03*
D03*
Y-8871D03*
X398673Y-28871D03*
Y-18871D03*
D03*
Y-8871D03*
X718093Y-28871D03*
Y-18871D03*
D03*
Y-8871D03*
X743093Y-28871D03*
Y-18871D03*
D03*
Y-8871D03*
X825152Y-35011D03*
Y-25011D03*
Y-15011D03*
Y-25011D03*
Y-15011D03*
Y-5011D03*
D03*
Y4989D03*
Y14989D03*
D03*
Y4989D03*
Y24989D03*
X850152Y-35011D03*
Y-25011D03*
Y-15011D03*
Y-25011D03*
Y-15011D03*
Y-5011D03*
D03*
Y4989D03*
Y14989D03*
D03*
Y4989D03*
Y24989D03*
X1169572Y-35011D03*
Y-15011D03*
Y-25011D03*
D03*
Y-15011D03*
Y-5011D03*
D03*
Y4989D03*
Y14989D03*
Y4989D03*
Y14989D03*
Y24989D03*
X1194572Y-35011D03*
Y-15011D03*
Y-25011D03*
D03*
Y-15011D03*
Y-5011D03*
D03*
Y4989D03*
Y14989D03*
Y4989D03*
Y14989D03*
Y24989D03*
X1228672Y-35011D03*
Y-25011D03*
Y-15011D03*
Y-25011D03*
Y-15011D03*
Y-5011D03*
D03*
Y4989D03*
Y14989D03*
D03*
Y4989D03*
Y24989D03*
X1253672Y-35011D03*
Y-25011D03*
Y-15011D03*
Y-25011D03*
Y-15011D03*
Y-5011D03*
D03*
Y4989D03*
Y14989D03*
D03*
Y4989D03*
Y24989D03*
X1428431Y-35011D03*
Y-15011D03*
Y-25011D03*
D03*
Y-15011D03*
Y-5011D03*
D03*
Y4989D03*
Y14989D03*
Y4989D03*
Y14989D03*
Y24989D03*
X1453431Y-35011D03*
Y-15011D03*
Y-25011D03*
D03*
Y-15011D03*
Y-5011D03*
D03*
Y4989D03*
Y14989D03*
Y4989D03*
Y14989D03*
Y24989D03*
X1521966Y-29212D03*
D03*
Y-39212D03*
Y-19212D03*
X1546966Y-29212D03*
D03*
Y-39212D03*
Y-19212D03*
X1721725Y-29212D03*
Y-39212D03*
Y-29212D03*
Y-19212D03*
X1746725Y-29212D03*
Y-39212D03*
Y-29212D03*
Y-19212D03*
G54D53*
X793879Y194881D03*
X789942Y204724D03*
X793879Y214567D03*
X805690Y188976D03*
Y220472D03*
X817501Y194881D03*
X821438Y204724D03*
X817501Y214567D03*
X828390Y1420331D03*
X841240Y1407481D03*
X832154Y1411245D03*
Y1429417D03*
X841240Y1433181D03*
X850326Y1411245D03*
Y1429417D03*
X854090Y1420331D03*
X1007154Y1411245D03*
X1003390Y1420331D03*
X1007154Y1429417D03*
X1016240Y1407481D03*
Y1433181D03*
X1025326Y1411245D03*
Y1429417D03*
X1029090Y1420331D03*
X1045848Y194881D03*
X1041911Y204724D03*
X1045848Y214567D03*
X1057659Y188976D03*
Y220472D03*
X1069470Y194881D03*
X1073407Y204724D03*
X1069470Y214567D03*
G54D10*
X3001Y61178D03*
Y127178D03*
Y149178D03*
Y171178D03*
Y193178D03*
Y215178D03*
Y237178D03*
Y259178D03*
Y281178D03*
Y303178D03*
X10875Y323721D03*
Y345721D03*
Y367721D03*
Y389721D03*
Y411721D03*
Y433721D03*
Y455721D03*
Y477721D03*
Y499721D03*
Y521721D03*
X20587Y523970D03*
X16342Y516951D03*
X16512Y533155D03*
X10875Y543721D03*
Y565721D03*
Y587721D03*
Y609721D03*
Y653721D03*
Y675721D03*
Y697721D03*
Y719721D03*
Y741721D03*
Y763721D03*
Y785721D03*
Y807721D03*
Y829721D03*
Y851721D03*
Y873721D03*
Y895721D03*
Y917721D03*
Y939721D03*
Y961721D03*
Y983721D03*
Y1005721D03*
Y1027721D03*
Y1049721D03*
Y1071721D03*
Y1093721D03*
Y1115721D03*
Y1137721D03*
Y1159721D03*
Y1181721D03*
Y1203721D03*
Y1225721D03*
Y1247721D03*
Y1269721D03*
Y1291721D03*
Y1445721D03*
Y1467721D03*
Y1489721D03*
Y1511721D03*
Y1533721D03*
Y1555721D03*
Y1577721D03*
X33184Y523285D03*
X36402Y528675D03*
X33257Y540370D03*
X26887Y541805D03*
X35133Y1603396D03*
X35167Y1610521D03*
X28592Y1617961D03*
X35233Y1623196D03*
X28592Y1639961D03*
Y1661961D03*
Y1683961D03*
X44600Y280357D03*
X50500Y311100D03*
X47602Y1622414D03*
X51333Y1640996D03*
X54584Y8335D03*
Y30335D03*
X58633Y1641388D03*
X85133Y1616396D03*
Y1620896D03*
Y1625396D03*
X85167Y1629905D03*
X101939Y1657742D03*
Y1662728D03*
X120891Y521216D03*
X144610Y429560D03*
X163113Y1486190D03*
X160513Y1479500D03*
Y1484280D03*
X165713Y1479500D03*
Y1484280D03*
X160513Y1501300D03*
Y1506080D03*
X165713D03*
X163113Y1507982D03*
X165713Y1501300D03*
X173488Y1510800D03*
Y1514420D03*
Y1518040D03*
X224055Y127146D03*
X262886Y147391D03*
X274201Y579478D03*
X280621Y1486682D03*
X291175Y1486190D03*
X288575Y1484280D03*
Y1479500D03*
X280621Y1500082D03*
X288575Y1506080D03*
Y1501300D03*
X291175Y1507990D03*
X301747Y121469D03*
Y127469D03*
Y124469D03*
X293775Y1484280D03*
Y1479500D03*
Y1506080D03*
Y1501300D03*
X304606Y1546333D03*
X297323Y1659772D03*
X311754Y121472D03*
Y124472D03*
Y127472D03*
X311476Y1552567D03*
X307255Y1649750D03*
X326475Y182855D03*
X349676Y276708D03*
X349695Y286712D03*
X380181Y236674D03*
X390461Y270694D03*
Y267694D03*
Y275194D03*
X387184Y494382D03*
X390082Y1549178D03*
X404743Y494451D03*
X408683Y1486682D03*
Y1500082D03*
X425555Y92014D03*
Y82014D03*
X412715Y254165D03*
X423730Y249570D03*
X412715Y262165D03*
Y270165D03*
X418543Y494374D03*
X418918Y1006025D03*
Y1013505D03*
Y1009765D03*
Y1024726D03*
Y1020986D03*
Y1028466D03*
Y1017245D03*
X415318Y1032206D03*
X424686Y1484280D03*
Y1479500D03*
Y1506080D03*
Y1501300D03*
X431299Y204145D03*
X432343Y494297D03*
X427286Y1486190D03*
X429886Y1484280D03*
Y1479500D03*
Y1506080D03*
Y1501300D03*
X427286Y1507990D03*
X438732Y1546977D03*
X444090Y116007D03*
X443400Y247880D03*
X448852Y283318D03*
X441159Y1055141D03*
X447587Y1552567D03*
X468228Y70016D03*
X457931Y212703D03*
X465699Y282833D03*
X469323Y306273D03*
X462093Y310123D03*
X467943Y311563D03*
X465153Y310123D03*
X467893Y308643D03*
X458873Y310173D03*
X455813D03*
X462365Y1006025D03*
Y1009765D03*
Y1013505D03*
Y1020986D03*
Y1028466D03*
Y1024726D03*
Y1017245D03*
Y1032206D03*
X462500Y1733500D03*
X480323Y291023D03*
X474691Y306073D03*
X471743Y304923D03*
X473643Y308683D03*
X471003Y311563D03*
X470953Y308643D03*
X484063Y313956D03*
X498776Y209285D03*
Y213285D03*
X500269Y225071D03*
X488908Y242754D03*
X503161Y149895D03*
X514418Y141171D03*
X515151Y220166D03*
X501718Y240558D03*
X508723Y280721D03*
X510223Y289035D03*
X507698D03*
Y297090D03*
X510223D03*
X507698Y305145D03*
X510223D03*
X510606Y314124D03*
X508081D03*
X523831Y95445D03*
Y102931D03*
X519579Y207435D03*
X530418Y141171D03*
X538567Y294777D03*
X542813Y319173D03*
X544794Y1486682D03*
Y1500082D03*
X549800Y147000D03*
X553300Y164500D03*
X556811Y152742D03*
X552699Y291833D03*
X556323Y315273D03*
X558743Y313923D03*
X545873Y319173D03*
X549093Y319123D03*
X558003Y320563D03*
X554943D03*
X552153Y319123D03*
X554893Y317643D03*
X557953D03*
X555348Y1486190D03*
X552748Y1484280D03*
Y1479500D03*
X557948Y1484280D03*
Y1479500D03*
X552748Y1506080D03*
Y1501300D03*
X557948Y1506080D03*
Y1501300D03*
X555348Y1507990D03*
X568472Y149226D03*
X563951Y160644D03*
X567323Y300023D03*
X561691Y315073D03*
X560643Y317683D03*
X568573Y321993D03*
X568779Y1546333D03*
X585685Y178125D03*
X578172Y231393D03*
X587140Y257630D03*
X575524Y261171D03*
X575649Y1552567D03*
X599678Y175534D03*
X595723Y289721D03*
X594698Y298035D03*
X597223D03*
X594698Y314145D03*
X597223D03*
X594698Y306090D03*
X597223D03*
Y322200D03*
X594698D03*
X600520Y401728D03*
X616654Y1382864D03*
X633805Y302289D03*
X642816Y574185D03*
X634529Y674890D03*
X640129D03*
X643649Y674781D03*
X649936Y574185D03*
X660062Y672761D03*
X654676Y674806D03*
X654005Y1548999D03*
X670000Y465844D03*
X672856Y1486682D03*
Y1500082D03*
X719195Y172873D03*
Y177865D03*
X714203Y172873D03*
Y177865D03*
X719195Y196373D03*
X714203D03*
X719195Y184873D03*
Y189865D03*
X714203Y184873D03*
Y189865D03*
Y208207D03*
X719195D03*
Y201365D03*
X714203D03*
Y213199D03*
X719195D03*
X733380Y1577231D03*
X727780Y1582361D03*
Y1577231D03*
X733380Y1587491D03*
X727780D03*
X736998Y1597463D03*
X730998D03*
X733998D03*
X736998Y1594463D03*
X730998D03*
X733998D03*
X736998Y1600463D03*
X730998D03*
X733998D03*
Y1603663D03*
X736998D03*
X733998Y1606663D03*
X736998D03*
X730998Y1603663D03*
Y1606663D03*
X744911Y166887D03*
X738880Y1582361D03*
Y1577231D03*
Y1587491D03*
X745998Y1597463D03*
X742998D03*
X745998Y1594463D03*
X742998D03*
X739998Y1597463D03*
Y1594463D03*
X745998Y1600463D03*
X742998D03*
X739998D03*
X745998Y1603663D03*
X742998D03*
X739998D03*
X745998Y1606663D03*
X742998D03*
X739998D03*
X749261Y1628208D03*
X754286Y266319D03*
X754291Y269322D03*
X756692Y278942D03*
X765285Y276374D03*
X761510Y1638434D03*
X762030Y1668583D03*
X755408Y1672381D03*
X757557Y1684444D03*
X773457Y249792D03*
X774485Y286879D03*
X779977Y1577233D03*
Y1582363D03*
Y1587493D03*
X779550Y1594533D03*
X782550D03*
X776550Y1597533D03*
Y1594533D03*
X779550Y1597533D03*
X782550D03*
Y1600533D03*
X776550D03*
X779550D03*
Y1606533D03*
X782550Y1603533D03*
X779550D03*
X776550Y1606533D03*
Y1603533D03*
X782550Y1606533D03*
X791341Y264848D03*
X784261Y1482049D03*
Y1534963D03*
X784277Y1528191D03*
X791077Y1577233D03*
X785577D03*
X791077Y1582363D03*
X785577Y1587493D03*
X791077D03*
X791550Y1597533D03*
X785550Y1594533D03*
X788550D03*
X791550D03*
X785550Y1597533D03*
X788550D03*
X785550Y1600533D03*
X788550D03*
X791550D03*
Y1606533D03*
X788550D03*
X785550D03*
X791550Y1603533D03*
X788550D03*
X785550D03*
X808469Y1356745D03*
Y1359245D03*
X811272Y1382752D03*
X811767Y1388154D03*
X821977Y1577233D03*
X827577D03*
X821977Y1582363D03*
Y1587493D03*
X827577D03*
X821550Y1594533D03*
X827550Y1597533D03*
Y1594533D03*
X824550Y1597533D03*
Y1594533D03*
X821550Y1597533D03*
Y1600533D03*
X827550D03*
X824550D03*
X815550Y1606533D03*
X818550D03*
X821550Y1603533D03*
X818550D03*
X827550Y1606533D03*
X824550D03*
X821550D03*
X827550Y1603533D03*
X824550D03*
X836163Y279355D03*
X833077Y1577233D03*
Y1582363D03*
Y1587493D03*
X830550Y1597533D03*
X833550D03*
X830550Y1594533D03*
X833550D03*
X830550Y1600533D03*
X833550D03*
X830550Y1603533D03*
X836550Y1606533D03*
Y1603533D03*
X833550D03*
X830550Y1606533D03*
X833550D03*
X856397Y344669D03*
X857550Y1606533D03*
X865132Y333317D03*
X860152D03*
X861377Y344669D03*
X869406Y753541D03*
X863977Y1577233D03*
Y1582363D03*
X869577Y1577233D03*
X863977Y1587493D03*
X869577D03*
X863550Y1597533D03*
X866550Y1594533D03*
Y1597533D03*
X869550Y1594533D03*
Y1597533D03*
X863550Y1594533D03*
X872550D03*
Y1597533D03*
X866550Y1600533D03*
X869550D03*
X863550D03*
X872550D03*
Y1606533D03*
Y1603533D03*
X863550Y1606533D03*
X866550D03*
X869550D03*
X860550D03*
X869550Y1603533D03*
X866550D03*
X863550D03*
X860550D03*
X874617Y1084657D03*
X877817D03*
Y1088057D03*
X874617D03*
X881217Y1084657D03*
Y1088057D03*
X874617Y1100957D03*
X877817D03*
Y1097557D03*
X874617D03*
X881217Y1100957D03*
Y1097557D03*
X875077Y1577233D03*
Y1582363D03*
Y1587493D03*
X875550Y1597533D03*
Y1594533D03*
Y1600533D03*
Y1606533D03*
X878550D03*
Y1603533D03*
X875550D03*
X889057Y1053133D03*
X897754Y1156119D03*
X899550Y1606533D03*
X902550Y1603533D03*
Y1606533D03*
X916268Y277859D03*
X905977Y1577233D03*
Y1582363D03*
X911577Y1577233D03*
X917077D03*
Y1582363D03*
X905977Y1587493D03*
X911577D03*
X917077D03*
X914550Y1597533D03*
Y1594533D03*
X905550D03*
X911550Y1597533D03*
Y1594533D03*
X908550Y1597533D03*
Y1594533D03*
X905550Y1597533D03*
X917550D03*
Y1594533D03*
X914550Y1600533D03*
X905550D03*
X911550D03*
X908550D03*
X917550D03*
X914550Y1603533D03*
Y1606533D03*
X905550Y1603533D03*
X908550D03*
X911550D03*
Y1606533D03*
X908550D03*
X905550D03*
X917550Y1603533D03*
Y1606533D03*
X928224Y264072D03*
X920550Y1603533D03*
Y1606533D03*
X942763Y272340D03*
X944820Y1156119D03*
X957421Y157699D03*
X960421D03*
X962243Y179917D03*
X947748Y1146553D03*
X964743Y179917D03*
X963985Y177154D03*
X965520Y1567570D03*
X962520D03*
X968520D03*
X965520Y1582570D03*
X962520D03*
Y1579570D03*
X965520D03*
Y1576570D03*
X962520D03*
X965520Y1573570D03*
X962520D03*
Y1570570D03*
X965520D03*
X968520Y1582570D03*
Y1579570D03*
Y1576570D03*
Y1573570D03*
Y1570570D03*
X965520Y1588570D03*
X962520D03*
Y1585570D03*
X965520D03*
X968520Y1588570D03*
Y1585570D03*
X991553Y216809D03*
X988460Y354725D03*
X992233Y373679D03*
X986356Y1087508D03*
X983156D03*
Y1084108D03*
X986356D03*
X989556Y1087508D03*
Y1084108D03*
X986356Y1097008D03*
X983156D03*
Y1100408D03*
X986356D03*
X989556Y1097008D03*
Y1100408D03*
X1002736Y157943D03*
X999736D03*
X993306Y174953D03*
X993206Y178053D03*
X1006436Y176843D03*
X999916Y184548D03*
X996416D03*
X992506Y184553D03*
X993460Y354725D03*
X998460D03*
X997488Y370287D03*
X994160Y1567710D03*
X997160D03*
X1000160D03*
X994160Y1582710D03*
X997160D03*
Y1579710D03*
X994160D03*
X997160Y1570710D03*
X994160D03*
Y1573710D03*
X997160D03*
X994160Y1576710D03*
X997160D03*
X1000160Y1582710D03*
Y1579710D03*
Y1570710D03*
Y1573710D03*
Y1576710D03*
X994160Y1588710D03*
X997160D03*
Y1585710D03*
X994160D03*
X1000160Y1588710D03*
Y1585710D03*
X1021899Y61590D03*
Y127590D03*
X1011358Y195324D03*
X1008068Y198387D03*
X1019936Y207333D03*
Y210463D03*
X1013306Y528942D03*
X1032354Y538201D03*
X1022686D03*
X1027520Y552724D03*
X1025750Y1567710D03*
X1031750D03*
X1028750D03*
X1025750Y1576710D03*
Y1573710D03*
Y1570710D03*
Y1579710D03*
Y1582710D03*
X1028750Y1576710D03*
Y1573710D03*
Y1570710D03*
Y1579710D03*
Y1582710D03*
X1031750Y1576710D03*
Y1573710D03*
Y1570710D03*
Y1579710D03*
Y1582710D03*
X1025750Y1585710D03*
Y1588710D03*
X1028750Y1585710D03*
Y1588710D03*
X1031750Y1585710D03*
Y1588710D03*
X1059055Y492537D03*
X1057219Y1567883D03*
X1060219D03*
X1063219D03*
X1066219D03*
X1057219Y1576883D03*
Y1573883D03*
Y1570883D03*
Y1579883D03*
Y1582883D03*
X1060219Y1576883D03*
Y1573883D03*
Y1570883D03*
Y1579883D03*
Y1582883D03*
X1063219Y1576883D03*
Y1573883D03*
Y1570883D03*
X1066219Y1576883D03*
Y1573883D03*
Y1570883D03*
Y1579883D03*
X1063219D03*
Y1582883D03*
X1066219D03*
X1057219Y1585883D03*
Y1588883D03*
X1060219Y1585883D03*
Y1588883D03*
X1066219Y1585883D03*
X1063219D03*
Y1588883D03*
X1066219D03*
X1094399Y1568043D03*
X1091399D03*
X1085399D03*
X1088399D03*
X1091399Y1580043D03*
X1094399D03*
Y1571043D03*
Y1574043D03*
Y1577043D03*
X1091399Y1571043D03*
Y1574043D03*
Y1577043D03*
X1088399Y1580043D03*
X1085399D03*
X1088399Y1571043D03*
X1085399D03*
Y1574043D03*
X1088399D03*
X1085399Y1577043D03*
X1088399D03*
X1094399Y1583043D03*
X1091399D03*
X1085399D03*
X1088399D03*
X1094399Y1589043D03*
X1091399D03*
Y1586043D03*
X1094399D03*
X1085399Y1589043D03*
X1088399D03*
Y1586043D03*
X1085399D03*
X1092030Y1715841D03*
Y1725991D03*
X1097399Y1568043D03*
Y1580043D03*
Y1571043D03*
Y1574043D03*
Y1577043D03*
Y1583043D03*
Y1589043D03*
Y1586043D03*
X1170986Y1519190D03*
X1168386Y1517280D03*
Y1512500D03*
Y1534300D03*
Y1539080D03*
X1170986Y1540990D03*
X1173586Y1517280D03*
Y1512500D03*
Y1534300D03*
Y1539080D03*
X1181361Y1543800D03*
Y1547420D03*
Y1551040D03*
X1172603Y1554561D03*
X1188472Y80165D03*
X1197980Y1688270D03*
X1213072Y1682899D03*
X1207770Y1717011D03*
Y1731011D03*
X1226094Y297066D03*
X1288494Y1519682D03*
Y1533082D03*
X1304705Y79807D03*
X1303266Y533713D03*
Y530413D03*
X1300200Y590600D03*
X1299048Y1519190D03*
X1296448Y1517280D03*
Y1512500D03*
X1301648Y1517280D03*
Y1512500D03*
X1296448Y1534300D03*
X1301648D03*
X1296448Y1539080D03*
X1301648D03*
X1299048Y1540990D03*
X1309185Y74748D03*
X1316266Y564514D03*
X1317266Y589522D03*
X1318300Y640000D03*
Y643000D03*
Y649000D03*
Y646000D03*
X1318363Y1411404D03*
X1312700Y1579596D03*
X1319349Y1585567D03*
X1330820Y525165D03*
X1330758Y521749D03*
X1330820Y518265D03*
X1330658Y538749D03*
X1330758Y528649D03*
X1330773Y531776D03*
X1330758Y535449D03*
X1329673Y552509D03*
X1332673D03*
X1326673Y544909D03*
X1329673Y545909D03*
Y549309D03*
X1330658Y542949D03*
X1332673Y545909D03*
Y549309D03*
X1329673Y558709D03*
Y555709D03*
X1332673D03*
X1325366Y589522D03*
X1321300Y643000D03*
Y640000D03*
Y649000D03*
Y646000D03*
X1326433Y1214334D03*
X1335260Y236594D03*
Y246594D03*
Y241594D03*
Y251594D03*
X1348611Y1212963D03*
Y1218463D03*
X1364239Y1207949D03*
X1391460Y1032205D03*
X1388918Y1687878D03*
X1382045Y1712038D03*
Y1708038D03*
X1384604Y1728318D03*
X1393179Y1733118D03*
X1404917Y109037D03*
X1395060Y1009764D03*
Y1006024D03*
Y1013504D03*
Y1020985D03*
Y1024725D03*
Y1028465D03*
Y1017244D03*
X1397955Y1582178D03*
X1405058Y1639607D03*
X1417301Y1055140D03*
X1416556Y1519682D03*
Y1533082D03*
X1418740Y1622902D03*
X1427973Y60409D03*
X1438507Y1006024D03*
Y1009764D03*
Y1013504D03*
Y1024725D03*
Y1020985D03*
Y1017244D03*
Y1028465D03*
Y1032205D03*
X1435160Y1519190D03*
X1432560Y1517280D03*
Y1512500D03*
X1437760Y1517280D03*
Y1512500D03*
X1432560Y1534300D03*
X1437760D03*
X1432560Y1539080D03*
X1437760D03*
X1435160Y1540990D03*
X1433979Y1655655D03*
X1441141Y53699D03*
X1448505Y1579725D03*
X1455461Y1585567D03*
X1528993Y4115D03*
Y26115D03*
X1534067Y1582178D03*
X1552668Y1519682D03*
Y1533082D03*
X1568176Y568423D03*
X1570676D03*
X1565676D03*
X1561376Y572258D03*
X1566010Y673210D03*
X1562730Y675180D03*
X1563222Y1519190D03*
X1560622Y1517280D03*
Y1512500D03*
X1565822Y1517280D03*
Y1512500D03*
X1560622Y1534300D03*
X1565822D03*
X1560622Y1539080D03*
X1565822D03*
X1563222Y1540990D03*
X1586291Y306746D03*
X1584160Y558973D03*
X1576653Y1579333D03*
X1583523Y1585567D03*
X1606535Y553297D03*
X1607369Y561330D03*
X1631889Y521480D03*
X1618884Y533388D03*
X1632798Y544564D03*
X1622391Y564169D03*
X1627242Y1436148D03*
X1627181Y1448016D03*
X1636929Y524690D03*
Y528190D03*
Y531690D03*
Y535190D03*
Y538690D03*
X1639868Y542444D03*
X1636783Y542604D03*
X1635798Y545564D03*
X1638798D03*
Y548964D03*
Y552164D03*
X1635798D03*
Y548964D03*
Y555364D03*
X1638798D03*
X1635798Y558364D03*
X1648029Y1718759D03*
Y1733909D03*
X1652525Y141762D03*
X1662129Y1582178D03*
X1673100Y126762D03*
X1676971Y1668582D03*
X1686154Y434160D03*
X1685298Y1451231D03*
X1680730Y1519682D03*
Y1533082D03*
X1688243Y1663802D03*
X1682724Y1717701D03*
X1704444Y407045D03*
X1707444D03*
X1697914Y427155D03*
X1698014Y424055D03*
X1701124Y433650D03*
X1697214Y433655D03*
X1704624Y433650D03*
X1704822Y1694243D03*
X1702985Y1700328D03*
X1711144Y425945D03*
X1722149Y1715265D03*
X1719149Y1703190D03*
X1722149Y1730415D03*
X1724263Y1681465D03*
X1752250Y303850D03*
X1749329Y1662956D03*
X1743329Y1668956D03*
X1743153Y1662956D03*
X1749329Y1674956D03*
X1743329D03*
X1754850Y303930D03*
X1755329Y1668956D03*
Y1662956D03*
Y1674956D03*
X1763463Y1691465D03*
X1758963Y1691565D03*
X1787390Y161834D03*
X1800040Y164393D03*
X1797719Y186610D03*
X1811668Y218900D03*
X1811606Y222513D03*
X1808429Y218837D03*
X1811606Y226438D03*
X1808367Y222450D03*
X1810479Y211850D03*
X1810509Y214660D03*
X1808260Y213232D03*
X1808367Y226375D03*
X1825111Y164393D03*
X1813079Y211850D03*
X1813109Y214660D03*
G54D17*
X18960Y1598181D03*
X440029Y240381D03*
X434420Y239930D03*
X934302Y578318D03*
X1769420Y19506D03*
X1777420D03*
Y24506D03*
G54D19*
X35852Y673010D03*
Y675510D03*
Y697322D03*
Y694822D03*
Y705728D03*
X50138Y425810D03*
X45182D03*
X45022Y449106D03*
X50002D03*
X48626Y552365D03*
X50880Y1412563D03*
X51358Y1647717D03*
Y1650217D03*
X52052Y1684027D03*
X67257Y69340D03*
X62930Y282866D03*
Y312866D03*
X62833Y409597D03*
X62808Y418675D03*
X65380Y427810D03*
X60393D03*
X58349Y1403331D03*
X54449Y1641722D03*
X61415Y1661695D03*
X61374Y1669931D03*
X70127Y1687362D03*
X73015Y28406D03*
X80101D03*
X73015Y40020D03*
X80101D03*
X78253Y75343D03*
X74773Y790297D03*
Y800336D03*
Y827108D03*
Y837147D03*
Y863919D03*
Y873958D03*
Y900730D03*
Y910769D03*
Y937541D03*
Y947580D03*
Y1084785D03*
Y1094824D03*
Y1121596D03*
Y1131635D03*
Y1158407D03*
Y1168446D03*
Y1195218D03*
Y1205257D03*
Y1232029D03*
Y1242068D03*
X71511Y1444379D03*
X69486Y1661828D03*
X69589Y1669878D03*
X78127Y1687362D03*
X74127D03*
X94274Y28406D03*
X87188D03*
Y40020D03*
X94274D03*
X89257Y69340D03*
X90150Y1314560D03*
X86127Y1687362D03*
X92192Y1713741D03*
X92596Y1737117D03*
X108448Y28406D03*
X101361D03*
Y40020D03*
X108448D03*
X100257Y75340D03*
X111257Y69340D03*
X104474Y790297D03*
Y800336D03*
Y827108D03*
Y837147D03*
Y863919D03*
Y873958D03*
Y900730D03*
Y910769D03*
Y937541D03*
Y947580D03*
Y1084785D03*
Y1094824D03*
Y1121596D03*
Y1131635D03*
Y1158407D03*
Y1168446D03*
Y1195218D03*
Y1205257D03*
Y1232029D03*
Y1242068D03*
X112355Y1426064D03*
Y1433564D03*
Y1441064D03*
X110144Y1597831D03*
X110996Y1592018D03*
X122621Y28406D03*
X115534D03*
Y40020D03*
X122621D03*
X122257Y75340D03*
X119855Y1426064D03*
X127355Y1433564D03*
Y1426064D03*
X119855Y1441064D03*
X127355D03*
X127374Y1572749D03*
X127392Y1575524D03*
X125768Y1568744D03*
X127246Y1585801D03*
X127264Y1588576D03*
X113496Y1592018D03*
X116353Y1646612D03*
X120353D03*
X124353D03*
X123278Y1658587D03*
X119353Y1695941D03*
X115353D03*
X125107Y1702666D03*
X124461Y1726116D03*
X114596Y1737117D03*
X129708Y28406D03*
Y40020D03*
X133257Y69343D03*
X141642Y491434D03*
X134174Y790297D03*
Y800336D03*
Y837147D03*
Y827108D03*
Y863919D03*
Y873958D03*
Y900730D03*
Y910769D03*
Y937541D03*
Y947580D03*
Y1084785D03*
Y1094824D03*
Y1121596D03*
Y1131635D03*
Y1158407D03*
Y1168446D03*
Y1195218D03*
Y1205257D03*
Y1232029D03*
Y1242068D03*
X128617Y1561022D03*
X129892Y1575524D03*
X129874Y1572749D03*
X128268Y1568744D03*
X129764Y1588576D03*
X129746Y1585801D03*
X128353Y1646612D03*
X140353D03*
X136048Y1666851D03*
X133548Y1677351D03*
X131353Y1696062D03*
X135353D03*
X139353D03*
X136596Y1737117D03*
X151400Y28406D03*
Y40020D03*
X144257Y75340D03*
X155253Y69343D03*
X148353Y1646612D03*
X144353D03*
X155328Y1670087D03*
X146928Y1685087D03*
X143353Y1696062D03*
X158487Y28406D03*
X165574D03*
X158487Y40020D03*
X165574D03*
X167461Y75340D03*
X163875Y790297D03*
Y800336D03*
Y837147D03*
Y827108D03*
Y863919D03*
Y873958D03*
Y900730D03*
Y910769D03*
Y937541D03*
Y947580D03*
Y1084785D03*
Y1094824D03*
Y1121596D03*
Y1131635D03*
Y1158407D03*
Y1168446D03*
Y1195218D03*
Y1205257D03*
Y1232029D03*
Y1242068D03*
X163421Y1425171D03*
Y1427671D03*
Y1430171D03*
Y1432671D03*
X158596Y1737117D03*
X172660Y28406D03*
X179747D03*
X172660Y40020D03*
X179747D03*
X178461Y69340D03*
X173960Y400560D03*
X172721Y1425171D03*
Y1430171D03*
Y1427671D03*
Y1432671D03*
X175351Y1462595D03*
X182051Y1452895D03*
X181760Y1731351D03*
X180596Y1737117D03*
X195534Y28406D03*
Y40020D03*
X189457Y75343D03*
X200461Y69340D03*
X193576Y790297D03*
Y800336D03*
Y827108D03*
Y837147D03*
Y863919D03*
Y873958D03*
Y900730D03*
Y910769D03*
Y937541D03*
Y947580D03*
Y1084785D03*
Y1094824D03*
Y1121596D03*
Y1131635D03*
Y1158407D03*
Y1168446D03*
Y1205257D03*
Y1195218D03*
Y1232029D03*
Y1242068D03*
X202151Y1462595D03*
X195451Y1472295D03*
X202621Y28406D03*
X216794D03*
X209708D03*
X202621Y40020D03*
X209708D03*
X216794D03*
X211595Y75340D03*
X208851Y1452895D03*
X202596Y1737117D03*
X223881Y28406D03*
X230967D03*
X223881Y40020D03*
X230967D03*
X222591Y69343D03*
X223277Y790297D03*
Y800336D03*
Y837147D03*
Y827108D03*
Y863919D03*
Y873958D03*
Y900730D03*
Y910769D03*
Y937541D03*
Y947580D03*
Y1084785D03*
Y1094824D03*
Y1121596D03*
Y1131635D03*
Y1158407D03*
Y1168446D03*
Y1205257D03*
Y1195218D03*
Y1232029D03*
Y1242068D03*
X228951Y1462595D03*
X222251Y1472295D03*
X224596Y1737117D03*
X233595Y75340D03*
X242215Y151788D03*
X234727Y584030D03*
Y571211D03*
X245815Y672746D03*
X244565Y677846D03*
Y680446D03*
Y675246D03*
X242543Y691115D03*
X239443Y691015D03*
X239843Y709715D03*
X235651Y1452895D03*
X252996Y28365D03*
X256496D03*
X249496D03*
X259996D03*
X252195Y144320D03*
X259475Y657245D03*
X259426Y644830D03*
X259475Y662845D03*
X250312Y670080D03*
Y667180D03*
X250835Y672692D03*
X253279Y672708D03*
X258379Y666644D03*
Y669601D03*
Y672708D03*
X255779D03*
X260979Y666644D03*
Y669601D03*
Y672708D03*
X247165Y677846D03*
Y680446D03*
Y675246D03*
X254448Y692050D03*
X255751Y1462595D03*
X249051Y1472295D03*
X266601Y586578D03*
X271571Y644796D03*
X264335Y657245D03*
X261905D03*
Y662845D03*
X264335D03*
X263579Y669601D03*
X266179D03*
Y672708D03*
X263579D03*
X270857Y668515D03*
X263839Y692049D03*
X275851Y1452895D03*
X262451D03*
X266596Y1737117D03*
X278979Y28406D03*
X286066D03*
X279273Y99186D03*
X289553Y121806D03*
X291109Y700885D03*
X283062Y700979D03*
X279895Y709487D03*
X283565Y706933D03*
X286009Y706949D03*
X278545Y706987D03*
X279895Y712087D03*
Y714687D03*
X291109Y703842D03*
Y706949D03*
X288509D03*
X277295Y709487D03*
Y712087D03*
Y714687D03*
X283062Y703936D03*
X277055Y722649D03*
X279171Y724988D03*
X281992Y1342705D03*
X292705Y580275D03*
X292156Y679071D03*
X304301Y679037D03*
X292205Y691486D03*
X297065D03*
X294635D03*
X293709Y700885D03*
X297065Y697086D03*
X303657Y702815D03*
X292205Y697086D03*
X294635D03*
X293709Y703842D03*
Y706949D03*
X298909Y703842D03*
Y706949D03*
X296309Y703842D03*
Y706949D03*
X303413Y1462595D03*
X315912Y721039D03*
Y723996D03*
X321279Y727099D03*
X312665Y729637D03*
Y732237D03*
X310065Y729637D03*
Y732237D03*
X316335Y727083D03*
X311315Y727137D03*
X318779Y727099D03*
X313255Y746279D03*
X312665Y734837D03*
X310065D03*
X310113Y1452895D03*
X312596Y1737117D03*
X328966Y548030D03*
X324926Y699221D03*
X329835Y711636D03*
X324975D03*
X329835Y717236D03*
X327405Y711636D03*
X324975Y717236D03*
X327405D03*
X326479Y721035D03*
X323879D03*
Y727099D03*
X326479D03*
X329079D03*
X331679D03*
X323879Y723992D03*
X326479D03*
X329079D03*
X331679D03*
X330213Y1462595D03*
X323513Y1472295D03*
X334596Y1737117D03*
X350817Y558248D03*
X343182Y586415D03*
Y591335D03*
X348449Y720827D03*
Y723784D03*
X345725Y729369D03*
X343125D03*
X345725Y731969D03*
X343125D03*
X344375Y726869D03*
X349395Y726815D03*
X336457Y722815D03*
X339825Y746269D03*
X342425D03*
X349625D03*
X345725Y734569D03*
X343125D03*
X336913Y1452895D03*
X350313Y1472295D03*
X352418Y225329D03*
Y222329D03*
X355733Y275059D03*
X357986Y698953D03*
X362895Y716968D03*
X360465Y711368D03*
X362895D03*
X358035D03*
Y716968D03*
X360465D03*
X359539Y720767D03*
X356939D03*
X351839Y726831D03*
X354339D03*
X356939D03*
X362139D03*
X359539D03*
X364739D03*
X356939Y723724D03*
X362139D03*
X359539D03*
X364739D03*
X352225Y746269D03*
X360025D03*
X362625D03*
X352943Y1214510D03*
X363713Y1452895D03*
X357013Y1462595D03*
X356596Y1737117D03*
X379023Y225149D03*
X371318Y218629D03*
X379023Y228649D03*
X379028Y232559D03*
X369428Y231759D03*
X372528Y231859D03*
X369171Y562380D03*
X376671D03*
X369100Y577400D03*
X369171Y569880D03*
X376600Y577400D03*
X376165Y729437D03*
X378765D03*
X376165Y732037D03*
X378765D03*
X377415Y726937D03*
X369557Y722615D03*
X373425Y746169D03*
X370825D03*
X376165Y734637D03*
X378765D03*
X367836Y1209506D03*
X377190Y1387697D03*
X377113Y1472295D03*
X393287Y-9234D03*
X391635Y161091D03*
X384259Y562426D03*
X384301Y577446D03*
X385443Y597279D03*
X391026Y699021D03*
X395935Y717036D03*
Y711436D03*
X393505D03*
X391075D03*
Y717036D03*
X393505D03*
X392579Y720835D03*
X389979D03*
X381802Y720789D03*
Y723746D03*
X387379Y726899D03*
X384879D03*
X389979D03*
Y723792D03*
X382435Y726883D03*
X392579Y726899D03*
X395179D03*
X392579Y723792D03*
X395179D03*
X389981Y1015474D03*
Y1022560D03*
Y1019017D03*
X383813Y1462595D03*
X390513Y1452895D03*
X406243Y100076D03*
X402184Y507101D03*
X403133Y565415D03*
X403157Y569415D03*
X410415Y709137D03*
X409165Y711637D03*
Y714237D03*
Y716837D03*
X397779Y726899D03*
Y723792D03*
X402457Y722615D03*
X397461Y1015474D03*
X404941D03*
X397461Y1022560D03*
X404941Y1019017D03*
Y1022560D03*
X397461Y1019017D03*
X403913Y1452895D03*
X417617Y79073D03*
X423376Y96664D03*
X411952Y132751D03*
Y123051D03*
X422936Y228147D03*
Y232793D03*
X420288Y244184D03*
X415984Y507024D03*
X424026Y681221D03*
X424075Y693636D03*
X425579Y703035D03*
X422979D03*
X424075Y699236D03*
X414682Y703139D03*
X411765Y711637D03*
Y714237D03*
Y716837D03*
X415435Y709083D03*
X417879Y709099D03*
X425579D03*
X422979D03*
X420379D03*
X425579Y705992D03*
X422979D03*
X414682Y706096D03*
X423811Y1009400D03*
Y1028831D03*
X417098Y1533764D03*
Y1531264D03*
X422596Y1737117D03*
X429685Y88657D03*
X436090Y116007D03*
Y124007D03*
Y132007D03*
X440591Y684518D03*
X436130Y683281D03*
X426505Y693636D03*
X428935D03*
Y699236D03*
X426505D03*
X430779Y709099D03*
Y705992D03*
X428179Y709099D03*
Y705992D03*
X435457Y704915D03*
X439411Y733527D03*
X436811D03*
X439411Y736147D03*
X436811D03*
X436411Y738717D03*
X439011D03*
X436411Y743917D03*
X439011D03*
X436411Y741317D03*
X439011D03*
X431291Y1009400D03*
X438316Y1014745D03*
X427551Y1009400D03*
X435031D03*
X438771D03*
X428473Y1014745D03*
X438771Y1028831D03*
X438316Y1023013D03*
X427551Y1028831D03*
X435031D03*
X438316Y1018879D03*
X428473D03*
Y1023013D03*
X431291Y1028831D03*
X427251Y1291747D03*
X439524Y1462595D03*
X448090Y116007D03*
X444090Y132007D03*
X452480Y273420D03*
X441320Y298170D03*
X452565Y652837D03*
X455379Y678435D03*
X450279Y684499D03*
X455379D03*
X452779D03*
X455379Y681392D03*
X444165Y687037D03*
X441565D03*
X443235Y684637D03*
X447835Y684483D03*
X447162Y678409D03*
Y681366D03*
X444325Y702449D03*
X441725D03*
X444165Y689637D03*
Y692237D03*
X441565D03*
Y689637D03*
X446591Y716837D03*
X443991D03*
X446591Y719437D03*
X443991D03*
X441959Y993766D03*
Y997766D03*
X442034Y989766D03*
X442511Y1009400D03*
X449992D03*
X446252D03*
X453732D03*
X441959Y1001766D03*
X447174Y1014745D03*
X446252Y1028831D03*
X453732D03*
X449992D03*
X447174Y1023013D03*
X442511Y1028831D03*
X447174Y1018879D03*
X446224Y1452895D03*
X444596Y1737117D03*
X463402Y229970D03*
X457731Y237588D03*
X463653Y237390D03*
X462703Y242342D03*
X467644Y353417D03*
X469046Y657062D03*
X456426Y656621D03*
X458905Y669036D03*
X456475D03*
X461335D03*
X457979Y678435D03*
X460579Y684499D03*
X457979D03*
X460579Y681392D03*
X457979D03*
X467957Y680315D03*
X463179Y684499D03*
Y681392D03*
X461335Y674636D03*
X456475D03*
X458905D03*
X457472Y1009400D03*
X457410Y1014745D03*
Y1018879D03*
Y1023013D03*
X457472Y1028831D03*
X466324Y1462595D03*
X459624Y1472295D03*
X466596Y1737117D03*
X486682Y197516D03*
X483800Y270440D03*
X475415Y658037D03*
X482879Y657999D03*
X480435Y657983D03*
X485379Y657999D03*
X479822Y651989D03*
Y654946D03*
X476765Y660537D03*
X474165D03*
X476765Y663137D03*
X474165D03*
X476765Y665737D03*
X474165D03*
X473024Y1452895D03*
X495232Y189516D03*
X486600Y200800D03*
X495232Y197516D03*
X491635Y212577D03*
X487541Y226527D03*
X488076Y350420D03*
X501171Y630087D03*
X493935Y642536D03*
X489075D03*
X491505D03*
X489026Y630121D03*
X493935Y648136D03*
X487979Y651935D03*
X490579D03*
X493179Y654892D03*
Y657999D03*
X487979Y654892D03*
X490579D03*
Y657999D03*
X487979D03*
X495779Y654892D03*
Y657999D03*
X489075Y648136D03*
X491505D03*
X499824Y1452895D03*
X493124Y1462595D03*
X486424Y1472295D03*
X488596Y1737117D03*
X510810Y49193D03*
X510065Y626437D03*
X508715Y623937D03*
X507465Y626437D03*
X513735Y623883D03*
X513012Y620706D03*
Y617749D03*
X510065Y629037D03*
X507465D03*
X510065Y631637D03*
X507465D03*
X514771Y643138D03*
X500457Y653715D03*
X513224Y1472295D03*
X517915Y42257D03*
X525001D03*
X517896Y49193D03*
X524763Y49189D03*
X522418Y137171D03*
X526418D03*
X517973Y211998D03*
X522326Y596021D03*
X524805Y608436D03*
X522375D03*
X527235D03*
X526479Y620792D03*
Y623899D03*
X523879Y620792D03*
X521279D03*
X523879Y623899D03*
X521279D03*
X518679D03*
X516179D03*
X529079Y620792D03*
Y623899D03*
X523879Y617835D03*
X521279D03*
X527235Y614036D03*
X522375D03*
X524805D03*
X521771Y643138D03*
X528771D03*
X519924Y1462595D03*
X526624Y1452895D03*
X532070Y49193D03*
X539156D03*
X530418Y137171D03*
X541013Y222441D03*
X534471Y595987D03*
X533857Y619615D03*
X534271Y643138D03*
X540024Y1452895D03*
X532596Y1737117D03*
X557091Y114382D03*
X550505D03*
X553100Y227700D03*
X551200Y377650D03*
X551171Y1167678D03*
X554596Y1737117D03*
X564431Y45132D03*
X562475Y242721D03*
X571271Y1259488D03*
X567586Y1462595D03*
X574286Y1452895D03*
X578621Y45112D03*
X585296Y222954D03*
X586000Y808862D03*
X578830Y1218588D03*
X585501Y1229536D03*
X587686Y1472295D03*
X576596Y1737117D03*
X595682Y44842D03*
X603064Y44523D03*
X599284Y32866D03*
X593920Y49193D03*
X600793Y193185D03*
X596661Y188775D03*
X590300Y190660D03*
X595563Y239128D03*
X603283Y419744D03*
X597071Y799268D03*
X592761Y1220688D03*
X594386Y1462595D03*
X601086Y1452895D03*
X598596Y1737117D03*
X618427Y43432D03*
X615180Y49193D03*
X618600Y160750D03*
X613207Y182229D03*
X615464Y347522D03*
X607871Y359262D03*
X613761Y790418D03*
X605771Y1267098D03*
X614486Y1472295D03*
X624937Y44019D03*
X620390Y36794D03*
X630900Y118920D03*
X632695Y1366157D03*
Y1372257D03*
Y1378257D03*
X627886Y1452895D03*
X621186Y1462595D03*
X620596Y1737117D03*
X648487Y44106D03*
X638695Y1366157D03*
X644795D03*
X643395Y1372857D03*
X638695Y1378257D03*
X644795D03*
X647986Y1462595D03*
X641286Y1472295D03*
X642596Y1737117D03*
X654590Y49193D03*
X661676D03*
X652804Y790297D03*
Y800336D03*
Y837147D03*
Y827108D03*
Y863919D03*
Y873958D03*
Y900730D03*
Y910769D03*
Y937541D03*
Y947580D03*
Y1084785D03*
Y1094824D03*
Y1121596D03*
Y1131635D03*
Y1158407D03*
Y1168446D03*
Y1205257D03*
Y1195218D03*
Y1232029D03*
Y1242068D03*
X661685Y1367283D03*
X654686Y1452895D03*
X662153Y1727718D03*
X675849Y49193D03*
X668763D03*
X668086Y1452895D03*
X664596Y1737117D03*
X682505Y790297D03*
Y800336D03*
Y837147D03*
Y827108D03*
Y863919D03*
Y873958D03*
Y900730D03*
Y910769D03*
Y937541D03*
Y947580D03*
Y1084785D03*
Y1094824D03*
Y1121596D03*
Y1131635D03*
Y1158407D03*
Y1168446D03*
Y1205257D03*
Y1195218D03*
Y1232029D03*
Y1242068D03*
X688540Y1455140D03*
X697400Y345761D03*
X697300Y1454140D03*
X722581Y49182D03*
X713420Y102060D03*
X712206Y790297D03*
Y800336D03*
Y827108D03*
Y837147D03*
Y863919D03*
Y873958D03*
Y900730D03*
Y910769D03*
Y937541D03*
Y947580D03*
Y1084785D03*
Y1094824D03*
Y1121596D03*
Y1131635D03*
Y1158407D03*
Y1168446D03*
Y1195218D03*
Y1205257D03*
Y1232029D03*
Y1242068D03*
X731743Y-30584D03*
X734996Y-30570D03*
X731758Y-28069D03*
X735011Y-28055D03*
X728718Y-29264D03*
X735041Y-23025D03*
X735026Y-25540D03*
X731555Y83685D03*
X737009Y83169D03*
X724134Y141288D03*
X728500Y533862D03*
X736500D03*
X732500D03*
X738260Y553625D03*
X747637Y534874D03*
X740638Y549900D03*
X741907Y790297D03*
Y800336D03*
Y827108D03*
Y837147D03*
Y863919D03*
Y873958D03*
Y900730D03*
Y910769D03*
Y937541D03*
Y947580D03*
Y1084785D03*
Y1094824D03*
Y1121596D03*
Y1131635D03*
Y1158407D03*
Y1168446D03*
Y1195218D03*
Y1205257D03*
Y1232029D03*
Y1242068D03*
X751521Y1659158D03*
X752596Y1737117D03*
X762199Y126684D03*
Y129684D03*
X758111Y172636D03*
X762300Y188910D03*
X764500Y534424D03*
X760500Y534352D03*
X781242Y489574D03*
X771608Y790297D03*
Y800336D03*
Y837147D03*
Y827108D03*
Y863919D03*
Y873958D03*
Y900730D03*
Y910769D03*
Y937541D03*
Y947580D03*
Y1084785D03*
Y1094824D03*
Y1121596D03*
Y1131635D03*
Y1158407D03*
Y1168446D03*
Y1195218D03*
Y1205257D03*
Y1232029D03*
Y1242068D03*
X778030Y1310259D03*
X780530D03*
X773974Y1731920D03*
X796333Y439344D03*
X786030Y1310259D03*
X794030D03*
X796530D03*
X788530D03*
X791823Y1527404D03*
X795926Y1731918D03*
X807451Y763765D03*
X801308Y790297D03*
Y800336D03*
Y837147D03*
Y827108D03*
Y863919D03*
Y873958D03*
Y900730D03*
Y910769D03*
Y937541D03*
Y947580D03*
Y1084785D03*
Y1094824D03*
Y1121596D03*
Y1131635D03*
Y1158407D03*
Y1168446D03*
Y1195218D03*
Y1205257D03*
Y1232029D03*
Y1242068D03*
X802030Y1310259D03*
X804530D03*
X807601Y1307191D03*
X810246Y1351988D03*
X817974Y1731920D03*
X839974D03*
X844766Y-15374D03*
Y-5374D03*
Y24626D03*
X849711Y212062D03*
X845221Y216532D03*
X854707Y229878D03*
X852207D03*
X874295Y163862D03*
X863488Y176332D03*
X861974Y1731920D03*
X883974D03*
X898000Y1112336D03*
Y1109736D03*
Y1116544D03*
Y1119144D03*
Y1130160D03*
Y1132760D03*
Y1123352D03*
Y1125952D03*
X916880Y1138969D03*
X906473Y1158574D03*
X903980Y1268420D03*
X904024Y1272692D03*
X903947Y1276968D03*
X903899Y1281203D03*
X903945Y1285420D03*
X903923Y1289630D03*
X903651Y1293853D03*
X903690Y1298027D03*
X905974Y1731920D03*
X921477Y1134647D03*
X925525Y1135172D03*
X919880Y1146569D03*
Y1139969D03*
Y1143369D03*
Y1149769D03*
X922880Y1146569D03*
Y1139969D03*
Y1143369D03*
Y1149769D03*
X919077Y1136521D03*
X923125Y1137046D03*
X919880Y1152769D03*
X928751Y1266347D03*
X928901Y1270408D03*
X928852Y1274591D03*
X928979Y1278713D03*
X928827Y1283048D03*
X928928Y1287193D03*
X928906Y1291676D03*
X928983Y1295957D03*
X927974Y1731920D03*
X935497Y195925D03*
Y210098D03*
Y203012D03*
Y224272D03*
Y217185D03*
Y231358D03*
X935783Y634051D03*
X941000Y1110557D03*
Y1107957D03*
Y1117557D03*
Y1114957D03*
Y1124557D03*
Y1121957D03*
Y1131557D03*
Y1128957D03*
X953498Y1158574D03*
X949974Y1731920D03*
X967315Y1135550D03*
X972109Y1135149D03*
X966905Y1146569D03*
X969905D03*
X966905Y1139969D03*
Y1143369D03*
X969905Y1139969D03*
Y1143369D03*
X966905Y1149769D03*
X969905D03*
X963012Y1139511D03*
X964915Y1137424D03*
X969709Y1137023D03*
X966905Y1152769D03*
X968594Y1288193D03*
X971974Y1731920D03*
X991031Y528574D03*
X998056Y518214D03*
Y523874D03*
X999031Y528574D03*
X999894Y1267126D03*
X993974Y1731920D03*
X1021220Y243638D03*
X1012220D03*
X1007669Y268884D03*
Y258222D03*
X1007587Y767480D03*
Y769980D03*
Y780880D03*
Y778380D03*
Y789484D03*
Y791984D03*
X1010894Y1271743D03*
X1010865Y1275768D03*
X1010944Y1279751D03*
X1010650Y1310500D03*
X1015974Y1731920D03*
X1025493Y758819D03*
X1044012Y268659D03*
X1051495Y265133D03*
X1040097Y529508D03*
X1050915Y790296D03*
Y800335D03*
Y827107D03*
Y837146D03*
Y863918D03*
Y873957D03*
Y910768D03*
Y900729D03*
Y937540D03*
Y947579D03*
Y1084784D03*
Y1094823D03*
Y1131634D03*
Y1121595D03*
Y1158406D03*
Y1168445D03*
Y1205256D03*
Y1195217D03*
Y1232028D03*
Y1242067D03*
X1037974Y1731920D03*
X1054355Y258698D03*
X1065552Y271441D03*
X1056517Y512787D03*
X1061837Y519703D03*
X1060721Y1313954D03*
X1061974Y1731920D03*
X1080616Y790296D03*
Y800335D03*
Y827107D03*
Y837146D03*
Y863918D03*
Y873957D03*
Y910768D03*
Y900729D03*
Y937540D03*
Y947579D03*
Y1084784D03*
Y1094823D03*
Y1131634D03*
Y1121595D03*
Y1158406D03*
Y1168445D03*
Y1205256D03*
Y1195217D03*
Y1232028D03*
Y1242067D03*
X1081857Y269856D03*
X1089030Y1691229D03*
X1092980Y1696029D03*
X1095489Y1708519D03*
X1081974Y1731920D03*
X1110316Y790296D03*
Y800335D03*
Y827107D03*
Y837146D03*
Y863918D03*
Y873957D03*
Y910768D03*
Y900729D03*
Y937540D03*
Y947579D03*
Y1084784D03*
Y1094823D03*
Y1131634D03*
Y1121595D03*
Y1158406D03*
Y1168445D03*
Y1205256D03*
Y1195217D03*
Y1232028D03*
Y1242067D03*
X1103351Y1737117D03*
X1112001Y1718991D03*
X1125351Y1737117D03*
X1140017Y790296D03*
Y800335D03*
Y827107D03*
Y837146D03*
Y863918D03*
Y873957D03*
Y910768D03*
Y900729D03*
Y937540D03*
Y947579D03*
Y1084784D03*
Y1094823D03*
Y1131634D03*
Y1121595D03*
Y1158406D03*
Y1168445D03*
Y1205256D03*
Y1195217D03*
Y1232028D03*
Y1242067D03*
X1169718Y790296D03*
Y800335D03*
Y837146D03*
Y827107D03*
Y863918D03*
Y873957D03*
Y900729D03*
Y910768D03*
Y937540D03*
Y947579D03*
Y1084784D03*
Y1094823D03*
Y1121595D03*
Y1131634D03*
Y1158406D03*
Y1168445D03*
Y1205256D03*
Y1195217D03*
Y1232028D03*
Y1242067D03*
X1183050Y-20074D03*
Y-10074D03*
Y-74D03*
Y9926D03*
X1183224Y1495595D03*
X1186312Y-20074D03*
Y-10074D03*
Y-74D03*
Y9926D03*
X1200037Y164987D03*
Y160987D03*
X1189727Y177187D03*
X1200012Y185187D03*
X1199419Y790296D03*
Y800335D03*
Y837146D03*
Y827107D03*
Y863918D03*
Y873957D03*
Y900729D03*
Y910768D03*
Y937540D03*
Y947579D03*
Y1084784D03*
Y1094823D03*
Y1121595D03*
Y1131634D03*
Y1158406D03*
Y1168445D03*
Y1195217D03*
Y1205256D03*
Y1232028D03*
Y1242067D03*
X1189924Y1485895D03*
X1199612Y1700334D03*
X1199294Y1721143D03*
X1191351Y1737117D03*
X1215581Y91346D03*
X1202711Y87651D03*
X1215581Y94846D03*
X1213355Y1412564D03*
Y1427564D03*
Y1420064D03*
X1203324Y1505295D03*
X1210024Y1495595D03*
X1214954Y1700343D03*
X1204447Y1707143D03*
X1213351Y1737117D03*
X1223455Y91346D03*
X1230312Y88635D03*
X1215931Y141530D03*
X1218431D03*
X1231118Y142125D03*
X1228355Y1412564D03*
X1220855D03*
X1228355Y1427564D03*
Y1420064D03*
X1220855Y1427564D03*
X1216724Y1485895D03*
X1230124Y1505295D03*
X1235546Y75293D03*
X1232812Y88635D03*
X1239218Y128239D03*
Y137239D03*
Y132739D03*
Y123739D03*
X1238094Y280573D03*
X1233345Y300157D03*
X1242429Y443255D03*
Y447255D03*
X1243524Y1485895D03*
X1236824Y1495595D03*
X1235351Y1737117D03*
X1248286Y-15374D03*
Y-25374D03*
Y14626D03*
X1252561Y72675D03*
X1255185Y140053D03*
Y142553D03*
X1255175Y137553D03*
X1246094Y280573D03*
X1246748Y785752D03*
X1258121Y1342686D03*
X1256924Y1505295D03*
X1257351Y1737117D03*
X1270324Y1485895D03*
X1263624Y1495595D03*
X1278677Y808988D03*
X1283724Y1485895D03*
X1279351Y1737117D03*
X1295532Y539513D03*
X1301666Y555413D03*
X1301351Y1737117D03*
X1319667Y87587D03*
Y105227D03*
X1307857Y111353D03*
X1317986Y1485895D03*
X1311286Y1495595D03*
X1333878Y637721D03*
X1331386Y1505295D03*
X1323351Y1737117D03*
X1344958Y85358D03*
X1336558Y637721D03*
X1339238D03*
X1344438D03*
X1341838D03*
X1344786Y1485895D03*
X1338086Y1495595D03*
X1345351Y1737117D03*
X1356868Y85324D03*
X1360629Y120380D03*
X1363831Y642042D03*
X1361387Y642026D03*
X1356367Y642080D03*
X1352527Y638278D03*
X1360944Y638999D03*
Y636042D03*
X1357717Y647180D03*
Y649780D03*
X1355117D03*
Y647180D03*
X1357717Y644580D03*
X1355117D03*
X1364317Y661368D03*
X1357057Y661328D03*
X1364886Y1495595D03*
X1358186Y1505295D03*
X1369808Y87587D03*
X1382123Y614130D03*
X1374887Y626579D03*
X1372457D03*
X1370027D03*
X1369978Y614164D03*
X1366331Y642042D03*
X1376731Y638935D03*
Y642042D03*
X1371531Y638935D03*
Y642042D03*
Y635978D03*
X1374887Y632179D03*
X1374131Y638935D03*
Y642042D03*
X1368931Y638935D03*
Y642042D03*
Y635978D03*
X1370027Y632179D03*
X1372457D03*
X1371847Y661328D03*
X1366123Y1015473D03*
X1373603D03*
Y1019016D03*
Y1022559D03*
X1366123D03*
Y1019016D03*
X1371586Y1485895D03*
X1367351Y1737117D03*
X1381457Y637865D03*
X1380306Y664816D03*
X1380256Y667466D03*
X1393664Y671949D03*
Y668992D03*
X1390417Y677480D03*
X1389067Y674980D03*
X1387817Y677480D03*
X1394087Y674926D03*
X1390417Y680080D03*
X1387817D03*
X1390417Y682680D03*
X1387817D03*
X1388757Y693397D03*
Y690897D03*
X1381083Y1015473D03*
Y1022559D03*
Y1019016D03*
X1384986Y1505295D03*
X1391686Y1495595D03*
X1389351Y1737117D03*
X1403207Y118938D03*
X1402678Y647064D03*
X1404231Y671835D03*
X1406831D03*
X1409431D03*
X1404231Y668878D03*
X1407587Y665079D03*
X1405157Y659479D03*
X1407587D03*
X1401631Y671835D03*
Y668878D03*
X1402727Y659479D03*
Y665079D03*
X1405157D03*
X1404231Y674942D03*
X1409431D03*
X1406831D03*
X1396531D03*
X1399031D03*
X1401631D03*
X1403693Y1009399D03*
X1407433D03*
X1399953D03*
X1404615Y1014744D03*
X1399953Y1028830D03*
X1407433D03*
X1404615Y1023012D03*
Y1018878D03*
X1403693Y1028830D03*
X1406608Y1282606D03*
X1398386Y1485895D03*
X1414823Y647030D03*
X1414157Y670665D03*
X1416241Y700281D03*
X1416291Y697631D03*
X1420417Y712660D03*
Y715260D03*
Y710060D03*
X1423017Y712660D03*
Y715260D03*
Y710060D03*
X1421667Y707560D03*
X1422757Y726097D03*
Y723597D03*
X1418101Y997765D03*
Y993765D03*
X1418176Y989765D03*
X1418653Y1009399D03*
X1418101Y1001765D03*
X1422394Y1009399D03*
X1414913D03*
X1411173D03*
X1423316Y1014744D03*
X1414458D03*
Y1023012D03*
X1418653Y1028830D03*
X1411173D03*
X1414913D03*
X1423316Y1023012D03*
Y1018878D03*
X1422394Y1028830D03*
X1414458Y1018878D03*
X1411786Y1485895D03*
X1413199Y1643920D03*
X1411351Y1737117D03*
X1438883Y-15050D03*
Y-25050D03*
Y-5050D03*
Y14950D03*
Y4950D03*
X1438312Y152166D03*
X1435278Y679644D03*
X1436257Y676265D03*
X1436831Y701458D03*
X1435327Y692059D03*
X1437757D03*
X1434231Y701458D03*
X1435327Y697659D03*
X1437757D03*
X1426264Y701572D03*
X1436831Y704415D03*
Y707522D03*
X1439431Y704415D03*
Y707522D03*
X1431631D03*
X1429131D03*
X1426687Y707506D03*
X1434231Y704415D03*
Y707522D03*
X1426264Y704529D03*
X1433614Y1009399D03*
X1426134D03*
X1429874D03*
X1433552Y1014744D03*
X1429874Y1028830D03*
X1433552Y1018878D03*
Y1023012D03*
X1426134Y1028830D03*
X1433614D03*
X1433351Y1737117D03*
X1441908Y-26370D03*
X1445161Y-26356D03*
X1441908Y-16370D03*
X1441923Y-13855D03*
X1445161Y-16356D03*
X1445176Y-13841D03*
X1441923Y-23855D03*
X1445176Y-23841D03*
X1441908Y-6370D03*
X1441923Y-3855D03*
X1445161Y-6356D03*
X1445176Y-3841D03*
X1441908Y3630D03*
X1445161Y3644D03*
X1441908Y13630D03*
X1441923Y16145D03*
X1445161Y13644D03*
X1445176Y16159D03*
X1441923Y6145D03*
X1445176Y6159D03*
X1440871Y130118D03*
X1453667Y152166D03*
X1447423Y679610D03*
X1440187Y697659D03*
X1446757Y703265D03*
X1440187Y692059D03*
X1442031Y704415D03*
Y707522D03*
X1453335Y729637D03*
Y732237D03*
Y734837D03*
X1453757Y743597D03*
Y746097D03*
X1454098Y1485895D03*
X1447398Y1495595D03*
X1459177Y163796D03*
X1456282Y568977D03*
Y572977D03*
Y576977D03*
Y580977D03*
X1468196Y699221D03*
X1468245Y711636D03*
Y717236D03*
X1467149Y721035D03*
X1458599Y721045D03*
Y724002D03*
X1455935Y729637D03*
Y732237D03*
X1454585Y727137D03*
X1459605Y727083D03*
X1462049Y727099D03*
X1464549D03*
X1467149Y723992D03*
Y727099D03*
X1455935Y734837D03*
X1467498Y1505295D03*
X1455579Y1636114D03*
X1473105Y717236D03*
X1470675Y711636D03*
X1473105D03*
X1470675Y717236D03*
X1469749Y721035D03*
X1479757Y722865D03*
X1469749Y723992D03*
X1474949D03*
X1472349D03*
Y727099D03*
X1469749D03*
X1474949D03*
X1481665Y745809D03*
X1477177Y803488D03*
X1478177Y817013D03*
X1480898Y1485895D03*
X1474198Y1495595D03*
X1498543Y587841D03*
X1492264Y721149D03*
X1486417Y729637D03*
Y732237D03*
X1489017Y729687D03*
Y732237D03*
X1492264Y724106D03*
X1487667Y727137D03*
X1492687Y727083D03*
X1495131Y727099D03*
X1497631D03*
X1486417Y734837D03*
X1489017D03*
X1484265Y745809D03*
X1489177Y803488D03*
X1498177Y817013D03*
X1494298Y1505295D03*
X1501278Y699221D03*
X1506187Y717236D03*
Y711636D03*
X1501327D03*
X1503757D03*
X1501327Y717404D03*
X1503757D03*
X1502831Y721035D03*
X1500231D03*
X1512757Y722897D03*
X1500231Y723992D03*
X1502831D03*
X1505431D03*
X1508031D03*
X1500231Y727099D03*
X1502831D03*
X1505431D03*
X1508031D03*
X1505905Y746119D03*
X1508505D03*
X1507698Y1485895D03*
X1500998Y1495595D03*
X1499351Y1737117D03*
X1519930Y543470D03*
X1516357Y555318D03*
X1516257Y559977D03*
X1525064Y721149D03*
Y724106D03*
X1521817Y729637D03*
Y732237D03*
X1525487Y727083D03*
X1527931Y727099D03*
X1519217Y729637D03*
Y732237D03*
X1520467Y727137D03*
X1521817Y734837D03*
X1519217D03*
X1515895Y746119D03*
X1518495D03*
X1521098Y1505295D03*
X1527798Y1495595D03*
X1521351Y1737117D03*
X1541580Y-19575D03*
X1541666Y69340D03*
X1532853Y560264D03*
X1534078Y699221D03*
X1536557Y711636D03*
X1534127D03*
X1538987Y717236D03*
Y711636D03*
X1534127Y717236D03*
X1536557D03*
X1535631Y721035D03*
X1533031D03*
X1538231Y723992D03*
X1540831D03*
X1538231Y727099D03*
X1540831D03*
X1530431D03*
X1533031Y723992D03*
X1535631D03*
X1533031Y727099D03*
X1535631D03*
X1543563Y757803D03*
X1543585Y762919D03*
X1543574Y760361D03*
X1534317Y1216828D03*
X1531227Y1227648D03*
X1540227D03*
X1534498Y1485895D03*
X1543351Y1737117D03*
X1554510Y28406D03*
X1547424D03*
X1554510Y40020D03*
X1547424D03*
X1552662Y75343D03*
X1546257Y701097D03*
X1558194Y702166D03*
Y699209D03*
X1552347Y712897D03*
X1554947D03*
X1552347Y710297D03*
Y707697D03*
X1554947Y710297D03*
Y707697D03*
X1553597Y705197D03*
X1558617Y705143D03*
X1551250Y723840D03*
X1553750D03*
X1545557Y722897D03*
X1556555Y740617D03*
X1556544Y738059D03*
X1554055Y740617D03*
X1554044Y738059D03*
X1546965Y746119D03*
X1546954Y743561D03*
X1548119Y751952D03*
X1545619D03*
X1548119Y754832D03*
X1545619D03*
X1546063Y757803D03*
X1546085Y762919D03*
X1546074Y760361D03*
X1549877Y1217288D03*
Y1221288D03*
X1547898Y1485895D03*
X1561597Y28406D03*
X1568683D03*
Y40020D03*
X1561597D03*
X1563666Y69340D03*
X1567208Y677281D03*
X1572117Y695296D03*
X1568761Y702052D03*
X1571361D03*
X1568761Y699095D03*
X1566161Y702052D03*
Y699095D03*
X1569687Y689696D03*
X1572117D03*
X1567257D03*
Y695296D03*
X1569687D03*
X1563561Y705159D03*
X1561061D03*
X1568761D03*
X1571361D03*
X1566161D03*
X1568660Y1283460D03*
X1572036Y1306083D03*
X1565351Y1737117D03*
X1575770Y28406D03*
X1582857D03*
Y40020D03*
X1575770D03*
X1574666Y75340D03*
X1585666Y69340D03*
X1579748Y536344D03*
X1576843Y674425D03*
X1579807Y671268D03*
X1586367Y671428D03*
X1587717Y676528D03*
Y673928D03*
X1585117Y676528D03*
Y673928D03*
Y679128D03*
X1587717D03*
X1578757Y700965D03*
X1573961Y702052D03*
X1586070Y696830D03*
Y694330D03*
X1573961Y705159D03*
X1578904Y721340D03*
Y723840D03*
X1584849Y793506D03*
X1587028Y1307137D03*
X1582160Y1485895D03*
X1575460Y1495595D03*
X1587351Y1737117D03*
X1589943Y28406D03*
X1597030D03*
Y40020D03*
X1589943D03*
X1596666Y75340D03*
X1599837Y295328D03*
X1593214Y531226D03*
X1599978Y643512D03*
X1600027Y655927D03*
X1602457D03*
X1591387Y671374D03*
X1593831Y671390D03*
X1596331D03*
X1601531D03*
Y668283D03*
Y665326D03*
X1598931Y671390D03*
Y668283D03*
Y665326D03*
X1600027Y661527D03*
X1602457D03*
X1590964Y668397D03*
Y665440D03*
X1594539Y1295288D03*
X1595560Y1505295D03*
X1602260Y1495595D03*
X1604117Y28406D03*
Y40020D03*
X1607666Y69343D03*
X1609355Y592794D03*
X1615677Y648488D03*
X1604887Y655927D03*
X1618117Y657528D03*
Y654928D03*
X1611557Y667165D03*
X1606731Y671390D03*
Y668283D03*
X1604131Y671390D03*
Y668283D03*
X1604887Y661527D03*
X1618117Y660128D03*
X1613154Y688238D03*
Y690738D03*
X1605447Y1288748D03*
X1608960Y1485895D03*
X1609351Y1737117D03*
X1632896Y28406D03*
X1625809D03*
X1632896Y40020D03*
X1625809D03*
X1618666Y75340D03*
X1631558Y588513D03*
X1628756Y588591D03*
X1624067Y588474D03*
X1621187Y588591D03*
X1632978Y624512D03*
X1633027Y636927D03*
Y642527D03*
X1620717Y657528D03*
X1631931Y652390D03*
Y649283D03*
X1626831Y652390D03*
X1629331D03*
X1631931Y646326D03*
X1624387Y652374D03*
X1619367Y652428D03*
X1620717Y654928D03*
X1623964Y649397D03*
Y646440D03*
X1621050Y671768D03*
X1623550D03*
X1620717Y660128D03*
X1628946Y790296D03*
Y800335D03*
Y827107D03*
Y837146D03*
Y863918D03*
Y873957D03*
Y900729D03*
Y910768D03*
Y937540D03*
Y947579D03*
Y1084784D03*
Y1094823D03*
Y1121595D03*
Y1131634D03*
Y1158406D03*
Y1168445D03*
Y1195217D03*
Y1205256D03*
Y1232028D03*
Y1242067D03*
X1629060Y1495595D03*
X1622360Y1505295D03*
X1631351Y1737117D03*
X1647069Y28406D03*
X1639983D03*
X1647069Y40020D03*
X1639983D03*
X1641870Y75340D03*
X1645123Y624478D03*
X1637887Y642527D03*
Y636927D03*
X1635457D03*
Y642527D03*
X1644457Y648265D03*
X1639731Y652390D03*
X1634531D03*
X1637131D03*
X1639731Y649283D03*
X1634531D03*
X1637131D03*
X1634531Y646326D03*
X1643183Y1419441D03*
X1643283Y1431541D03*
X1635760Y1485895D03*
X1654156Y28406D03*
Y40020D03*
X1652870Y69340D03*
X1650917Y657528D03*
Y654928D03*
X1653517Y657528D03*
X1652167Y652428D03*
X1653517Y654928D03*
X1648604Y671768D03*
X1650917Y660128D03*
X1659618Y659021D03*
X1662298D03*
X1651104Y671768D03*
X1653517Y660128D03*
X1656938Y659021D03*
X1651959Y689800D03*
X1658647Y790296D03*
Y800335D03*
Y827107D03*
Y837146D03*
Y863918D03*
Y873957D03*
Y900729D03*
Y910768D03*
Y937540D03*
Y947579D03*
Y1084784D03*
Y1094823D03*
Y1121595D03*
Y1131634D03*
Y1158406D03*
Y1168445D03*
Y1205256D03*
Y1195217D03*
Y1232028D03*
Y1242067D03*
X1649283Y1419441D03*
Y1431541D03*
X1655383D03*
Y1419441D03*
X1655957Y1445116D03*
X1662560Y1485895D03*
X1649160Y1505295D03*
X1655860Y1495595D03*
X1653351Y1737117D03*
X1677030Y28406D03*
X1669943D03*
X1677030Y40020D03*
X1669943D03*
X1663866Y75343D03*
X1674870Y69340D03*
X1668516Y599956D03*
X1674516D03*
X1668516Y609450D03*
X1671516Y599956D03*
X1674516Y609450D03*
X1677516Y599956D03*
X1671516Y609450D03*
X1677516D03*
X1667498Y659021D03*
X1664898D03*
X1675960Y1485895D03*
X1668000Y1711759D03*
Y1726909D03*
X1675351Y1737117D03*
X1684117Y28406D03*
X1691203D03*
Y40020D03*
X1684117D03*
X1686004Y75340D03*
X1688348Y790296D03*
Y800335D03*
Y827107D03*
Y837146D03*
Y863918D03*
Y873957D03*
Y910768D03*
Y900729D03*
Y937540D03*
Y947579D03*
Y1084784D03*
Y1094823D03*
Y1131634D03*
Y1121595D03*
Y1158406D03*
Y1168445D03*
Y1205256D03*
Y1195217D03*
Y1232028D03*
Y1242067D03*
X1684677Y1440258D03*
X1687357Y1440268D03*
X1698290Y28406D03*
X1705376D03*
X1698290Y40020D03*
X1697000Y69343D03*
X1701121Y641658D03*
X1706101D03*
X1695529Y1545193D03*
X1703000Y1711759D03*
X1697351Y1737117D03*
X1708004Y75340D03*
X1708305Y679720D03*
X1718049Y790296D03*
Y800335D03*
Y827107D03*
Y837146D03*
Y863918D03*
Y873957D03*
Y910768D03*
Y900729D03*
Y937540D03*
Y947579D03*
Y1084784D03*
Y1094823D03*
Y1131634D03*
Y1121595D03*
Y1158406D03*
Y1168445D03*
Y1195217D03*
Y1205256D03*
Y1232028D03*
Y1242067D03*
X1719351Y1737117D03*
X1735375Y-40925D03*
X1732350Y-39605D03*
X1735390Y-38410D03*
X1738628Y-40911D03*
X1738658Y-35881D03*
X1738673Y-33366D03*
X1738643Y-38396D03*
X1749571Y255317D03*
Y252317D03*
X1745502Y660088D03*
X1747750Y790296D03*
Y800335D03*
Y827107D03*
Y837146D03*
Y863918D03*
Y873957D03*
Y910768D03*
Y900729D03*
Y937540D03*
Y947579D03*
Y1084784D03*
Y1094823D03*
Y1131634D03*
Y1121595D03*
Y1158406D03*
Y1168445D03*
Y1205256D03*
Y1195217D03*
Y1232028D03*
Y1242067D03*
X1742120Y1708265D03*
Y1723415D03*
X1741351Y1737117D03*
X1753388Y28406D03*
X1760475D03*
X1754364Y100353D03*
X1764644Y122973D03*
X1755969Y251524D03*
Y248524D03*
X1763509Y251341D03*
Y248341D03*
X1763351Y1737117D03*
X1771881Y128439D03*
Y125939D03*
Y123439D03*
X1781966Y128501D03*
Y126001D03*
Y123501D03*
X1775984Y253779D03*
Y256779D03*
X1777450Y790296D03*
Y800335D03*
Y827107D03*
Y837146D03*
Y863918D03*
Y873957D03*
Y910768D03*
Y900729D03*
Y937540D03*
Y947579D03*
Y1084784D03*
Y1094823D03*
Y1131634D03*
Y1121595D03*
Y1158406D03*
Y1168445D03*
Y1205256D03*
Y1195217D03*
Y1232028D03*
Y1242067D03*
X1785072Y53161D03*
X1789811Y178083D03*
X1794629Y193323D03*
X1791645Y193397D03*
X1795219Y185910D03*
X1795949Y205580D03*
X1795909Y209128D03*
X1795365Y197567D03*
X1796019Y202030D03*
X1791445Y197497D03*
X1783592Y763765D03*
X1804111Y178083D03*
X1807711D03*
Y175083D03*
X1803165Y196127D03*
X1797621Y193373D03*
X1800389Y193424D03*
X1803045Y193397D03*
X1798943Y204744D03*
Y209044D03*
X1802276Y209013D03*
X1805235Y208950D03*
X1802276Y204713D03*
X1800125Y201857D03*
X1805235Y204650D03*
X1799629Y198870D03*
X1803145Y198697D03*
X1817674Y188699D03*
X1829732Y367359D03*
G54D24*
X67725Y1538946D03*
X74912D03*
X72585D03*
X70155D03*
X103468D03*
X105898D03*
X108328D03*
X110655D03*
X1757438Y1571982D03*
X1755008D03*
X1762195D03*
X1759868D03*
X1793181D03*
X1790751D03*
X1795611D03*
X1797938D03*
G54D28*
X130000Y1719450D03*
X543277Y88632D03*
X538620Y93289D03*
G54D63*
X1156378Y133866D03*
X1183858Y207205D03*
X1173858D03*
X1193858D03*
X1351260Y164213D03*
Y174213D03*
X1361260Y164213D03*
Y174213D03*
X1371260Y164213D03*
X1381260D03*
X1371260Y174213D03*
X1381260D03*
X1391260Y164213D03*
Y174213D03*
G54D20*
X50880Y1415563D03*
Y1418963D03*
X58349Y1406331D03*
Y1409731D03*
X78265Y26477D03*
X74865D03*
X81970Y19541D03*
X85370D03*
X92438Y26477D03*
X89038D03*
X96143Y19541D03*
X90965Y960966D03*
X99543Y19541D03*
X106611Y26477D03*
X103211D03*
X110316Y19541D03*
X99024Y780257D03*
Y786950D03*
Y803682D03*
Y793643D03*
Y796989D03*
Y817068D03*
Y810375D03*
Y823761D03*
Y830454D03*
Y833800D03*
Y840493D03*
Y847186D03*
Y853879D03*
Y860572D03*
Y877304D03*
Y867265D03*
Y870611D03*
Y883997D03*
Y890690D03*
Y897383D03*
Y904076D03*
Y907423D03*
Y914115D03*
Y920808D03*
Y927501D03*
Y934194D03*
Y940887D03*
Y950926D03*
Y944234D03*
Y964312D03*
Y957619D03*
Y971005D03*
Y977698D03*
Y984391D03*
Y1001123D03*
Y997777D03*
Y991084D03*
Y1031241D03*
Y1037934D03*
Y1044627D03*
Y1058013D03*
Y1051320D03*
Y1074745D03*
Y1081438D03*
Y1088131D03*
Y1098171D03*
Y1104863D03*
Y1091478D03*
Y1111556D03*
Y1118249D03*
Y1134982D03*
Y1124942D03*
Y1128289D03*
Y1148367D03*
Y1141675D03*
Y1155060D03*
Y1161753D03*
Y1165100D03*
Y1171793D03*
Y1178486D03*
Y1185178D03*
Y1191871D03*
Y1208604D03*
Y1198564D03*
Y1201911D03*
Y1215297D03*
Y1221989D03*
Y1228682D03*
Y1235375D03*
Y1238722D03*
Y1245415D03*
Y1252108D03*
X112473Y1660235D03*
X109073D03*
X107569Y1685763D03*
X110969D03*
X113716Y19541D03*
X120785Y26477D03*
X117385D03*
X124490Y19541D03*
X115166Y776911D03*
Y783604D03*
Y790297D03*
Y800336D03*
Y807029D03*
Y793643D03*
Y813722D03*
Y820415D03*
Y837147D03*
Y830454D03*
Y827108D03*
Y843840D03*
Y850533D03*
Y857226D03*
Y863919D03*
Y873958D03*
Y880651D03*
Y867265D03*
Y887344D03*
Y894037D03*
Y910769D03*
Y904076D03*
Y900730D03*
Y924155D03*
Y917462D03*
Y930848D03*
Y940887D03*
Y937541D03*
Y947580D03*
Y954273D03*
Y967659D03*
Y974352D03*
Y981045D03*
Y987737D03*
Y994430D03*
Y1001123D03*
Y1027895D03*
Y1034588D03*
Y1041281D03*
Y1047974D03*
Y1054667D03*
Y1061360D03*
Y1071399D03*
Y1064706D03*
Y1078092D03*
Y1088131D03*
Y1084785D03*
Y1094824D03*
Y1101517D03*
Y1108210D03*
Y1114903D03*
Y1131635D03*
Y1124942D03*
Y1121596D03*
Y1138328D03*
Y1145021D03*
Y1151714D03*
Y1161753D03*
Y1158407D03*
Y1168446D03*
Y1175139D03*
Y1181832D03*
Y1188525D03*
Y1205257D03*
Y1198564D03*
Y1195218D03*
Y1211950D03*
Y1218643D03*
Y1225336D03*
Y1235375D03*
Y1232029D03*
Y1242068D03*
Y1248761D03*
X127890Y19541D03*
X128724Y780257D03*
Y786950D03*
Y803682D03*
Y793643D03*
Y796989D03*
Y817068D03*
Y810375D03*
Y823761D03*
Y830454D03*
Y833800D03*
Y840493D03*
Y847186D03*
Y853879D03*
Y860572D03*
Y877304D03*
Y867265D03*
Y870611D03*
Y883997D03*
Y890690D03*
Y897383D03*
Y904076D03*
Y907423D03*
Y914115D03*
Y920808D03*
Y927501D03*
Y934194D03*
Y940887D03*
Y950926D03*
Y944234D03*
Y964312D03*
Y957619D03*
Y971005D03*
Y977698D03*
Y984391D03*
Y1001123D03*
Y997777D03*
Y991084D03*
Y1031241D03*
Y1037934D03*
Y1044627D03*
Y1058013D03*
Y1051320D03*
Y1074745D03*
Y1081438D03*
Y1088131D03*
Y1098171D03*
Y1104863D03*
Y1091478D03*
Y1111556D03*
Y1118249D03*
Y1134982D03*
Y1124942D03*
Y1128289D03*
Y1148367D03*
Y1141675D03*
Y1155060D03*
Y1161753D03*
Y1165100D03*
Y1171793D03*
Y1178486D03*
Y1185178D03*
Y1191871D03*
Y1208604D03*
Y1198564D03*
Y1201911D03*
Y1215297D03*
Y1221989D03*
Y1228682D03*
Y1235375D03*
Y1238722D03*
Y1245415D03*
Y1252108D03*
X156651Y26477D03*
X153251D03*
X144866Y776911D03*
Y783604D03*
Y790297D03*
Y800336D03*
Y807029D03*
Y793643D03*
Y813722D03*
Y820415D03*
Y837147D03*
Y830454D03*
Y827108D03*
Y843840D03*
Y850533D03*
Y857226D03*
Y863919D03*
Y873958D03*
Y880651D03*
Y867265D03*
Y887344D03*
Y894037D03*
Y910769D03*
Y904076D03*
Y900730D03*
Y924155D03*
Y917462D03*
Y930848D03*
Y940887D03*
Y937541D03*
Y947580D03*
Y954273D03*
Y967659D03*
Y974352D03*
Y981045D03*
Y987737D03*
Y994430D03*
Y1001123D03*
Y1027895D03*
Y1034588D03*
Y1041281D03*
Y1047974D03*
Y1054667D03*
Y1061360D03*
Y1071399D03*
Y1064706D03*
Y1078092D03*
Y1088131D03*
Y1084785D03*
Y1094824D03*
Y1101517D03*
Y1108210D03*
Y1114903D03*
Y1131635D03*
Y1124942D03*
Y1121596D03*
Y1138328D03*
Y1145021D03*
Y1151714D03*
Y1161753D03*
Y1158407D03*
Y1168446D03*
Y1175139D03*
Y1181832D03*
Y1188525D03*
Y1205257D03*
Y1198564D03*
Y1195218D03*
Y1211950D03*
Y1218643D03*
Y1225336D03*
Y1235375D03*
Y1232029D03*
Y1242068D03*
Y1248761D03*
X170824Y26477D03*
X163756Y19541D03*
X167424Y26477D03*
X160356Y19541D03*
X158425Y780257D03*
Y786950D03*
Y803682D03*
Y793643D03*
Y796989D03*
Y817068D03*
Y810375D03*
Y823761D03*
Y830454D03*
Y833800D03*
Y840493D03*
Y847186D03*
Y853879D03*
Y860572D03*
Y877304D03*
Y867265D03*
Y870611D03*
Y883997D03*
Y890690D03*
Y897383D03*
Y904076D03*
Y907423D03*
Y914115D03*
Y920808D03*
Y927501D03*
Y934194D03*
Y940887D03*
Y950926D03*
Y944234D03*
Y964312D03*
Y957619D03*
Y971005D03*
Y977698D03*
Y984391D03*
Y1001123D03*
Y997777D03*
Y991084D03*
Y1031241D03*
Y1037934D03*
Y1044627D03*
Y1058013D03*
Y1051320D03*
Y1074745D03*
Y1081438D03*
Y1088131D03*
Y1098171D03*
Y1104863D03*
Y1091478D03*
Y1111556D03*
Y1118249D03*
Y1134982D03*
Y1124942D03*
Y1128289D03*
Y1148367D03*
Y1141675D03*
Y1155060D03*
Y1161753D03*
Y1165100D03*
Y1171793D03*
Y1178486D03*
Y1185178D03*
Y1191871D03*
Y1208604D03*
Y1198564D03*
Y1201911D03*
Y1215297D03*
Y1221989D03*
Y1228682D03*
Y1235375D03*
Y1238722D03*
Y1245415D03*
Y1252108D03*
X169351Y1462595D03*
X163113Y1483590D03*
Y1480190D03*
Y1501990D03*
Y1505390D03*
X177929Y19541D03*
X174529D03*
X174567Y776911D03*
Y783604D03*
Y790297D03*
Y800336D03*
Y807029D03*
Y793643D03*
Y813722D03*
Y820415D03*
Y837147D03*
Y830454D03*
Y827108D03*
Y843840D03*
Y850533D03*
Y857226D03*
Y863919D03*
Y873958D03*
Y880651D03*
Y867265D03*
Y887344D03*
Y894037D03*
Y910769D03*
Y904076D03*
Y900730D03*
Y924155D03*
Y917462D03*
Y930848D03*
Y940887D03*
Y937541D03*
Y947580D03*
Y954273D03*
Y967659D03*
Y974352D03*
Y981045D03*
Y987737D03*
Y994430D03*
Y1001123D03*
Y1027895D03*
Y1034588D03*
Y1041281D03*
Y1047974D03*
Y1054667D03*
Y1061360D03*
Y1071399D03*
Y1064706D03*
Y1078092D03*
Y1088131D03*
Y1084785D03*
Y1094824D03*
Y1101517D03*
Y1108210D03*
Y1114903D03*
Y1131635D03*
Y1124942D03*
Y1121596D03*
Y1138328D03*
Y1145021D03*
Y1151714D03*
Y1161753D03*
Y1158407D03*
Y1168446D03*
Y1175139D03*
Y1181832D03*
Y1188525D03*
Y1205257D03*
Y1198564D03*
Y1195218D03*
Y1211950D03*
Y1218643D03*
Y1225336D03*
Y1235375D03*
Y1232029D03*
Y1242068D03*
Y1248761D03*
X172751Y1462595D03*
X179451Y1452895D03*
X176051D03*
X200785Y26477D03*
X197385D03*
X199551Y1462595D03*
X196151D03*
X192851Y1472295D03*
X189451D03*
X188166Y1592380D03*
X200226D03*
X191566D03*
X194196Y1602380D03*
X197596D03*
X207890Y19541D03*
X214958Y26477D03*
X204490Y19541D03*
X211558Y26477D03*
X209768Y960966D03*
X206251Y1452895D03*
X202851D03*
X216251Y1472295D03*
X212286Y1592380D03*
X203626D03*
X215686D03*
X206256Y1602380D03*
X209656D03*
X222063Y19541D03*
X218663D03*
X226351Y1462595D03*
X222951D03*
X229651Y1452895D03*
X219651Y1472295D03*
X224346Y1592380D03*
X227746D03*
X218316Y1602380D03*
X230376D03*
X221716D03*
X233051Y1452895D03*
X246451Y1472295D03*
X243051D03*
X236406Y1592380D03*
X239806D03*
X242436Y1602380D03*
X233776D03*
X245836D03*
X253151Y1462595D03*
X259851Y1452895D03*
X249751Y1462595D03*
X256451Y1452895D03*
X248466Y1592380D03*
X260526D03*
X251866D03*
X254496Y1602380D03*
X257896D03*
X269851Y1452895D03*
X273251D03*
X272586Y1592380D03*
X263926D03*
X275986D03*
X266556Y1602380D03*
X269956D03*
X280621Y1484082D03*
Y1480682D03*
X291175Y1483590D03*
Y1480190D03*
X280621Y1497482D03*
Y1494082D03*
X291175Y1501990D03*
Y1505390D03*
X284646Y1592380D03*
X288046D03*
X278616Y1602380D03*
X290676D03*
X282016D03*
X300813Y1462595D03*
X297413D03*
X304113Y1452895D03*
X296706Y1592380D03*
X300106D03*
X302736Y1602380D03*
X294076D03*
X306136D03*
X307513Y1452895D03*
X320913Y1472295D03*
X317513D03*
X308766Y1592380D03*
X320826D03*
X312166D03*
X314796Y1602380D03*
X318196D03*
X327613Y1462595D03*
X334313Y1452895D03*
X324213Y1462595D03*
X330913Y1452895D03*
X332886Y1592380D03*
X324226D03*
X326856Y1602380D03*
X330256D03*
X351013Y1462595D03*
X347713Y1472295D03*
X344313D03*
X344946Y1592380D03*
X336286D03*
X348346D03*
X338916Y1602380D03*
X350976D03*
X342316D03*
X354413Y1462595D03*
X361113Y1452895D03*
X357713D03*
X357006Y1592380D03*
X360406D03*
X363036Y1602380D03*
X354376D03*
X371999Y819527D03*
X372000Y831797D03*
Y835197D03*
X371999Y822927D03*
X372000Y846427D03*
Y843027D03*
X377813Y1462595D03*
X374513Y1472295D03*
X371113D03*
X369066Y1592380D03*
X372466D03*
X375096Y1602380D03*
X366436D03*
X378496D03*
X390841Y-25571D03*
Y-22171D03*
Y-15571D03*
Y-12171D03*
X385001Y816927D03*
Y813527D03*
X381213Y1462595D03*
X387913Y1452895D03*
X384513D03*
X400426Y112815D03*
Y116215D03*
X405606Y125815D03*
Y129715D03*
X401313Y1452895D03*
X397913D03*
X408683Y1480682D03*
Y1484082D03*
Y1497482D03*
Y1494082D03*
X455502Y88711D03*
X452102D03*
X448414Y94684D03*
X445014D03*
X452339Y1592380D03*
X464399D03*
X455739D03*
X467799D03*
X476295Y130020D03*
X472895D03*
X476459Y1592380D03*
X479859D03*
X488519D03*
X491919D03*
X514240Y97146D03*
X500579Y1592380D03*
X512639D03*
X503979D03*
X526460Y100895D03*
Y97495D03*
X517640Y97146D03*
X524699Y1592380D03*
X516039D03*
X528099D03*
X536759D03*
X540159D03*
X559069Y105385D03*
Y101985D03*
X548819Y1592380D03*
X552219D03*
X572939D03*
X560879D03*
X564279D03*
X584999D03*
X576339D03*
X588399D03*
X597059D03*
X600459D03*
X609119D03*
X612519D03*
X621179D03*
X633239D03*
X624579D03*
X636639D03*
X653999Y1426757D03*
Y1423357D03*
X687697Y960966D03*
X691276Y1455112D03*
X704771Y179599D03*
Y182999D03*
Y194810D03*
Y191410D03*
Y206621D03*
Y203221D03*
Y218432D03*
Y215032D03*
X706756Y780257D03*
Y786950D03*
Y803682D03*
Y793643D03*
Y796989D03*
Y817068D03*
Y810375D03*
Y823761D03*
Y830454D03*
Y833800D03*
Y840493D03*
Y847186D03*
Y853879D03*
Y860572D03*
Y877304D03*
Y867265D03*
Y870611D03*
Y883997D03*
Y890690D03*
Y897383D03*
Y904076D03*
Y907423D03*
Y914115D03*
Y920808D03*
Y927501D03*
Y934194D03*
Y940887D03*
Y950926D03*
Y944234D03*
Y964312D03*
Y957619D03*
Y971005D03*
Y977698D03*
Y984391D03*
Y1001123D03*
Y997777D03*
Y991084D03*
Y1031241D03*
Y1037934D03*
Y1044627D03*
Y1058013D03*
Y1051320D03*
Y1074745D03*
Y1081438D03*
Y1088131D03*
Y1098171D03*
Y1104863D03*
Y1091478D03*
Y1111556D03*
Y1118249D03*
Y1134982D03*
Y1124942D03*
Y1128289D03*
Y1148367D03*
Y1141675D03*
Y1155060D03*
Y1161753D03*
Y1165100D03*
Y1171793D03*
Y1178486D03*
Y1185178D03*
Y1191871D03*
Y1208604D03*
Y1198564D03*
Y1201911D03*
Y1215297D03*
Y1221989D03*
Y1228682D03*
Y1235375D03*
Y1238722D03*
Y1245415D03*
Y1252108D03*
X694676Y1455112D03*
X716699Y177087D03*
Y173687D03*
Y189087D03*
Y185687D03*
Y200587D03*
Y197187D03*
Y209021D03*
Y212421D03*
X722898Y776911D03*
Y783604D03*
Y790297D03*
Y800336D03*
Y807029D03*
Y793643D03*
Y813722D03*
Y820415D03*
Y837147D03*
Y830454D03*
Y827108D03*
Y843840D03*
Y850533D03*
Y857226D03*
Y863919D03*
Y873958D03*
Y880651D03*
Y867265D03*
Y887344D03*
Y894037D03*
Y910769D03*
Y904076D03*
Y900730D03*
Y924155D03*
Y917462D03*
Y930848D03*
Y940887D03*
Y937541D03*
Y947580D03*
Y954273D03*
Y967659D03*
Y974352D03*
Y981045D03*
Y987737D03*
Y994430D03*
Y1001123D03*
Y1027895D03*
Y1034588D03*
Y1041281D03*
Y1047974D03*
Y1054667D03*
Y1061360D03*
Y1071399D03*
Y1064706D03*
Y1078092D03*
Y1088131D03*
Y1084785D03*
Y1094824D03*
Y1101517D03*
Y1108210D03*
Y1114903D03*
Y1131635D03*
Y1124942D03*
Y1121596D03*
Y1138328D03*
Y1145021D03*
Y1151714D03*
Y1161753D03*
Y1158407D03*
Y1168446D03*
Y1175139D03*
Y1181832D03*
Y1188525D03*
Y1205257D03*
Y1198564D03*
Y1195218D03*
Y1211950D03*
Y1218643D03*
Y1225336D03*
Y1235375D03*
Y1232029D03*
Y1242068D03*
Y1248761D03*
X725925Y-25571D03*
Y-22171D03*
Y-15571D03*
Y-12171D03*
X736457Y780257D03*
Y786950D03*
Y803682D03*
Y793643D03*
Y796989D03*
Y817068D03*
Y810375D03*
Y823761D03*
Y830454D03*
Y833800D03*
Y840493D03*
Y847186D03*
Y853879D03*
Y860572D03*
Y877304D03*
Y867265D03*
Y870611D03*
Y883997D03*
Y890690D03*
Y897383D03*
Y904076D03*
Y907423D03*
Y914115D03*
Y920808D03*
Y927501D03*
Y934194D03*
Y940887D03*
Y950926D03*
Y944234D03*
Y964312D03*
Y957619D03*
Y971005D03*
Y977698D03*
Y984391D03*
Y1001123D03*
Y997777D03*
Y991084D03*
Y1031241D03*
Y1037934D03*
Y1044627D03*
Y1058013D03*
Y1051320D03*
Y1074745D03*
Y1081438D03*
Y1088131D03*
Y1098171D03*
Y1104863D03*
Y1091478D03*
Y1111556D03*
Y1118249D03*
Y1134982D03*
Y1124942D03*
Y1128289D03*
Y1148367D03*
Y1141675D03*
Y1155060D03*
Y1161753D03*
Y1165100D03*
Y1171793D03*
Y1178486D03*
Y1185178D03*
Y1191871D03*
Y1208604D03*
Y1198564D03*
Y1201911D03*
Y1215297D03*
Y1221989D03*
Y1228682D03*
Y1235375D03*
Y1238722D03*
Y1245415D03*
Y1252108D03*
X752599Y776911D03*
Y783604D03*
Y790297D03*
Y800336D03*
Y807029D03*
Y793643D03*
Y813722D03*
Y820415D03*
Y837147D03*
Y830454D03*
Y827108D03*
Y843840D03*
Y850533D03*
Y857226D03*
Y863919D03*
Y873958D03*
Y880651D03*
Y867265D03*
Y887344D03*
Y894037D03*
Y910769D03*
Y904076D03*
Y900730D03*
Y924155D03*
Y917462D03*
Y930848D03*
Y940887D03*
Y937541D03*
Y947580D03*
Y954273D03*
Y967659D03*
Y974352D03*
Y981045D03*
Y987737D03*
Y994430D03*
Y1001123D03*
Y1027895D03*
Y1034588D03*
Y1041281D03*
Y1047974D03*
Y1054667D03*
Y1061360D03*
Y1071399D03*
Y1064706D03*
Y1078092D03*
Y1088131D03*
Y1084785D03*
Y1094824D03*
Y1101517D03*
Y1108210D03*
Y1114903D03*
Y1131635D03*
Y1124942D03*
Y1121596D03*
Y1138328D03*
Y1145021D03*
Y1151714D03*
Y1161753D03*
Y1158407D03*
Y1168446D03*
Y1175139D03*
Y1181832D03*
Y1188525D03*
Y1205257D03*
Y1198564D03*
Y1195218D03*
Y1211950D03*
Y1218643D03*
Y1225336D03*
Y1235375D03*
Y1232029D03*
Y1242068D03*
Y1248761D03*
X766158Y780257D03*
Y786950D03*
Y803682D03*
Y793643D03*
Y796989D03*
Y817068D03*
Y810375D03*
Y823761D03*
Y830454D03*
Y833800D03*
Y840493D03*
Y847186D03*
Y853879D03*
Y860572D03*
Y877304D03*
Y867265D03*
Y870611D03*
Y883997D03*
Y890690D03*
Y897383D03*
Y904076D03*
Y907423D03*
Y914115D03*
Y920808D03*
Y927501D03*
Y934194D03*
Y940887D03*
Y950926D03*
Y944234D03*
Y964312D03*
Y957619D03*
Y971005D03*
Y977698D03*
Y984391D03*
Y1001123D03*
Y997777D03*
Y991084D03*
Y1031241D03*
Y1037934D03*
Y1044627D03*
Y1058013D03*
Y1051320D03*
Y1074745D03*
Y1081438D03*
Y1088131D03*
Y1098171D03*
Y1104863D03*
Y1091478D03*
Y1111556D03*
Y1118249D03*
Y1134982D03*
Y1124942D03*
Y1128289D03*
Y1148367D03*
Y1141675D03*
Y1155060D03*
Y1161753D03*
Y1165100D03*
Y1171793D03*
Y1178486D03*
Y1185178D03*
Y1191871D03*
Y1208604D03*
Y1198564D03*
Y1201911D03*
Y1215297D03*
Y1221989D03*
Y1228682D03*
Y1235375D03*
Y1238722D03*
Y1245415D03*
Y1252108D03*
X782300Y776911D03*
Y783604D03*
Y790297D03*
Y800336D03*
Y807029D03*
Y793643D03*
Y813722D03*
Y820415D03*
Y837147D03*
Y830454D03*
Y827108D03*
Y843840D03*
Y850533D03*
Y857226D03*
Y863919D03*
Y873958D03*
Y880651D03*
Y867265D03*
Y887344D03*
Y894037D03*
Y910769D03*
Y904076D03*
Y900730D03*
Y924155D03*
Y917462D03*
Y930848D03*
Y940887D03*
Y937541D03*
Y947580D03*
Y954273D03*
Y967659D03*
Y974352D03*
Y981045D03*
Y987737D03*
Y994430D03*
Y1001123D03*
Y1027895D03*
Y1034588D03*
Y1041281D03*
Y1047974D03*
Y1054667D03*
Y1061360D03*
Y1071399D03*
Y1064706D03*
Y1078092D03*
Y1088131D03*
Y1084785D03*
Y1094824D03*
Y1101517D03*
Y1108210D03*
Y1114903D03*
Y1131635D03*
Y1124942D03*
Y1121596D03*
Y1138328D03*
Y1145021D03*
Y1151714D03*
Y1161753D03*
Y1158407D03*
Y1168446D03*
Y1175139D03*
Y1181832D03*
Y1188525D03*
Y1205257D03*
Y1198564D03*
Y1195218D03*
Y1211950D03*
Y1218643D03*
Y1225336D03*
Y1235375D03*
Y1232029D03*
Y1242068D03*
Y1248761D03*
X806500Y960966D03*
X814296Y1384045D03*
Y1387445D03*
X842320Y-21711D03*
Y-18311D03*
Y-11711D03*
Y-8311D03*
Y11689D03*
Y8289D03*
Y18289D03*
Y21689D03*
X1007587Y805418D03*
Y816352D03*
Y819752D03*
Y808818D03*
Y827354D03*
Y830754D03*
Y838356D03*
Y841756D03*
X1075166Y780256D03*
Y786949D03*
Y803681D03*
Y793642D03*
Y796988D03*
Y817067D03*
Y810374D03*
Y823760D03*
Y830453D03*
Y833799D03*
Y840492D03*
Y847185D03*
Y853878D03*
Y860571D03*
Y877303D03*
Y867264D03*
Y870610D03*
Y883996D03*
Y890689D03*
Y897382D03*
Y904075D03*
Y907422D03*
Y914114D03*
Y920807D03*
Y927500D03*
Y934193D03*
Y940886D03*
Y950925D03*
Y944233D03*
Y964311D03*
Y957618D03*
Y971004D03*
X1067107Y960965D03*
X1075166Y977697D03*
Y984390D03*
Y1001122D03*
Y997776D03*
Y991083D03*
Y1031240D03*
Y1037933D03*
Y1044626D03*
Y1058012D03*
Y1051319D03*
Y1074744D03*
Y1081437D03*
Y1088130D03*
Y1098170D03*
Y1104862D03*
Y1091477D03*
Y1111555D03*
Y1118248D03*
Y1134981D03*
Y1124941D03*
Y1128288D03*
Y1148366D03*
Y1141674D03*
Y1155059D03*
Y1161752D03*
Y1165099D03*
Y1171792D03*
Y1178485D03*
Y1185177D03*
Y1191870D03*
Y1208603D03*
Y1198563D03*
Y1201910D03*
Y1215296D03*
Y1221988D03*
Y1228681D03*
Y1235374D03*
Y1238721D03*
Y1245414D03*
Y1252107D03*
X1091308Y776910D03*
Y783603D03*
Y790296D03*
Y800335D03*
Y807028D03*
Y793642D03*
Y813721D03*
Y820414D03*
Y837146D03*
Y830453D03*
Y827107D03*
Y843839D03*
Y850532D03*
Y857225D03*
Y863918D03*
Y873957D03*
Y880650D03*
Y867264D03*
Y887343D03*
Y894036D03*
Y910768D03*
Y904075D03*
Y900729D03*
Y924154D03*
Y917461D03*
Y930847D03*
Y940886D03*
Y937540D03*
Y947579D03*
Y954272D03*
Y967658D03*
Y974351D03*
Y981044D03*
Y987736D03*
Y994429D03*
Y1001122D03*
Y1027894D03*
Y1034587D03*
Y1041280D03*
Y1047973D03*
Y1054666D03*
Y1061359D03*
Y1071398D03*
Y1064705D03*
Y1078091D03*
Y1088130D03*
Y1084784D03*
Y1094823D03*
Y1101516D03*
Y1108209D03*
Y1114902D03*
Y1131634D03*
Y1124941D03*
Y1121595D03*
Y1138327D03*
Y1145020D03*
Y1151713D03*
Y1161752D03*
Y1158406D03*
Y1168445D03*
Y1175138D03*
Y1181831D03*
Y1188524D03*
Y1205256D03*
Y1198563D03*
Y1195217D03*
Y1211949D03*
Y1218642D03*
Y1225335D03*
Y1235374D03*
Y1232028D03*
Y1242067D03*
Y1248760D03*
X1104866Y780256D03*
Y786949D03*
Y803681D03*
Y793642D03*
Y796988D03*
Y817067D03*
Y810374D03*
Y823760D03*
Y830453D03*
Y833799D03*
Y840492D03*
Y847185D03*
Y853878D03*
Y860571D03*
Y877303D03*
Y867264D03*
Y870610D03*
Y883996D03*
Y890689D03*
Y897382D03*
Y904075D03*
Y907422D03*
Y914114D03*
Y920807D03*
Y927500D03*
Y934193D03*
Y940886D03*
Y950925D03*
Y944233D03*
Y964311D03*
Y957618D03*
Y971004D03*
Y977697D03*
Y984390D03*
Y1001122D03*
Y997776D03*
Y991083D03*
Y1031240D03*
Y1037933D03*
Y1044626D03*
Y1058012D03*
Y1051319D03*
Y1074744D03*
Y1081437D03*
Y1088130D03*
Y1098170D03*
Y1104862D03*
Y1091477D03*
Y1111555D03*
Y1118248D03*
Y1134981D03*
Y1124941D03*
Y1128288D03*
Y1148366D03*
Y1141674D03*
Y1155059D03*
Y1161752D03*
Y1165099D03*
Y1171792D03*
Y1178485D03*
Y1185177D03*
Y1191870D03*
Y1208603D03*
Y1198563D03*
Y1201910D03*
Y1215296D03*
Y1221988D03*
Y1228681D03*
Y1235374D03*
Y1238721D03*
Y1245414D03*
Y1252107D03*
X1121008Y776910D03*
Y783603D03*
Y790296D03*
Y800335D03*
Y807028D03*
Y793642D03*
Y813721D03*
Y820414D03*
Y837146D03*
Y830453D03*
Y827107D03*
Y843839D03*
Y850532D03*
Y857225D03*
Y863918D03*
Y873957D03*
Y880650D03*
Y867264D03*
Y887343D03*
Y894036D03*
Y910768D03*
Y904075D03*
Y900729D03*
Y924154D03*
Y917461D03*
Y930847D03*
Y940886D03*
Y937540D03*
Y947579D03*
Y954272D03*
Y967658D03*
Y974351D03*
Y981044D03*
Y987736D03*
Y994429D03*
Y1001122D03*
Y1027894D03*
Y1034587D03*
Y1041280D03*
Y1047973D03*
Y1054666D03*
Y1061359D03*
Y1071398D03*
Y1064705D03*
Y1078091D03*
Y1088130D03*
Y1084784D03*
Y1094823D03*
Y1101516D03*
Y1108209D03*
Y1114902D03*
Y1131634D03*
Y1124941D03*
Y1121595D03*
Y1138327D03*
Y1145020D03*
Y1151713D03*
Y1161752D03*
Y1158406D03*
Y1168445D03*
Y1175138D03*
Y1181831D03*
Y1188524D03*
Y1205256D03*
Y1198563D03*
Y1195217D03*
Y1211949D03*
Y1218642D03*
Y1225335D03*
Y1235374D03*
Y1232028D03*
Y1242067D03*
Y1248760D03*
X1134567Y780256D03*
Y786949D03*
Y803681D03*
Y793642D03*
Y796988D03*
Y817067D03*
Y810374D03*
Y823760D03*
Y830453D03*
Y833799D03*
Y840492D03*
Y847185D03*
Y853878D03*
Y860571D03*
Y877303D03*
Y867264D03*
Y870610D03*
Y883996D03*
Y890689D03*
Y897382D03*
Y904075D03*
Y907422D03*
Y914114D03*
Y920807D03*
Y927500D03*
Y934193D03*
Y940886D03*
Y950925D03*
Y944233D03*
Y964311D03*
Y957618D03*
Y971004D03*
Y977697D03*
Y984390D03*
Y1001122D03*
Y997776D03*
Y991083D03*
Y1031240D03*
Y1037933D03*
Y1044626D03*
Y1058012D03*
Y1051319D03*
Y1074744D03*
Y1081437D03*
Y1088130D03*
Y1098170D03*
Y1104862D03*
Y1091477D03*
Y1111555D03*
Y1118248D03*
Y1134981D03*
Y1124941D03*
Y1128288D03*
Y1148366D03*
Y1141674D03*
Y1155059D03*
Y1161752D03*
Y1165099D03*
Y1171792D03*
Y1178485D03*
Y1185177D03*
Y1191870D03*
Y1208603D03*
Y1198563D03*
Y1201910D03*
Y1215296D03*
Y1221988D03*
Y1228681D03*
Y1235374D03*
Y1238721D03*
Y1245414D03*
Y1252107D03*
X1150709Y776910D03*
Y783603D03*
Y790296D03*
Y800335D03*
Y807028D03*
Y793642D03*
Y813721D03*
Y820414D03*
Y837146D03*
Y830453D03*
Y827107D03*
Y843839D03*
Y850532D03*
Y857225D03*
Y863918D03*
Y873957D03*
Y880650D03*
Y867264D03*
Y887343D03*
Y894036D03*
Y910768D03*
Y904075D03*
Y900729D03*
Y924154D03*
Y917461D03*
Y930847D03*
Y940886D03*
Y937540D03*
Y947579D03*
Y954272D03*
Y967658D03*
Y974351D03*
Y981044D03*
Y987736D03*
Y994429D03*
Y1001122D03*
Y1027894D03*
Y1034587D03*
Y1041280D03*
Y1047973D03*
Y1054666D03*
Y1061359D03*
Y1071398D03*
Y1064705D03*
Y1078091D03*
Y1088130D03*
Y1084784D03*
Y1094823D03*
Y1101516D03*
Y1108209D03*
Y1114902D03*
Y1131634D03*
Y1124941D03*
Y1121595D03*
Y1138327D03*
Y1145020D03*
Y1151713D03*
Y1161752D03*
Y1158406D03*
Y1168445D03*
Y1175138D03*
Y1181831D03*
Y1188524D03*
Y1205256D03*
Y1198563D03*
Y1195217D03*
Y1211949D03*
Y1218642D03*
Y1225335D03*
Y1235374D03*
Y1232028D03*
Y1242067D03*
Y1248760D03*
X1170986Y1516590D03*
Y1513190D03*
Y1534990D03*
Y1538390D03*
X1177404Y-21711D03*
Y-18311D03*
Y-11711D03*
Y-8311D03*
Y11689D03*
Y8289D03*
Y18289D03*
Y21689D03*
X1183924Y1485895D03*
X1180624Y1495595D03*
X1177224D03*
X1185910Y960965D03*
X1187324Y1485895D03*
X1200724Y1505295D03*
X1197324D03*
X1196039Y1625380D03*
X1199439D03*
X1214124Y1485895D03*
X1210724D03*
X1207424Y1495595D03*
X1204024D03*
X1208099Y1625380D03*
X1211499D03*
X1227524Y1505295D03*
X1224124D03*
X1230824Y1495595D03*
X1220159Y1625380D03*
X1223559D03*
X1240924Y1485895D03*
X1237524D03*
X1234224Y1495595D03*
X1232219Y1625380D03*
X1244279D03*
X1235619D03*
X1245840Y-28311D03*
Y-31711D03*
Y-18311D03*
Y-21711D03*
Y1689D03*
Y-1711D03*
Y11689D03*
Y8289D03*
X1254324Y1505295D03*
X1250924D03*
X1257624Y1495595D03*
X1256339Y1625380D03*
X1247679D03*
X1259739D03*
X1267724Y1485895D03*
X1264324D03*
X1261024Y1495595D03*
X1268399Y1625380D03*
X1271799D03*
X1277724Y1485895D03*
X1281124D03*
X1288494Y1517082D03*
Y1513682D03*
Y1530482D03*
Y1527082D03*
X1280459Y1625380D03*
X1283859D03*
X1305286Y1495595D03*
X1299048Y1516590D03*
Y1513190D03*
Y1534990D03*
Y1538390D03*
X1292519Y1625380D03*
X1304579D03*
X1295919D03*
X1315386Y1485895D03*
X1311986D03*
X1308686Y1495595D03*
X1316639Y1625380D03*
X1320039D03*
X1307979D03*
X1328786Y1505295D03*
X1325386D03*
X1332086Y1495595D03*
X1328699Y1625380D03*
X1332099D03*
X1342186Y1485895D03*
X1338786D03*
X1335486Y1495595D03*
X1340759Y1625380D03*
X1344159D03*
X1355586Y1505295D03*
X1362286Y1495595D03*
X1352186Y1505295D03*
X1358886Y1495595D03*
X1352819Y1625380D03*
X1356219D03*
X1368986Y1485895D03*
X1365586D03*
X1378986Y1505295D03*
X1364879Y1625380D03*
X1376939D03*
X1368279D03*
X1392386Y1485895D03*
X1382386Y1505295D03*
X1389086Y1495595D03*
X1385686D03*
X1380339Y1625380D03*
X1395786Y1485895D03*
X1409186D03*
X1405786D03*
X1416556Y1513682D03*
Y1517082D03*
Y1530482D03*
Y1527082D03*
X1436263Y-28311D03*
Y-31711D03*
Y-18311D03*
Y-21711D03*
Y1689D03*
Y-1711D03*
Y11689D03*
Y8289D03*
X1460213Y1625380D03*
X1463613D03*
X1472273D03*
X1475673D03*
X1484333D03*
X1496393D03*
X1487733D03*
X1508453D03*
X1499793D03*
X1511853D03*
X1520513D03*
X1523913D03*
X1539134Y-35912D03*
Y-32512D03*
Y-22512D03*
Y-25912D03*
X1535566Y69340D03*
X1538966D03*
X1532573Y1625380D03*
X1535973D03*
X1557566Y69340D03*
X1546562Y75343D03*
X1549962D03*
X1544633Y1625380D03*
X1556693D03*
X1548033D03*
X1568566Y75340D03*
X1571966D03*
X1560966Y69340D03*
X1568753Y1625380D03*
X1560093D03*
X1572153D03*
X1579566Y69340D03*
X1582966D03*
X1580813Y1625380D03*
X1584213D03*
X1590566Y75340D03*
X1601562Y69343D03*
X1593966Y75340D03*
X1592873Y1625380D03*
X1596273D03*
X1612566Y75340D03*
X1615966D03*
X1604962Y69343D03*
X1604933Y1625380D03*
X1616993D03*
X1608333D03*
X1623562Y69343D03*
X1626962D03*
X1629053Y1625380D03*
X1620393D03*
X1632453D03*
X1646770Y69340D03*
X1635770Y75340D03*
X1639170D03*
X1641113Y1625380D03*
X1644513D03*
X1657766Y75343D03*
X1661166D03*
X1650170Y69340D03*
X1668770D03*
X1672170D03*
X1663839Y960965D03*
X1690900Y69343D03*
X1679904Y75340D03*
X1683304D03*
X1682898Y780256D03*
Y786949D03*
Y803681D03*
Y793642D03*
Y796988D03*
Y817067D03*
Y810374D03*
Y823760D03*
Y830453D03*
Y833799D03*
Y840492D03*
Y847185D03*
Y853878D03*
Y860571D03*
Y877303D03*
Y867264D03*
Y870610D03*
Y883996D03*
Y890689D03*
Y897382D03*
Y904075D03*
Y907422D03*
Y914114D03*
Y920807D03*
Y927500D03*
Y934193D03*
Y940886D03*
Y950925D03*
Y944233D03*
Y964311D03*
Y957618D03*
Y971004D03*
Y977697D03*
Y984390D03*
Y1001122D03*
Y997776D03*
Y991083D03*
Y1031240D03*
Y1037933D03*
Y1044626D03*
Y1058012D03*
Y1051319D03*
Y1074744D03*
Y1081437D03*
Y1088130D03*
Y1098170D03*
Y1104862D03*
Y1091477D03*
Y1111555D03*
Y1118248D03*
Y1134981D03*
Y1124941D03*
Y1128288D03*
Y1148366D03*
Y1141674D03*
Y1155059D03*
Y1161752D03*
Y1165099D03*
Y1171792D03*
Y1178485D03*
Y1185177D03*
Y1191870D03*
Y1208603D03*
Y1198563D03*
Y1201910D03*
Y1215296D03*
Y1221988D03*
Y1228681D03*
Y1235374D03*
Y1238721D03*
Y1245414D03*
Y1252107D03*
X1701904Y75340D03*
X1705304D03*
X1694300Y69343D03*
X1699040Y776910D03*
Y783603D03*
Y790296D03*
Y800335D03*
Y807028D03*
Y793642D03*
Y813721D03*
Y820414D03*
Y837146D03*
Y830453D03*
Y827107D03*
Y843839D03*
Y850532D03*
Y857225D03*
Y863918D03*
Y873957D03*
Y880650D03*
Y867264D03*
Y887343D03*
Y894036D03*
Y910768D03*
Y904075D03*
Y900729D03*
Y924154D03*
Y917461D03*
Y930847D03*
Y940886D03*
Y937540D03*
Y947579D03*
Y954272D03*
Y967658D03*
Y974351D03*
Y981044D03*
Y987736D03*
Y994429D03*
Y1001122D03*
Y1027894D03*
Y1034587D03*
Y1041280D03*
Y1047973D03*
Y1054666D03*
Y1061359D03*
Y1071398D03*
Y1064705D03*
Y1078091D03*
Y1088130D03*
Y1084784D03*
Y1094823D03*
Y1101516D03*
Y1108209D03*
Y1114902D03*
Y1131634D03*
Y1124941D03*
Y1121595D03*
Y1138327D03*
Y1145020D03*
Y1151713D03*
Y1161752D03*
Y1158406D03*
Y1168445D03*
Y1175138D03*
Y1181831D03*
Y1188524D03*
Y1205256D03*
Y1198563D03*
Y1195217D03*
Y1211949D03*
Y1218642D03*
Y1225335D03*
Y1235374D03*
Y1232028D03*
Y1242067D03*
Y1248760D03*
X1712599Y780256D03*
Y786949D03*
Y803681D03*
Y793642D03*
Y796988D03*
Y817067D03*
Y810374D03*
Y823760D03*
Y830453D03*
Y833799D03*
Y840492D03*
Y847185D03*
Y853878D03*
Y860571D03*
Y877303D03*
Y867264D03*
Y870610D03*
Y883996D03*
Y890689D03*
Y897382D03*
Y904075D03*
Y907422D03*
Y914114D03*
Y920807D03*
Y927500D03*
Y934193D03*
Y940886D03*
Y950925D03*
Y944233D03*
Y964311D03*
Y957618D03*
Y971004D03*
Y977697D03*
Y984390D03*
Y1001122D03*
Y997776D03*
Y991083D03*
Y1031240D03*
Y1037933D03*
Y1044626D03*
Y1058012D03*
Y1051319D03*
Y1074744D03*
Y1081437D03*
Y1088130D03*
Y1098170D03*
Y1104862D03*
Y1091477D03*
Y1111555D03*
Y1118248D03*
Y1134981D03*
Y1124941D03*
Y1128288D03*
Y1148366D03*
Y1141674D03*
Y1155059D03*
Y1161752D03*
Y1165099D03*
Y1171792D03*
Y1178485D03*
Y1185177D03*
Y1191870D03*
Y1208603D03*
Y1198563D03*
Y1201910D03*
Y1215296D03*
Y1221988D03*
Y1228681D03*
Y1235374D03*
Y1238721D03*
Y1245414D03*
Y1252107D03*
X1729557Y-35912D03*
Y-32512D03*
Y-22512D03*
Y-25912D03*
X1728741Y776910D03*
Y783603D03*
Y790296D03*
Y800335D03*
Y807028D03*
Y793642D03*
Y813721D03*
Y820414D03*
Y837146D03*
Y830453D03*
Y827107D03*
Y843839D03*
Y850532D03*
Y857225D03*
Y863918D03*
Y873957D03*
Y880650D03*
Y867264D03*
Y887343D03*
Y894036D03*
Y910768D03*
Y904075D03*
Y900729D03*
Y924154D03*
Y917461D03*
Y930847D03*
Y940886D03*
Y937540D03*
Y947579D03*
Y954272D03*
Y967658D03*
Y974351D03*
Y981044D03*
Y987736D03*
Y994429D03*
Y1001122D03*
Y1027894D03*
Y1034587D03*
Y1041280D03*
Y1047973D03*
Y1054666D03*
Y1061359D03*
Y1071398D03*
Y1064705D03*
Y1078091D03*
Y1088130D03*
Y1084784D03*
Y1094823D03*
Y1101516D03*
Y1108209D03*
Y1114902D03*
Y1131634D03*
Y1124941D03*
Y1121595D03*
Y1138327D03*
Y1145020D03*
Y1151713D03*
Y1161752D03*
Y1158406D03*
Y1168445D03*
Y1175138D03*
Y1181831D03*
Y1188524D03*
Y1205256D03*
Y1198563D03*
Y1195217D03*
Y1211949D03*
Y1218642D03*
Y1225335D03*
Y1235374D03*
Y1232028D03*
Y1242067D03*
Y1248760D03*
X1742300Y780256D03*
Y786949D03*
Y803681D03*
Y793642D03*
Y796988D03*
Y817067D03*
Y810374D03*
Y823760D03*
Y830453D03*
Y833799D03*
Y840492D03*
Y847185D03*
Y853878D03*
Y860571D03*
Y877303D03*
Y867264D03*
Y870610D03*
Y883996D03*
Y890689D03*
Y897382D03*
Y904075D03*
Y907422D03*
Y914114D03*
Y920807D03*
Y927500D03*
Y934193D03*
Y940886D03*
Y950925D03*
Y944233D03*
Y964311D03*
Y957618D03*
Y971004D03*
Y977697D03*
Y984390D03*
Y1001122D03*
Y997776D03*
Y991083D03*
Y1031240D03*
Y1037933D03*
Y1044626D03*
Y1058012D03*
Y1051319D03*
Y1074744D03*
Y1081437D03*
Y1088130D03*
Y1098170D03*
Y1104862D03*
Y1091477D03*
Y1111555D03*
Y1118248D03*
Y1134981D03*
Y1124941D03*
Y1128288D03*
Y1148366D03*
Y1141674D03*
Y1155059D03*
Y1161752D03*
Y1165099D03*
Y1171792D03*
Y1178485D03*
Y1185177D03*
Y1191870D03*
Y1208603D03*
Y1198563D03*
Y1201910D03*
Y1215296D03*
Y1221988D03*
Y1228681D03*
Y1235374D03*
Y1238721D03*
Y1245414D03*
Y1252107D03*
X1758442Y776910D03*
Y783603D03*
Y790296D03*
Y800335D03*
Y807028D03*
Y793642D03*
Y813721D03*
Y820414D03*
Y837146D03*
Y830453D03*
Y827107D03*
Y843839D03*
Y850532D03*
Y857225D03*
Y863918D03*
Y873957D03*
Y880650D03*
Y867264D03*
Y887343D03*
Y894036D03*
Y910768D03*
Y904075D03*
Y900729D03*
Y924154D03*
Y917461D03*
Y930847D03*
Y940886D03*
Y937540D03*
Y947579D03*
Y954272D03*
Y967658D03*
Y974351D03*
Y981044D03*
Y987736D03*
Y994429D03*
Y1001122D03*
Y1027894D03*
Y1034587D03*
Y1041280D03*
Y1047973D03*
Y1054666D03*
Y1061359D03*
Y1071398D03*
Y1064705D03*
Y1078091D03*
Y1088130D03*
Y1084784D03*
Y1094823D03*
Y1101516D03*
Y1108209D03*
Y1114902D03*
Y1131634D03*
Y1124941D03*
Y1121595D03*
Y1138327D03*
Y1145020D03*
Y1151713D03*
Y1161752D03*
Y1158406D03*
Y1168445D03*
Y1175138D03*
Y1181831D03*
Y1188524D03*
Y1205256D03*
Y1198563D03*
Y1195217D03*
Y1211949D03*
Y1218642D03*
Y1225335D03*
Y1235374D03*
Y1232028D03*
Y1242067D03*
Y1248760D03*
X1782642Y960965D03*
G54D22*
X60303Y20354D03*
X312921Y24291D03*
X505185Y41141D03*
X757803Y45078D03*
X929331Y160413D03*
X922441Y237697D03*
X1534712Y20354D03*
X1787330Y24291D03*
G54D32*
X205478Y1536063D03*
X210202D03*
X219651D03*
X229100D03*
X233824D03*
X243273D03*
X253002Y1514243D03*
X252722Y1536063D03*
X302413Y906182D03*
Y912560D03*
Y918938D03*
Y925316D03*
Y931694D03*
Y938072D03*
Y944450D03*
Y950828D03*
Y957206D03*
Y963584D03*
Y969962D03*
Y976340D03*
Y982718D03*
Y989096D03*
Y995474D03*
Y1008230D03*
Y1001852D03*
X303594Y1030198D03*
Y1036576D03*
Y1042954D03*
Y1055710D03*
Y1049332D03*
Y1062088D03*
Y1074844D03*
Y1068466D03*
Y1081222D03*
Y1087600D03*
Y1093978D03*
Y1100356D03*
Y1106734D03*
Y1113112D03*
Y1119490D03*
Y1125868D03*
Y1132246D03*
Y1138623D03*
Y1145001D03*
Y1157757D03*
Y1151379D03*
X333540Y1536063D03*
X338264D03*
X347713D03*
X357162D03*
X361886D03*
X380784D03*
X371335D03*
X381064Y1514243D03*
X408614Y997608D03*
X410464Y1007175D03*
X404923Y1010366D03*
X423417Y997608D03*
X416015D03*
X430819D03*
X445622D03*
X453023D03*
X467826D03*
X460425D03*
X469651Y1536063D03*
X483824D03*
X474375D03*
X497997D03*
X493273D03*
X507446D03*
X526370Y1165290D03*
X515268D03*
X518969D03*
X522670D03*
X517175Y1514243D03*
X516895Y1536063D03*
X533772Y1165290D03*
X530071D03*
X602437Y1536063D03*
X597713D03*
X611886D03*
X626059D03*
X621335D03*
X645237Y1514243D03*
X644957Y1536063D03*
X635508D03*
X1213351Y1569063D03*
X1227524D03*
X1218075D03*
X1241697D03*
X1236973D03*
X1251146D03*
X1260875Y1547243D03*
X1260595Y1569063D03*
X1278555Y906181D03*
Y912559D03*
Y918937D03*
Y925315D03*
Y931693D03*
Y938071D03*
Y950827D03*
Y944449D03*
Y957205D03*
Y963583D03*
Y969961D03*
Y976339D03*
Y982717D03*
Y995473D03*
Y989095D03*
Y1008229D03*
Y1001851D03*
X1279736Y1030197D03*
Y1042953D03*
Y1036575D03*
Y1055709D03*
Y1049331D03*
Y1062087D03*
Y1068465D03*
Y1074843D03*
Y1081221D03*
Y1087599D03*
Y1093977D03*
Y1100355D03*
Y1106733D03*
Y1113111D03*
Y1119489D03*
Y1125867D03*
Y1132245D03*
Y1138622D03*
Y1145000D03*
Y1151378D03*
Y1157756D03*
X1346137Y1569063D03*
X1341413D03*
X1355586D03*
X1379208D03*
X1369759D03*
X1365035D03*
X1384756Y997607D03*
X1392157D03*
X1386606Y1007174D03*
X1381065Y1010365D03*
X1388937Y1547243D03*
X1388657Y1569063D03*
X1406961Y997607D03*
X1399559D03*
X1421764D03*
X1436567D03*
X1429165D03*
X1443968D03*
X1482249Y1569063D03*
X1477525D03*
X1491698D03*
X1502512Y1165289D03*
X1505871Y1569063D03*
X1501147D03*
X1525049Y1547243D03*
X1524769Y1569063D03*
X1515320D03*
X1610311D03*
X1605587D03*
X1629209D03*
X1619760D03*
X1643382D03*
X1633933D03*
X1653111Y1547243D03*
X1652831Y1569063D03*
G54D43*
X381770Y-30570D03*
X385023Y-30584D03*
X388048Y-29264D03*
X381755Y-28055D03*
X385008Y-28069D03*
X381740Y-25540D03*
X381725Y-23025D03*
X723479Y-19234D03*
Y-9234D03*
X833421Y-36647D03*
X839699Y-35341D03*
X833406Y-34132D03*
X836674Y-36661D03*
X836659Y-34146D03*
X833391Y-31617D03*
X833376Y-29102D03*
X836644Y-31631D03*
X836629Y-29116D03*
X1174958Y-15374D03*
Y-5374D03*
Y24626D03*
X1433817Y-25374D03*
Y-15374D03*
Y14626D03*
X1530063Y-40911D03*
X1530033Y-35881D03*
X1530018Y-33366D03*
X1530048Y-38396D03*
X1533316Y-40925D03*
X1536341Y-39605D03*
X1533301Y-38410D03*
X1727111Y-19575D03*
G54D81*
X1898799Y1198198D03*
X1908799D03*
X1921395Y-39963D03*
X1931395D03*
X1942395Y572417D03*
X1940886Y1198170D03*
X1963362Y-39821D03*
X1952395Y572417D03*
X1950886Y1198170D03*
X1973362Y-39821D03*
X1984482Y572389D03*
X1982856Y1198350D03*
X1992856D03*
X2005452Y-39811D03*
X1994482Y572389D03*
X2015452Y-39811D03*
X2026452Y572569D03*
X2036452D03*
X2047419Y-39669D03*
X2057419D03*
X2068539Y572541D03*
X2078539D03*
G54D47*
X539016Y274272D03*
X559016D03*
X569016D03*
X579016D03*
X589016D03*
X599016D03*
X609016D03*
G54D61*
X918780Y1684890D03*
Y1694890D03*
Y1714890D03*
X928780Y1684890D03*
Y1694890D03*
Y1704890D03*
Y1714890D03*
X938780Y1684890D03*
Y1694890D03*
Y1704890D03*
Y1714890D03*
G54D66*
X1225530Y67471D03*
X1454797Y80345D03*
G54D79*
X1900275Y-29973D03*
Y562227D03*
X1898799Y1208198D03*
Y1800398D03*
X1910275Y-29973D03*
Y562227D03*
X1908799Y1208198D03*
Y1800398D03*
X1921395Y-29963D03*
X1931395D03*
Y562237D03*
X1921395D03*
X1931395Y582237D03*
X1921395D03*
Y1174437D03*
X1931395D03*
X1929766Y1208160D03*
X1919766D03*
Y1800360D03*
X1929766D03*
X1942395Y-29783D03*
Y562417D03*
Y582417D03*
Y1174617D03*
X1940886Y1208170D03*
Y1800370D03*
X1952395Y-29783D03*
Y562417D03*
Y582417D03*
Y1174617D03*
X1950886Y1208170D03*
X1961856D03*
X1950886Y1800370D03*
X1961856D03*
X1963362Y-29821D03*
X1973362D03*
Y562379D03*
X1963362D03*
X1973362Y582379D03*
X1963362D03*
Y1174579D03*
X1973362D03*
X1971856Y1208170D03*
Y1800370D03*
X1984482Y-29811D03*
Y562389D03*
Y582389D03*
Y1174589D03*
X1982856Y1208350D03*
Y1800550D03*
X1994482Y-29811D03*
X2005452D03*
X1994482Y562389D03*
X2005452D03*
Y582389D03*
X1994482D03*
Y1174589D03*
X2005452D03*
X1992856Y1208350D03*
X2003823Y1208312D03*
X1992856Y1800550D03*
X2003823Y1800512D03*
X2015452Y-29811D03*
Y562389D03*
Y582389D03*
Y1174589D03*
X2013823Y1208312D03*
Y1800512D03*
X2036452Y-29631D03*
X2026452D03*
Y562569D03*
X2036452D03*
X2026452Y582569D03*
X2036452D03*
Y1174769D03*
X2026452D03*
X2047419Y-29669D03*
Y562531D03*
Y582531D03*
Y1174731D03*
X2057419Y-29669D03*
Y562531D03*
Y582531D03*
Y1174731D03*
X2068539Y582541D03*
X2078539D03*
Y1174741D03*
X2068539D03*
G54D80*
X1900275Y572227D03*
X1910275D03*
X1921395Y1184437D03*
X1931395D03*
X1919766Y1810360D03*
X1929766D03*
X1942395Y572417D03*
X1952395D03*
X1963362Y1184579D03*
X1961856Y1810370D03*
X1973362Y1184579D03*
X1971856Y1810370D03*
X1984482Y572389D03*
X1994482D03*
X2005452Y1184589D03*
X2003823Y1810512D03*
X2015452Y1184589D03*
X2013823Y1810512D03*
X2026452Y572569D03*
X2036452D03*
X2047419Y1184731D03*
X2057419D03*
G54D50*
X676509Y224606D03*
G54D31*
X188155Y1530608D03*
X192879D03*
X197604D03*
X189730Y1533336D03*
X194454D03*
X199178D03*
X202328Y1530608D03*
X207052D03*
X211777D03*
X216501D03*
X203903Y1533336D03*
X208627D03*
X213352D03*
X221226Y1530608D03*
X225950D03*
X230674D03*
X218076Y1533336D03*
X222800D03*
X227525D03*
X235399Y1530608D03*
X240123D03*
X244848D03*
X236974Y1533336D03*
X241698D03*
X246422D03*
X232249D03*
X249572Y1530608D03*
X254297D03*
X259021D03*
X251147Y1533336D03*
X255871D03*
X260596D03*
X317957Y886002D03*
X319807Y889191D03*
Y895569D03*
X317957Y892380D03*
X319807Y908325D03*
X317957Y898758D03*
X319807Y901947D03*
X317957Y905135D03*
Y911513D03*
Y917891D03*
X319807Y921080D03*
X317957Y924269D03*
X319807Y914702D03*
Y927458D03*
X317957Y937025D03*
X319807Y940214D03*
Y933836D03*
X317957Y930647D03*
Y943403D03*
X319807Y946592D03*
X317957Y956159D03*
X319807Y952970D03*
X317957Y949781D03*
Y962537D03*
X319807Y965726D03*
Y959348D03*
X317957Y968915D03*
Y975293D03*
X319807Y978482D03*
Y972104D03*
X317957Y994427D03*
X319807Y997616D03*
X317957Y1000805D03*
X319807Y991238D03*
Y1010372D03*
X317957Y1007183D03*
X319807Y1003994D03*
X320988Y1034434D03*
X319138Y1037623D03*
X320988Y1040812D03*
X319138Y1044001D03*
X320988Y1059946D03*
X319138Y1050379D03*
X320988Y1053568D03*
Y1072702D03*
X319138Y1063135D03*
Y1069513D03*
X320988Y1066324D03*
X319138Y1075891D03*
X320988Y1079080D03*
X319138Y1082269D03*
Y1088647D03*
X320988Y1085458D03*
X319138Y1101403D03*
X320988Y1091836D03*
X319138Y1095025D03*
X320988Y1098214D03*
Y1104592D03*
Y1110970D03*
X319138Y1114159D03*
X320988Y1117348D03*
X319138Y1107781D03*
Y1120537D03*
X320988Y1130103D03*
X319138Y1133293D03*
Y1126915D03*
X320988Y1123726D03*
Y1136481D03*
X319138Y1139670D03*
X320988Y1149237D03*
X319138Y1146048D03*
X320988Y1142859D03*
X319138Y1152426D03*
X323508Y889191D03*
X325358Y892380D03*
X323508Y895569D03*
X325358Y911513D03*
X323508Y901947D03*
X325358Y905135D03*
X323508Y908325D03*
X325358Y898758D03*
X323508Y921080D03*
X325358Y924269D03*
X323508Y914702D03*
X325358Y917891D03*
X323508Y927458D03*
X325358Y930647D03*
X323508Y940214D03*
Y933836D03*
X325358Y937025D03*
Y943403D03*
X323508Y946592D03*
X325358Y949781D03*
X323508Y952970D03*
X325358Y956159D03*
X323508Y965726D03*
X325358Y968915D03*
X323508Y959348D03*
X325358Y962537D03*
X323508Y984860D03*
Y978482D03*
X325358Y981671D03*
X323508Y972104D03*
X325358Y975293D03*
Y988049D03*
X323508Y997616D03*
X325358Y1000805D03*
Y994427D03*
X323508Y1003994D03*
X325358Y1007183D03*
X326539Y1031245D03*
X324689Y1034434D03*
X326539Y1037623D03*
X324689Y1040812D03*
X326539Y1050379D03*
X324689Y1047190D03*
X326539Y1063135D03*
X324689Y1066324D03*
X326539Y1069513D03*
X324689Y1072702D03*
X326539Y1075891D03*
X324689Y1079080D03*
X326539Y1082269D03*
X324689Y1085458D03*
X326539Y1088647D03*
X324689Y1104592D03*
X326539Y1095025D03*
X324689Y1098214D03*
X326539Y1101403D03*
X324689Y1091836D03*
X326539Y1114159D03*
X324689Y1117348D03*
X326539Y1107781D03*
X324689Y1110970D03*
X326539Y1120537D03*
X324689Y1123726D03*
X326539Y1133293D03*
Y1126915D03*
X324689Y1130103D03*
Y1136481D03*
X326539Y1139670D03*
X324689Y1142859D03*
X326539Y1146048D03*
X324689Y1149237D03*
X326539Y1152426D03*
X324689Y1155615D03*
X358665Y886002D03*
X364217Y889191D03*
X356815D03*
X362366Y892380D03*
X356815Y895569D03*
X364217D03*
X358665Y892380D03*
X356815Y908325D03*
X362366Y911513D03*
X358665Y898758D03*
X364217Y901947D03*
X356815D03*
X362366Y905135D03*
X358665D03*
X364217Y908325D03*
X358665Y911513D03*
X362366Y898758D03*
X358665Y917891D03*
X364217Y921080D03*
X356815D03*
X362366Y924269D03*
X358665D03*
X356815Y914702D03*
X364217D03*
X362366Y917891D03*
X364217Y927458D03*
X356815D03*
X362366Y930647D03*
X358665Y937025D03*
X364217Y940214D03*
X356815D03*
Y933836D03*
X364217D03*
X358665Y930647D03*
X362366Y937025D03*
Y943403D03*
X358665D03*
X364217Y946592D03*
X356815D03*
X362366Y949781D03*
X358665Y956159D03*
X356815Y952970D03*
X364217D03*
X358665Y949781D03*
X362366Y956159D03*
X358665Y962537D03*
X364217Y965726D03*
X356815D03*
X362366Y968915D03*
X364217Y959348D03*
X356815D03*
X362366Y962537D03*
X358665Y968915D03*
X364217Y984860D03*
X358665Y975293D03*
X364217Y978482D03*
X356815D03*
X362366Y981671D03*
X356815Y972104D03*
X364217D03*
X362366Y975293D03*
Y988049D03*
X358665Y994427D03*
X356815Y997616D03*
X364217D03*
X362366Y1000805D03*
X358665D03*
X356815Y991238D03*
X362366Y994427D03*
X356815Y1010372D03*
X358665Y1007183D03*
X356815Y1003994D03*
X364217D03*
X362366Y1007183D03*
X363547Y1031245D03*
X365398Y1034434D03*
X357996D03*
X359847Y1037623D03*
X363547D03*
X365398Y1040812D03*
X357996D03*
X359847Y1044001D03*
X363547Y1050379D03*
X357996Y1059946D03*
X365398Y1047190D03*
X359847Y1050379D03*
X357996Y1053568D03*
Y1072702D03*
X363547Y1063135D03*
X359847D03*
X365398Y1066324D03*
X363547Y1069513D03*
X359847D03*
X365398Y1072702D03*
X357996Y1066324D03*
X363547Y1075891D03*
X359847D03*
X365398Y1079080D03*
X357996D03*
X363547Y1082269D03*
X359847D03*
X365398Y1085458D03*
X359847Y1088647D03*
X363547D03*
X357996Y1085458D03*
X359847Y1101403D03*
X365398Y1104592D03*
X357996Y1091836D03*
X363547Y1095025D03*
X359847D03*
X365398Y1098214D03*
X357996D03*
X363547Y1101403D03*
X357996Y1104592D03*
X365398Y1091836D03*
X357996Y1110970D03*
X363547Y1114159D03*
X359847D03*
X365398Y1117348D03*
X357996D03*
X359847Y1107781D03*
X363547D03*
X365398Y1110970D03*
X363547Y1120537D03*
X359847D03*
X365398Y1123726D03*
X357996Y1130103D03*
X363547Y1133293D03*
X359847D03*
Y1126915D03*
X363547D03*
X357996Y1123726D03*
X365398Y1130103D03*
Y1136481D03*
X357996D03*
X363547Y1139670D03*
X359847D03*
X365398Y1142859D03*
X357996Y1149237D03*
X359847Y1146048D03*
X363547D03*
X357996Y1142859D03*
X365398Y1149237D03*
X363547Y1152426D03*
X359847D03*
X357996Y1155615D03*
X369768Y886002D03*
X375319Y889191D03*
X371618D03*
X377169Y892380D03*
X371618Y895569D03*
X375319D03*
X369768Y892380D03*
X371618Y908325D03*
X377169Y911513D03*
X369768Y898758D03*
X375319Y901947D03*
X371618D03*
X377169Y905135D03*
X369768D03*
X375319Y908325D03*
X369768Y911513D03*
X377169Y898758D03*
X369768Y917891D03*
X375319Y921080D03*
X371618D03*
X377169Y924269D03*
X369768D03*
X371618Y914702D03*
X375319D03*
X377169Y917891D03*
X375319Y927458D03*
X371618D03*
X377169Y930647D03*
X369768Y937025D03*
X375319Y940214D03*
X371618D03*
Y933836D03*
X375319D03*
X369768Y930647D03*
X377169Y937025D03*
Y943403D03*
X369768D03*
X375319Y946592D03*
X371618D03*
X377169Y949781D03*
X369768Y956159D03*
X371618Y952970D03*
X375319D03*
X369768Y949781D03*
X377169Y956159D03*
X369768Y962537D03*
X375319Y965726D03*
X371618D03*
X377169Y968915D03*
X375319Y959348D03*
X371618D03*
X377169Y962537D03*
X369768Y968915D03*
X375319Y984860D03*
X369768Y975293D03*
X375319Y978482D03*
X371618D03*
X377169Y981671D03*
X371618Y972104D03*
X375319D03*
X377169Y975293D03*
Y988049D03*
X369768Y994427D03*
X371618Y997616D03*
X375319D03*
X377169Y1000805D03*
X369768D03*
X371618Y991238D03*
X377169Y994427D03*
X371618Y1010372D03*
X369768Y1007183D03*
X371618Y1003994D03*
X375319D03*
X377169Y1007183D03*
X378351Y1031245D03*
X376500Y1034434D03*
X372799D03*
X370949Y1037623D03*
X378351D03*
X376500Y1040812D03*
X372799D03*
X370949Y1044001D03*
X378351Y1050379D03*
X372799Y1059946D03*
X376500Y1047190D03*
X370949Y1050379D03*
X372799Y1053568D03*
Y1072702D03*
X378351Y1063135D03*
X370949D03*
X376500Y1066324D03*
X378351Y1069513D03*
X370949D03*
X376500Y1072702D03*
X372799Y1066324D03*
X378351Y1075891D03*
X370949D03*
X376500Y1079080D03*
X372799D03*
X378351Y1082269D03*
X370949D03*
X376500Y1085458D03*
X370949Y1088647D03*
X378351D03*
X372799Y1085458D03*
X370949Y1101403D03*
X376500Y1104592D03*
X372799Y1091836D03*
X378351Y1095025D03*
X370949D03*
X376500Y1098214D03*
X372799D03*
X378351Y1101403D03*
X372799Y1104592D03*
X376500Y1091836D03*
X372799Y1110970D03*
X378351Y1114159D03*
X370949D03*
X376500Y1117348D03*
X372799D03*
X370949Y1107781D03*
X378351D03*
X376500Y1110970D03*
X378351Y1120537D03*
X370949D03*
X376500Y1123726D03*
X372799Y1130103D03*
X378351Y1133293D03*
X370949D03*
Y1126915D03*
X378351D03*
X372799Y1123726D03*
X376500Y1130103D03*
Y1136481D03*
X372799D03*
X378351Y1139670D03*
X370949D03*
X376500Y1142859D03*
X372799Y1149237D03*
X370949Y1146048D03*
X378351D03*
X372799Y1142859D03*
X376500Y1149237D03*
X378351Y1152426D03*
X370949D03*
X376500Y1155615D03*
X388272Y892380D03*
X384571D03*
X395673D03*
X388272Y911513D03*
Y898758D03*
Y905135D03*
X384571Y911513D03*
Y898758D03*
Y905135D03*
X395673Y898758D03*
Y905135D03*
Y911513D03*
X388272Y924269D03*
Y917891D03*
X384571Y924269D03*
Y917891D03*
X395673Y924269D03*
Y917891D03*
X388272Y930647D03*
X384571D03*
X395673D03*
X384571Y949781D03*
Y943403D03*
Y956159D03*
X395673Y949781D03*
Y943403D03*
Y956159D03*
X388272Y949781D03*
Y943403D03*
Y956159D03*
X389453Y1114159D03*
Y1107781D03*
X385752Y1114159D03*
Y1107781D03*
X389453Y1120537D03*
X385752D03*
X389453Y1126915D03*
Y1133293D03*
X385752Y1126915D03*
Y1133293D03*
X389453Y1139670D03*
Y1146048D03*
X385752Y1139670D03*
Y1146048D03*
Y1158804D03*
X382051D03*
X393154D03*
X389453Y1152426D03*
X385752D03*
X399374Y892380D03*
X410477D03*
X406776D03*
X399374Y898758D03*
Y905135D03*
X410477Y898758D03*
Y905135D03*
X406776Y898758D03*
Y905135D03*
X399374Y911513D03*
X410477D03*
X406776D03*
X399374Y924269D03*
Y917891D03*
X410477D03*
Y924269D03*
X406776Y917891D03*
Y924269D03*
X399374Y930647D03*
X406776Y949781D03*
Y943403D03*
Y956159D03*
X399374Y949781D03*
Y943403D03*
Y956159D03*
X410477Y949781D03*
Y943403D03*
Y956159D03*
X400555Y1114159D03*
Y1107781D03*
X396855Y1114159D03*
Y1107781D03*
X407957Y1114159D03*
X400555Y1120537D03*
Y1126915D03*
X396855Y1120537D03*
Y1126915D03*
X407957Y1120537D03*
Y1126915D03*
X400555Y1133293D03*
X396855D03*
X407957D03*
X400555Y1139670D03*
Y1146048D03*
X396855Y1139670D03*
Y1146048D03*
X407957Y1139670D03*
Y1146048D03*
X396855Y1158804D03*
X407957D03*
X404256D03*
X400555Y1152426D03*
X396855D03*
X407957D03*
X421579Y892380D03*
X417878D03*
X421579Y898758D03*
Y905135D03*
X417878Y898758D03*
Y905135D03*
X421579Y911513D03*
X417878D03*
X421579Y917891D03*
Y924269D03*
X417878Y917891D03*
Y924269D03*
Y937025D03*
X421579D03*
X417878Y943403D03*
Y956159D03*
Y949781D03*
X421579Y943403D03*
Y956159D03*
Y949781D03*
X422760Y1114159D03*
X411658D03*
X419059D03*
X422760Y1120537D03*
Y1126915D03*
X411658Y1120537D03*
Y1126915D03*
X419059Y1120537D03*
Y1126915D03*
X422760Y1133293D03*
X411658D03*
X419059D03*
X422760Y1139670D03*
Y1146048D03*
X411658Y1139670D03*
Y1146048D03*
X419059Y1139670D03*
Y1146048D03*
Y1158804D03*
X415358D03*
X411658Y1152426D03*
X422760D03*
X419059D03*
X430831Y895569D03*
X427130D03*
X430831Y901947D03*
Y908325D03*
X427130Y901947D03*
Y908325D03*
X430831Y914702D03*
Y921080D03*
X427130Y914702D03*
Y921080D03*
X430831Y927458D03*
X427130D03*
Y940214D03*
X430831D03*
X427130Y946592D03*
Y952970D03*
X430831Y946592D03*
Y952970D03*
X432012Y1117348D03*
Y1110970D03*
X428311Y1117348D03*
Y1110970D03*
X432012Y1123726D03*
X428311D03*
X432012Y1130103D03*
X428311D03*
X432012Y1142859D03*
Y1136481D03*
X428311Y1142859D03*
Y1136481D03*
X449310Y895569D03*
X453011D03*
X449310Y908325D03*
Y901947D03*
X453011Y908325D03*
Y901947D03*
X450491Y1110970D03*
Y1117348D03*
X454192Y1110970D03*
Y1117348D03*
X450491Y1123726D03*
X454192D03*
X450491Y1130103D03*
X454192D03*
X450491Y1136481D03*
Y1142859D03*
X454192Y1136481D03*
Y1142859D03*
X452328Y1516970D03*
X453903Y1519698D03*
X452328Y1530608D03*
X453903Y1533336D03*
X458562Y892380D03*
X469664D03*
X462263D03*
X458562Y905135D03*
Y898758D03*
X469664Y905135D03*
Y898758D03*
X462263Y905135D03*
Y898758D03*
X459743Y1114159D03*
X463444D03*
X459743Y1126915D03*
Y1120537D03*
X463444Y1126915D03*
Y1120537D03*
X459743Y1133293D03*
X463444D03*
X459743Y1146048D03*
Y1139670D03*
X463444Y1146048D03*
Y1139670D03*
X457052Y1516970D03*
X461777D03*
X466501D03*
X458627Y1519698D03*
X463351D03*
X468076D03*
X457052Y1530608D03*
X461777D03*
X466501D03*
X458627Y1533336D03*
X463351D03*
X468076D03*
X480767Y892380D03*
X484467D03*
X473365D03*
X480767Y898758D03*
Y905135D03*
X484467Y898758D03*
X473365Y905135D03*
Y898758D03*
X484467Y905135D03*
X481948Y1114159D03*
X470845D03*
X481948Y1107781D03*
X474546Y1114159D03*
X481948Y1126915D03*
Y1120537D03*
X470845Y1126915D03*
Y1120537D03*
X474546Y1126915D03*
Y1120537D03*
X470845Y1133293D03*
X481948D03*
X474546D03*
X481948Y1146048D03*
Y1139670D03*
X470845Y1146048D03*
Y1139670D03*
X474546Y1146048D03*
Y1139670D03*
X471225Y1516970D03*
X475950D03*
X480674D03*
X472800Y1519698D03*
X477525D03*
X482249D03*
X471225Y1530608D03*
X475950D03*
X480674D03*
X472800Y1533336D03*
X477525D03*
X482249D03*
X491869Y892380D03*
X495570D03*
X491869Y905135D03*
Y898758D03*
Y911513D03*
X495570Y905135D03*
Y898758D03*
Y911513D03*
X493050Y1107781D03*
Y1114159D03*
X485649D03*
X496751Y1107781D03*
Y1114159D03*
X485649Y1107781D03*
X493050Y1120537D03*
X485649Y1126915D03*
Y1120537D03*
X496751D03*
X493050Y1133293D03*
Y1126915D03*
X496751Y1133293D03*
Y1126915D03*
X485649Y1133293D03*
X493050Y1146048D03*
Y1139670D03*
X485649Y1146048D03*
Y1139670D03*
X496751Y1146048D03*
Y1139670D03*
X499572Y1516970D03*
X485399D03*
X490123D03*
X494847D03*
X486973Y1519698D03*
X491698D03*
X496422D03*
X499572Y1530608D03*
X485399D03*
X490123D03*
X494847D03*
X486973Y1533336D03*
X491698D03*
X496422D03*
X510373Y886002D03*
X504822Y889191D03*
X508523D03*
X502971Y892380D03*
X508523Y895569D03*
X504822D03*
X510373Y892380D03*
X508523Y908325D03*
X502971Y911513D03*
X510373Y898758D03*
X504822Y901947D03*
X508523D03*
X502971Y905135D03*
X510373D03*
X504822Y908325D03*
X510373Y911513D03*
X502971Y898758D03*
X510373Y917891D03*
X504822Y921080D03*
X508523D03*
X502971Y924269D03*
X510373D03*
X508523Y914702D03*
X504822D03*
X502971Y917891D03*
X504822Y927458D03*
X508523D03*
X502971Y930647D03*
X510373Y937025D03*
X504822Y940214D03*
X508523D03*
Y933836D03*
X504822D03*
X510373Y930647D03*
X502971Y937025D03*
Y943403D03*
X510373D03*
X504822Y946592D03*
X508523D03*
X502971Y949781D03*
X510373Y956159D03*
X508523Y952970D03*
X504822D03*
X510373Y949781D03*
X502971Y956159D03*
X510373Y962537D03*
X504822Y965726D03*
X508523D03*
X502971Y968915D03*
X504822Y959348D03*
X508523D03*
X502971Y962537D03*
X510373Y968915D03*
X504822Y984860D03*
X510373Y975293D03*
X504822Y978482D03*
X508523D03*
X502971Y981671D03*
X508523Y972104D03*
X504822D03*
X502971Y975293D03*
Y988049D03*
X510373Y994427D03*
X508523Y997616D03*
X504822D03*
X502971Y1000805D03*
X510373D03*
Y988049D03*
X504822Y991238D03*
X508523Y1010372D03*
X510373Y1007183D03*
X508523Y1003994D03*
X504822D03*
X502971Y1007183D03*
X504153Y1031245D03*
X506003Y1034434D03*
X509704D03*
X511554Y1037623D03*
X504153D03*
X506003Y1040812D03*
X509704D03*
X504153Y1044001D03*
Y1050379D03*
X509704Y1059946D03*
X506003Y1047190D03*
X511554Y1050379D03*
X509704Y1053568D03*
Y1072702D03*
X504153Y1063135D03*
X511554D03*
X506003Y1066324D03*
X504153Y1069513D03*
X511554D03*
X506003Y1072702D03*
X509704Y1066324D03*
X504153Y1075891D03*
X511554D03*
X506003Y1079080D03*
X509704D03*
X504153Y1082269D03*
X511554D03*
X506003Y1085458D03*
X511554Y1088647D03*
X504153D03*
X509704Y1085458D03*
X511554Y1101403D03*
X506003Y1104592D03*
X509704Y1091836D03*
X504153Y1095025D03*
X511554D03*
X506003Y1098214D03*
X509704D03*
X504153Y1101403D03*
X509704Y1104592D03*
X506003Y1091836D03*
X509704Y1110970D03*
X504153Y1114159D03*
X511554D03*
X506003Y1117348D03*
X509704D03*
X511554Y1107781D03*
X504153D03*
X506003Y1110970D03*
X504153Y1120537D03*
X511554D03*
X506003Y1123726D03*
X509704Y1130103D03*
X504153Y1133293D03*
X511554D03*
Y1126915D03*
X504153D03*
X509704Y1123726D03*
X506003Y1130103D03*
Y1136481D03*
X509704D03*
X504153Y1139670D03*
X511554D03*
X506003Y1142859D03*
X509704Y1149237D03*
X511554Y1146048D03*
X504153D03*
X509704Y1142859D03*
X506003Y1149237D03*
X504153Y1152426D03*
X511554D03*
X506003Y1155615D03*
X504296Y1516970D03*
X509021D03*
X513745D03*
X501147Y1519698D03*
X505871D03*
X510595D03*
X504296Y1530608D03*
X509021D03*
X513745D03*
X501147Y1533336D03*
X505871D03*
X510595D03*
X521475Y886002D03*
X515924Y889191D03*
X523326D03*
X517775Y892380D03*
X523326Y895569D03*
X515924D03*
X521475Y892380D03*
X523326Y908325D03*
X517775Y911513D03*
X521475Y898758D03*
X515924Y901947D03*
X523326D03*
X517775Y905135D03*
X521475D03*
X515924Y908325D03*
X521475Y911513D03*
X517775Y898758D03*
X521475Y917891D03*
X515924Y921080D03*
X523326D03*
X517775Y924269D03*
X521475D03*
X523326Y914702D03*
X515924D03*
X517775Y917891D03*
X515924Y927458D03*
X523326D03*
X517775Y930647D03*
X521475Y937025D03*
X515924Y940214D03*
X523326D03*
Y933836D03*
X515924D03*
X521475Y930647D03*
X517775Y937025D03*
Y943403D03*
X521475D03*
X515924Y946592D03*
X523326D03*
X517775Y949781D03*
X521475Y956159D03*
X523326Y952970D03*
X515924D03*
X521475Y949781D03*
X517775Y956159D03*
X521475Y962537D03*
X515924Y965726D03*
X523326D03*
X517775Y968915D03*
X515924Y959348D03*
X523326D03*
X517775Y962537D03*
X521475Y968915D03*
X515924Y984860D03*
X521475Y975293D03*
X515924Y978482D03*
X523326D03*
X517775Y981671D03*
X523326Y972104D03*
X515924D03*
X517775Y975293D03*
Y988049D03*
X521475Y994427D03*
X523326Y997616D03*
X515924D03*
X517775Y1000805D03*
X521475D03*
Y988049D03*
X515924Y991238D03*
X523326Y1010372D03*
X521475Y1007183D03*
X523326Y1003994D03*
X515924D03*
X517775Y1007183D03*
X518956Y1031245D03*
X517105Y1034434D03*
X524507D03*
X522657Y1037623D03*
X518956D03*
X517105Y1040812D03*
X524507D03*
X518956Y1044001D03*
Y1050379D03*
X524507Y1059946D03*
X517105Y1047190D03*
X522657Y1050379D03*
X524507Y1053568D03*
Y1072702D03*
X518956Y1063135D03*
X522657D03*
X517105Y1066324D03*
X518956Y1069513D03*
X522657D03*
X517105Y1072702D03*
X524507Y1066324D03*
X518956Y1075891D03*
X522657D03*
X517105Y1079080D03*
X524507D03*
X518956Y1082269D03*
X522657D03*
X517105Y1085458D03*
X522657Y1088647D03*
X518956D03*
X524507Y1085458D03*
X522657Y1101403D03*
X517105Y1104592D03*
X524507Y1091836D03*
X518956Y1095025D03*
X522657D03*
X517105Y1098214D03*
X524507D03*
X518956Y1101403D03*
X524507Y1104592D03*
X517105Y1091836D03*
X524507Y1110970D03*
X518956Y1114159D03*
X522657D03*
X517105Y1117348D03*
X524507D03*
X522657Y1107781D03*
X518956D03*
X517105Y1110970D03*
X518956Y1120537D03*
X522657D03*
X517105Y1123726D03*
X524507Y1130103D03*
X518956Y1133293D03*
X522657D03*
Y1126915D03*
X518956D03*
X524507Y1123726D03*
X517105Y1130103D03*
Y1136481D03*
X524507D03*
X518956Y1139670D03*
X522657D03*
X517105Y1142859D03*
X524507Y1149237D03*
X522657Y1146048D03*
X518956D03*
X524507Y1142859D03*
X517105Y1149237D03*
X518956Y1152426D03*
X522657D03*
X524507Y1155615D03*
X518470Y1516970D03*
X523194D03*
X515320Y1519698D03*
X520044D03*
X524769D03*
X518470Y1530608D03*
X523194D03*
X515320Y1533336D03*
X520044D03*
X524769D03*
X556633Y889191D03*
X554783Y892380D03*
X556633Y895569D03*
X554783Y911513D03*
X556633Y901947D03*
X554783Y905135D03*
X556633Y908325D03*
X554783Y898758D03*
X556633Y921080D03*
X554783Y924269D03*
X556633Y914702D03*
X554783Y917891D03*
X556633Y927458D03*
X554783Y930647D03*
X556633Y940214D03*
Y933836D03*
X554783Y937025D03*
Y943403D03*
X556633Y946592D03*
X554783Y949781D03*
X556633Y952970D03*
X554783Y956159D03*
X556633Y965726D03*
X554783Y968915D03*
X556633Y959348D03*
X554783Y962537D03*
X556633Y984860D03*
Y978482D03*
X554783Y981671D03*
X556633Y972104D03*
X554783Y975293D03*
Y988049D03*
X556633Y997616D03*
X554783Y1000805D03*
X556633Y991238D03*
Y1003994D03*
X554783Y1007183D03*
X555964Y1031245D03*
X557814Y1034434D03*
X555964Y1037623D03*
X557814Y1040812D03*
X555964Y1044001D03*
Y1050379D03*
X557814Y1047190D03*
X555964Y1063135D03*
X557814Y1066324D03*
X555964Y1069513D03*
X557814Y1072702D03*
X555964Y1075891D03*
X557814Y1079080D03*
X555964Y1082269D03*
X557814Y1085458D03*
X555964Y1088647D03*
X557814Y1104592D03*
X555964Y1095025D03*
X557814Y1098214D03*
X555964Y1101403D03*
X557814Y1091836D03*
X555964Y1114159D03*
X557814Y1117348D03*
X555964Y1107781D03*
X557814Y1110970D03*
X555964Y1120537D03*
X557814Y1123726D03*
X555964Y1133293D03*
Y1126915D03*
X557814Y1130103D03*
Y1136481D03*
X555964Y1139670D03*
X557814Y1142859D03*
X555964Y1146048D03*
X557814Y1149237D03*
X555964Y1152426D03*
X557814Y1155615D03*
X562184Y886002D03*
X560334Y889191D03*
Y895569D03*
X562184Y892380D03*
X560334Y908325D03*
X562184Y898758D03*
X560334Y901947D03*
X562184Y905135D03*
Y911513D03*
Y917891D03*
X560334Y921080D03*
X562184Y924269D03*
X560334Y914702D03*
Y927458D03*
X562184Y937025D03*
X560334Y940214D03*
Y933836D03*
X562184Y930647D03*
Y943403D03*
X560334Y946592D03*
X562184Y956159D03*
X560334Y952970D03*
X562184Y949781D03*
Y962537D03*
X560334Y965726D03*
Y959348D03*
X562184Y968915D03*
Y975293D03*
X560334Y978482D03*
Y972104D03*
X562184Y994427D03*
X560334Y997616D03*
X562184Y1000805D03*
Y988049D03*
X560334Y1010372D03*
X562184Y1007183D03*
X560334Y1003994D03*
X561515Y1034434D03*
X563365Y1037623D03*
X561515Y1040812D03*
Y1059946D03*
X563365Y1050379D03*
X561515Y1053568D03*
Y1072702D03*
X563365Y1063135D03*
Y1069513D03*
X561515Y1066324D03*
X563365Y1075891D03*
X561515Y1079080D03*
X563365Y1082269D03*
Y1088647D03*
X561515Y1085458D03*
X563365Y1101403D03*
X561515Y1091836D03*
X563365Y1095025D03*
X561515Y1098214D03*
Y1104592D03*
Y1110970D03*
X563365Y1114159D03*
X561515Y1117348D03*
X563365Y1107781D03*
Y1120537D03*
X561515Y1130103D03*
X563365Y1133293D03*
Y1126915D03*
X561515Y1123726D03*
Y1136481D03*
X563365Y1139670D03*
X561515Y1149237D03*
X563365Y1146048D03*
X561515Y1142859D03*
X563365Y1152426D03*
X580390Y1516970D03*
X585114D03*
X581965Y1519698D03*
X586689D03*
X580390Y1530608D03*
X585114D03*
X581965Y1533336D03*
X586689D03*
X589839Y1516970D03*
X594563D03*
X599287D03*
X604012D03*
X591413Y1519698D03*
X596138D03*
X600862D03*
X589839Y1530608D03*
X594563D03*
X599287D03*
X604012D03*
X591413Y1533336D03*
X596138D03*
X600862D03*
X608736Y1516970D03*
X613461D03*
X618185D03*
X605587Y1519698D03*
X610311D03*
X615035D03*
X608736Y1530608D03*
X613461D03*
X618185D03*
X605587Y1533336D03*
X610311D03*
X615035D03*
X627634Y1516970D03*
X632358D03*
X622909D03*
X629209Y1519698D03*
X633933D03*
X619760D03*
X624484D03*
X627634Y1530608D03*
X632358D03*
X622909D03*
X629209Y1533336D03*
X633933D03*
X619760D03*
X624484D03*
X637083Y1516970D03*
X641807D03*
X646532D03*
X638657Y1519698D03*
X643382D03*
X648106D03*
X637083Y1530608D03*
X641807D03*
X646532D03*
X638657Y1533336D03*
X643382D03*
X648106D03*
X651256Y1516970D03*
X652831Y1519698D03*
X651256Y1530608D03*
X652831Y1533336D03*
X1196028Y1563608D03*
X1197603Y1566336D03*
X1200752Y1563608D03*
X1205477D03*
X1210201D03*
X1214925D03*
X1202327Y1566336D03*
X1207051D03*
X1211776D03*
X1219650Y1563608D03*
X1224374D03*
X1229099D03*
X1216500Y1566336D03*
X1221225D03*
X1225949D03*
X1243272Y1563608D03*
X1233823D03*
X1238547D03*
X1244847Y1566336D03*
X1230673D03*
X1235398D03*
X1240122D03*
X1247996Y1563608D03*
X1252721D03*
X1257445D03*
X1249571Y1566336D03*
X1254295D03*
X1259020D03*
X1262170Y1563608D03*
X1266894D03*
X1263744Y1566336D03*
X1268469D03*
X1294099Y886001D03*
X1299650Y889190D03*
X1295949D03*
X1301500Y892379D03*
X1295949Y895568D03*
X1299650D03*
X1294099Y892379D03*
X1295949Y908324D03*
X1301500Y911512D03*
X1294099Y898757D03*
X1299650Y901946D03*
X1295949D03*
X1301500Y905134D03*
X1294099D03*
X1299650Y908324D03*
X1294099Y911512D03*
X1301500Y898757D03*
X1294099Y917890D03*
X1299650Y921079D03*
X1295949D03*
X1301500Y924268D03*
X1294099D03*
X1295949Y914701D03*
X1299650D03*
X1301500Y917890D03*
X1299650Y927457D03*
X1295949D03*
X1301500Y930646D03*
X1294099Y937024D03*
X1299650Y940213D03*
X1295949D03*
Y933835D03*
X1299650D03*
X1294099Y930646D03*
X1301500Y937024D03*
Y943402D03*
X1294099D03*
X1299650Y946591D03*
X1295949D03*
X1301500Y949780D03*
X1294099Y956158D03*
X1295949Y952969D03*
X1299650D03*
X1294099Y949780D03*
X1301500Y956158D03*
X1294099Y962536D03*
X1299650Y965725D03*
X1295949D03*
X1301500Y968914D03*
X1299650Y959347D03*
X1295949D03*
X1301500Y962536D03*
X1294099Y968914D03*
X1299650Y984859D03*
X1294099Y975292D03*
X1299650Y978481D03*
X1295949D03*
X1301500Y981670D03*
X1295949Y972103D03*
X1299650D03*
X1301500Y975292D03*
Y988048D03*
X1294099Y994426D03*
X1295949Y997615D03*
X1299650D03*
X1301500Y1000804D03*
X1294099D03*
X1295949Y991237D03*
X1301500Y994426D03*
X1295949Y1010371D03*
X1294099Y1007182D03*
X1295949Y1003993D03*
X1299650D03*
X1301500Y1007182D03*
X1302681Y1031244D03*
X1300831Y1034433D03*
X1297130D03*
X1295280Y1037622D03*
X1302681D03*
X1300831Y1040811D03*
X1297130D03*
X1295280Y1044000D03*
X1302681Y1050378D03*
X1297130Y1059945D03*
X1300831Y1047189D03*
X1295280Y1050378D03*
X1297130Y1053567D03*
Y1072701D03*
X1302681Y1063134D03*
X1295280D03*
X1300831Y1066323D03*
X1302681Y1069512D03*
X1295280D03*
X1300831Y1072701D03*
X1297130Y1066323D03*
X1302681Y1075890D03*
X1295280D03*
X1300831Y1079079D03*
X1297130D03*
X1302681Y1082268D03*
X1295280D03*
X1300831Y1085457D03*
X1295280Y1088646D03*
X1302681D03*
X1297130Y1085457D03*
X1295280Y1101402D03*
X1300831Y1104591D03*
X1297130Y1091835D03*
X1302681Y1095024D03*
X1295280D03*
X1300831Y1098213D03*
X1297130D03*
X1302681Y1101402D03*
X1297130Y1104591D03*
X1300831Y1091835D03*
X1297130Y1110969D03*
X1302681Y1114158D03*
X1295280D03*
X1300831Y1117347D03*
X1297130D03*
X1295280Y1107780D03*
X1302681D03*
X1300831Y1110969D03*
X1302681Y1120536D03*
X1295280D03*
X1300831Y1123725D03*
X1297130Y1130102D03*
X1302681Y1133292D03*
X1295280D03*
Y1126914D03*
X1302681D03*
X1297130Y1123725D03*
X1300831Y1130102D03*
Y1136480D03*
X1297130D03*
X1302681Y1139669D03*
X1295280D03*
X1300831Y1142858D03*
X1297130Y1149236D03*
X1295280Y1146047D03*
X1302681D03*
X1297130Y1142858D03*
X1300831Y1149236D03*
X1302681Y1152425D03*
X1295280D03*
X1300831Y1155614D03*
X1334807Y886001D03*
X1332957Y889190D03*
Y895568D03*
X1334807Y892379D03*
X1332957Y908324D03*
X1334807Y898757D03*
X1332957Y901946D03*
X1334807Y905134D03*
Y911512D03*
Y917890D03*
X1332957Y921079D03*
X1334807Y924268D03*
X1332957Y914701D03*
Y927457D03*
X1334807Y937024D03*
X1332957Y940213D03*
Y933835D03*
X1334807Y930646D03*
Y943402D03*
X1332957Y946591D03*
X1334807Y956158D03*
X1332957Y952969D03*
X1334807Y949780D03*
Y962536D03*
X1332957Y965725D03*
Y959347D03*
X1334807Y968914D03*
Y975292D03*
X1332957Y978481D03*
Y972103D03*
X1334807Y994426D03*
X1332957Y997615D03*
X1334807Y1000804D03*
X1332957Y991237D03*
Y1010371D03*
X1334807Y1007182D03*
X1332957Y1003993D03*
X1334138Y1034433D03*
Y1040811D03*
Y1059945D03*
Y1053567D03*
Y1072701D03*
Y1066323D03*
Y1079079D03*
Y1085457D03*
Y1091835D03*
Y1098213D03*
Y1104591D03*
Y1110969D03*
Y1117347D03*
Y1130102D03*
Y1123725D03*
Y1136480D03*
Y1149236D03*
Y1142858D03*
Y1155614D03*
X1324090Y1563608D03*
X1328814D03*
X1333539D03*
X1325665Y1566336D03*
X1330389D03*
X1345910Y886001D03*
X1347760Y889190D03*
Y895568D03*
X1345910Y892379D03*
X1340359Y889190D03*
X1338508Y892379D03*
X1340359Y895568D03*
X1347760Y908324D03*
X1345910Y898757D03*
X1347760Y901946D03*
X1345910Y905134D03*
Y911512D03*
X1338508D03*
X1340359Y901946D03*
X1338508Y905134D03*
X1340359Y908324D03*
X1338508Y898757D03*
X1345910Y917890D03*
X1347760Y921079D03*
X1345910Y924268D03*
X1347760Y914701D03*
X1340359Y921079D03*
X1338508Y924268D03*
X1340359Y914701D03*
X1338508Y917890D03*
X1347760Y927457D03*
X1345910Y937024D03*
X1347760Y940213D03*
Y933835D03*
X1345910Y930646D03*
X1340359Y927457D03*
X1338508Y930646D03*
X1340359Y940213D03*
Y933835D03*
X1338508Y937024D03*
X1345910Y943402D03*
X1347760Y946591D03*
X1345910Y956158D03*
X1347760Y952969D03*
X1345910Y949780D03*
X1338508Y943402D03*
X1340359Y946591D03*
X1338508Y949780D03*
X1340359Y952969D03*
X1338508Y956158D03*
X1345910Y962536D03*
X1347760Y965725D03*
Y959347D03*
X1345910Y968914D03*
X1340359Y965725D03*
X1338508Y968914D03*
X1340359Y959347D03*
X1338508Y962536D03*
X1345910Y975292D03*
X1347760Y978481D03*
Y972103D03*
X1340359Y984859D03*
Y978481D03*
X1338508Y981670D03*
X1340359Y972103D03*
X1338508Y975292D03*
X1345910Y994426D03*
X1347760Y997615D03*
X1345910Y1000804D03*
X1347760Y991237D03*
X1338508Y988048D03*
X1340359Y997615D03*
X1338508Y1000804D03*
Y994426D03*
X1347760Y1010371D03*
X1345910Y1007182D03*
X1347760Y1003993D03*
X1340359D03*
X1338508Y1007182D03*
X1348941Y1034433D03*
X1347091Y1037622D03*
X1348941Y1040811D03*
X1347091Y1044000D03*
X1339689Y1031244D03*
X1341540Y1034433D03*
X1335989Y1037622D03*
X1339689D03*
X1341540Y1040811D03*
X1335989Y1044000D03*
X1348941Y1059945D03*
X1347091Y1050378D03*
X1348941Y1053567D03*
X1339689Y1050378D03*
X1341540Y1047189D03*
X1335989Y1050378D03*
X1348941Y1072701D03*
X1347091Y1063134D03*
Y1069512D03*
X1348941Y1066323D03*
X1339689Y1063134D03*
X1335989D03*
X1341540Y1066323D03*
X1339689Y1069512D03*
X1335989D03*
X1341540Y1072701D03*
X1347091Y1075890D03*
X1348941Y1079079D03*
X1347091Y1082268D03*
Y1088646D03*
X1348941Y1085457D03*
X1339689Y1075890D03*
X1335989D03*
X1341540Y1079079D03*
X1339689Y1082268D03*
X1335989D03*
X1341540Y1085457D03*
X1335989Y1088646D03*
X1339689D03*
X1347091Y1101402D03*
X1348941Y1091835D03*
X1347091Y1095024D03*
X1348941Y1098213D03*
Y1104591D03*
X1335989Y1101402D03*
X1341540Y1104591D03*
X1339689Y1095024D03*
X1335989D03*
X1341540Y1098213D03*
X1339689Y1101402D03*
X1341540Y1091835D03*
X1348941Y1110969D03*
X1347091Y1114158D03*
X1348941Y1117347D03*
X1347091Y1107780D03*
X1339689Y1114158D03*
X1335989D03*
X1341540Y1117347D03*
X1335989Y1107780D03*
X1339689D03*
X1341540Y1110969D03*
X1347091Y1120536D03*
X1348941Y1130102D03*
X1347091Y1133292D03*
Y1126914D03*
X1348941Y1123725D03*
X1339689Y1120536D03*
X1335989D03*
X1341540Y1123725D03*
X1339689Y1133292D03*
X1335989D03*
Y1126914D03*
X1339689D03*
X1341540Y1130102D03*
X1348941Y1136480D03*
X1347091Y1139669D03*
X1348941Y1149236D03*
X1347091Y1146047D03*
X1348941Y1142858D03*
X1341540Y1136480D03*
X1339689Y1139669D03*
X1335989D03*
X1341540Y1142858D03*
X1335989Y1146047D03*
X1339689D03*
X1341540Y1149236D03*
X1347091Y1152425D03*
X1339689D03*
X1335989D03*
X1338263Y1563608D03*
X1342987D03*
X1347712D03*
X1335113Y1566336D03*
X1339838D03*
X1344562D03*
X1349287D03*
X1364414Y892379D03*
X1360713D03*
X1351461Y889190D03*
X1353311Y892379D03*
X1351461Y895568D03*
X1364414Y905134D03*
Y898757D03*
Y911512D03*
X1360713Y905134D03*
Y898757D03*
Y911512D03*
X1353311D03*
X1351461Y901946D03*
X1353311Y905134D03*
X1351461Y908324D03*
X1353311Y898757D03*
X1351461Y921079D03*
X1353311Y924268D03*
X1351461Y914701D03*
X1353311Y917890D03*
X1351461Y927457D03*
X1353311Y930646D03*
X1351461Y940213D03*
Y933835D03*
X1353311Y937024D03*
Y943402D03*
X1351461Y946591D03*
X1353311Y949780D03*
X1351461Y952969D03*
X1353311Y956158D03*
X1351461Y965725D03*
X1353311Y968914D03*
X1351461Y959347D03*
X1353311Y962536D03*
X1351461Y984859D03*
Y978481D03*
X1353311Y981670D03*
X1351461Y972103D03*
X1353311Y975292D03*
Y988048D03*
X1351461Y997615D03*
X1353311Y1000804D03*
Y994426D03*
X1351461Y1003993D03*
X1353311Y1007182D03*
X1354493Y1031244D03*
X1352642Y1034433D03*
X1354493Y1037622D03*
X1352642Y1040811D03*
X1354493Y1050378D03*
X1352642Y1047189D03*
X1354493Y1063134D03*
X1352642Y1066323D03*
X1354493Y1069512D03*
X1352642Y1072701D03*
X1354493Y1075890D03*
X1352642Y1079079D03*
X1354493Y1082268D03*
X1352642Y1085457D03*
X1354493Y1088646D03*
X1352642Y1104591D03*
X1354493Y1095024D03*
X1352642Y1098213D03*
X1354493Y1101402D03*
X1352642Y1091835D03*
X1354493Y1114158D03*
X1352642Y1117347D03*
X1354493Y1107780D03*
X1352642Y1110969D03*
X1361894Y1114158D03*
Y1107780D03*
X1354493Y1120536D03*
X1352642Y1123725D03*
X1354493Y1133292D03*
Y1126914D03*
X1352642Y1130102D03*
X1361894Y1120536D03*
Y1126914D03*
Y1133292D03*
X1352642Y1136480D03*
X1354493Y1139669D03*
X1352642Y1142858D03*
X1354493Y1146047D03*
X1352642Y1149236D03*
X1361894Y1139669D03*
Y1146047D03*
X1354493Y1152425D03*
X1352642Y1155614D03*
X1361894Y1158803D03*
X1358193D03*
X1361894Y1152425D03*
X1352436Y1563608D03*
X1357161D03*
X1361885D03*
X1354011Y1566336D03*
X1358735D03*
X1363460D03*
X1375516Y892379D03*
X1371815D03*
X1375516Y898757D03*
Y905134D03*
X1371815Y898757D03*
Y905134D03*
X1365595Y1114158D03*
Y1107780D03*
X1376697Y1114158D03*
Y1107780D03*
X1372997Y1114158D03*
Y1107780D03*
X1365595Y1120536D03*
X1376697D03*
Y1126914D03*
X1372997Y1120536D03*
Y1126914D03*
X1365595D03*
Y1133292D03*
X1376697D03*
X1372997D03*
X1365595Y1139669D03*
Y1146047D03*
X1376697Y1139669D03*
Y1146047D03*
X1372997Y1139669D03*
Y1146047D03*
Y1158803D03*
X1369296D03*
X1365595Y1152425D03*
X1376697D03*
X1372997D03*
X1371334Y1563608D03*
X1376058D03*
X1366609D03*
X1372909Y1566336D03*
X1377633D03*
X1368184D03*
X1386619Y892379D03*
X1394020D03*
X1382918D03*
X1386619Y905134D03*
Y898757D03*
X1394020Y905134D03*
Y898757D03*
X1382918Y905134D03*
Y898757D03*
X1387800Y1114158D03*
X1384099D03*
X1387800Y1120536D03*
Y1126914D03*
X1384099Y1120536D03*
Y1126914D03*
X1387800Y1133292D03*
X1384099D03*
X1387800Y1139669D03*
Y1146047D03*
X1384099Y1139669D03*
Y1146047D03*
Y1158803D03*
X1380398D03*
X1391500D03*
X1387800Y1152425D03*
X1384099D03*
X1380783Y1563608D03*
X1385507D03*
X1390232D03*
X1382357Y1566336D03*
X1387082D03*
X1391806D03*
X1406973Y895568D03*
X1397721Y892379D03*
X1403272Y895568D03*
X1406973Y908324D03*
Y901946D03*
X1397721Y905134D03*
Y898757D03*
X1403272Y908324D03*
Y901946D03*
X1398902Y1114158D03*
X1408154Y1117347D03*
Y1110969D03*
X1395201Y1114158D03*
X1404453Y1117347D03*
Y1110969D03*
X1398902Y1120536D03*
Y1126914D03*
X1408154Y1123725D03*
X1395201Y1120536D03*
Y1126914D03*
X1404453Y1123725D03*
X1398902Y1133292D03*
X1408154Y1130102D03*
X1395201Y1133292D03*
X1404453Y1130102D03*
X1398902Y1139669D03*
Y1146047D03*
X1408154Y1142858D03*
Y1136480D03*
X1395201Y1139669D03*
Y1146047D03*
X1404453Y1142858D03*
Y1136480D03*
X1395201Y1158803D03*
X1398902Y1152425D03*
X1395201D03*
X1394956Y1563608D03*
X1396531Y1566336D03*
X1434704Y892379D03*
X1425452Y895568D03*
X1438405Y892379D03*
X1429153Y895568D03*
X1434704Y898757D03*
Y905134D03*
X1425452Y901946D03*
Y908324D03*
X1438405Y898757D03*
Y905134D03*
X1429153Y901946D03*
Y908324D03*
X1434704Y911512D03*
X1438405D03*
X1434704Y917890D03*
Y924268D03*
X1425452Y914701D03*
Y921079D03*
X1438405Y917890D03*
Y924268D03*
X1429153Y914701D03*
Y921079D03*
X1438405Y937024D03*
X1429153Y940213D03*
X1434704Y937024D03*
X1425452Y940213D03*
Y927457D03*
X1429153D03*
X1438405Y943402D03*
Y956158D03*
X1429153Y946591D03*
Y952969D03*
X1438405Y949780D03*
X1434704Y943402D03*
Y956158D03*
X1425452Y946591D03*
Y952969D03*
X1434704Y949780D03*
X1426633Y1110969D03*
Y1117347D03*
X1435885Y1114158D03*
X1430334Y1110969D03*
Y1117347D03*
Y1130102D03*
X1426633D03*
Y1123725D03*
X1435885Y1126914D03*
Y1120536D03*
X1430334Y1123725D03*
X1435885Y1133292D03*
Y1146047D03*
Y1139669D03*
X1426633Y1136480D03*
Y1142858D03*
X1430334Y1136480D03*
Y1142858D03*
X1445806Y892379D03*
X1449507D03*
X1445806Y898757D03*
Y905134D03*
X1449507Y898757D03*
Y905134D03*
X1445806Y911512D03*
X1449507D03*
X1445806Y917890D03*
Y924268D03*
X1449507Y917890D03*
Y924268D03*
Y949780D03*
Y943402D03*
Y956158D03*
X1445806Y949780D03*
Y943402D03*
Y956158D03*
X1446987Y1114158D03*
X1439586D03*
X1450688D03*
X1446987Y1126914D03*
Y1120536D03*
X1439586Y1126914D03*
Y1120536D03*
X1450688Y1126914D03*
Y1120536D03*
X1446987Y1133292D03*
X1450688D03*
X1439586D03*
X1446987Y1139669D03*
X1450688D03*
X1446987Y1146047D03*
X1439586D03*
Y1139669D03*
X1450688Y1146047D03*
X1468011Y892379D03*
X1456909D03*
X1460609D03*
X1468011Y911512D03*
Y898757D03*
Y905134D03*
X1456909Y898757D03*
Y905134D03*
X1460609Y898757D03*
Y905134D03*
X1456909Y911512D03*
X1460609D03*
X1468011Y924268D03*
Y917890D03*
X1456909Y924268D03*
Y917890D03*
X1460609Y924268D03*
Y917890D03*
X1468011Y930646D03*
X1456909D03*
X1460609D03*
Y949780D03*
Y943402D03*
Y956158D03*
X1468011Y949780D03*
Y943402D03*
Y956158D03*
X1456909Y949780D03*
Y943402D03*
Y956158D03*
X1458090Y1114158D03*
Y1107780D03*
X1461791Y1114158D03*
Y1107780D03*
X1458090Y1133292D03*
X1461791D03*
X1458090Y1126914D03*
Y1120536D03*
X1461791Y1126914D03*
Y1120536D03*
X1458090Y1146047D03*
Y1139669D03*
X1461791Y1146047D03*
Y1139669D03*
X1461777Y1552698D03*
X1460202Y1549970D03*
X1464926D03*
X1466501Y1552698D03*
X1460202Y1563608D03*
X1464926D03*
X1461777Y1566336D03*
X1466501D03*
X1471712Y892379D03*
X1480964Y889190D03*
X1479113Y892379D03*
X1480964Y895568D03*
X1471712Y911512D03*
Y898757D03*
Y905134D03*
X1479113Y911512D03*
X1480964Y901946D03*
X1479113Y905134D03*
X1480964Y908324D03*
X1479113Y898757D03*
X1480964Y921079D03*
X1479113Y924268D03*
X1480964Y914701D03*
X1479113Y917890D03*
X1471712Y924268D03*
Y917890D03*
X1480964Y927457D03*
X1479113Y930646D03*
X1480964Y940213D03*
Y933835D03*
X1479113Y937024D03*
X1471712Y930646D03*
Y949780D03*
Y943402D03*
Y956158D03*
X1479113Y943402D03*
X1480964Y946591D03*
X1479113Y949780D03*
X1480964Y952969D03*
X1479113Y956158D03*
X1480964Y965725D03*
X1479113Y968914D03*
X1480964Y959347D03*
X1479113Y962536D03*
X1480964Y984859D03*
Y978481D03*
X1479113Y981670D03*
X1480964Y972103D03*
X1479113Y975292D03*
Y988048D03*
X1480964Y997615D03*
X1479113Y1000804D03*
X1480964Y991237D03*
Y1003993D03*
X1479113Y1007182D03*
X1480295Y1031244D03*
X1482145Y1034433D03*
X1480295Y1037622D03*
X1482145Y1040811D03*
X1480295Y1044000D03*
Y1050378D03*
X1482145Y1047189D03*
X1480295Y1063134D03*
X1482145Y1066323D03*
X1480295Y1069512D03*
X1482145Y1072701D03*
X1480295Y1075890D03*
X1482145Y1079079D03*
X1480295Y1082268D03*
X1482145Y1085457D03*
X1480295Y1088646D03*
X1482145Y1104591D03*
X1480295Y1095024D03*
X1482145Y1098213D03*
X1480295Y1101402D03*
X1482145Y1091835D03*
X1480295Y1114158D03*
X1482145Y1117347D03*
X1480295Y1107780D03*
X1482145Y1110969D03*
X1469192Y1107780D03*
Y1114158D03*
X1472893Y1107780D03*
Y1114158D03*
X1480295Y1120536D03*
X1482145Y1123725D03*
X1480295Y1133292D03*
Y1126914D03*
X1482145Y1130102D03*
X1469192Y1120536D03*
X1472893D03*
X1469192Y1133292D03*
Y1126914D03*
X1472893Y1133292D03*
Y1126914D03*
X1482145Y1136480D03*
X1480295Y1139669D03*
X1482145Y1142858D03*
X1480295Y1146047D03*
X1482145Y1149236D03*
X1469192Y1146047D03*
Y1139669D03*
X1472893Y1146047D03*
Y1139669D03*
X1480295Y1152425D03*
X1482145Y1155614D03*
X1479099Y1549970D03*
X1483824D03*
X1480674Y1552698D03*
X1469651Y1549970D03*
X1474375D03*
X1471225Y1552698D03*
X1475950D03*
X1469651Y1563608D03*
X1474375D03*
X1479099D03*
X1483824D03*
X1471225Y1566336D03*
X1475950D03*
X1480674D03*
X1486515Y886001D03*
X1484665Y889190D03*
Y895568D03*
X1486515Y892379D03*
X1497617Y886001D03*
X1492066Y889190D03*
X1493917Y892379D03*
X1492066Y895568D03*
X1497617Y892379D03*
X1484665Y908324D03*
X1486515Y898757D03*
X1484665Y901946D03*
X1486515Y905134D03*
Y911512D03*
X1493917D03*
X1497617Y898757D03*
X1492066Y901946D03*
X1493917Y905134D03*
X1497617D03*
X1492066Y908324D03*
X1497617Y911512D03*
X1493917Y898757D03*
X1486515Y917890D03*
X1484665Y921079D03*
X1486515Y924268D03*
X1484665Y914701D03*
X1497617Y917890D03*
X1492066Y921079D03*
X1493917Y924268D03*
X1497617D03*
X1492066Y914701D03*
X1493917Y917890D03*
X1484665Y927457D03*
X1486515Y937024D03*
X1484665Y940213D03*
Y933835D03*
X1486515Y930646D03*
X1492066Y927457D03*
X1493917Y930646D03*
X1497617Y937024D03*
X1492066Y940213D03*
Y933835D03*
X1497617Y930646D03*
X1493917Y937024D03*
X1486515Y943402D03*
X1484665Y946591D03*
X1486515Y956158D03*
X1484665Y952969D03*
X1486515Y949780D03*
X1493917Y943402D03*
X1497617D03*
X1492066Y946591D03*
X1493917Y949780D03*
X1497617Y956158D03*
X1492066Y952969D03*
X1497617Y949780D03*
X1493917Y956158D03*
X1486515Y962536D03*
X1484665Y965725D03*
Y959347D03*
X1486515Y968914D03*
X1497617Y962536D03*
X1492066Y965725D03*
X1493917Y968914D03*
X1492066Y959347D03*
X1493917Y962536D03*
X1497617Y968914D03*
X1486515Y975292D03*
X1484665Y978481D03*
Y972103D03*
X1492066Y984859D03*
X1497617Y975292D03*
X1492066Y978481D03*
X1493917Y981670D03*
X1492066Y972103D03*
X1493917Y975292D03*
X1486515Y994426D03*
X1484665Y997615D03*
X1486515Y1000804D03*
Y988048D03*
X1493917D03*
X1497617Y994426D03*
X1492066Y997615D03*
X1493917Y1000804D03*
X1497617D03*
Y988048D03*
X1492066Y991237D03*
X1484665Y1010371D03*
X1486515Y1007182D03*
X1484665Y1003993D03*
X1497617Y1007182D03*
X1492066Y1003993D03*
X1493917Y1007182D03*
X1485846Y1034433D03*
X1487696Y1037622D03*
X1485846Y1040811D03*
X1495098Y1031244D03*
X1493247Y1034433D03*
X1498799Y1037622D03*
X1495098D03*
X1493247Y1040811D03*
X1495098Y1044000D03*
X1485846Y1059945D03*
X1487696Y1050378D03*
X1485846Y1053567D03*
X1495098Y1050378D03*
X1493247Y1047189D03*
X1498799Y1050378D03*
X1485846Y1072701D03*
X1487696Y1063134D03*
Y1069512D03*
X1485846Y1066323D03*
X1495098Y1063134D03*
X1498799D03*
X1493247Y1066323D03*
X1495098Y1069512D03*
X1498799D03*
X1493247Y1072701D03*
X1487696Y1075890D03*
X1485846Y1079079D03*
X1487696Y1082268D03*
Y1088646D03*
X1485846Y1085457D03*
X1495098Y1075890D03*
X1498799D03*
X1493247Y1079079D03*
X1495098Y1082268D03*
X1498799D03*
X1493247Y1085457D03*
X1498799Y1088646D03*
X1495098D03*
X1487696Y1101402D03*
X1485846Y1091835D03*
X1487696Y1095024D03*
X1485846Y1098213D03*
Y1104591D03*
X1498799Y1101402D03*
X1493247Y1104591D03*
X1495098Y1095024D03*
X1498799D03*
X1493247Y1098213D03*
X1495098Y1101402D03*
X1493247Y1091835D03*
X1485846Y1110969D03*
X1487696Y1114158D03*
X1485846Y1117347D03*
X1487696Y1107780D03*
X1495098Y1114158D03*
X1498799D03*
X1493247Y1117347D03*
X1498799Y1107780D03*
X1495098D03*
X1493247Y1110969D03*
X1487696Y1120536D03*
X1485846Y1130102D03*
X1487696Y1133292D03*
Y1126914D03*
X1485846Y1123725D03*
X1495098Y1120536D03*
X1498799D03*
X1493247Y1123725D03*
X1495098Y1133292D03*
X1498799D03*
Y1126914D03*
X1495098D03*
X1493247Y1130102D03*
X1485846Y1136480D03*
X1487696Y1139669D03*
X1485846Y1149236D03*
X1487696Y1146047D03*
X1485846Y1142858D03*
X1493247Y1136480D03*
X1495098Y1139669D03*
X1498799D03*
X1493247Y1142858D03*
X1498799Y1146047D03*
X1495098D03*
X1493247Y1149236D03*
X1487696Y1152425D03*
X1495098D03*
X1498799D03*
X1497997Y1549970D03*
X1488548D03*
X1493273D03*
X1485399Y1552698D03*
X1490123D03*
X1494847D03*
X1488548Y1563608D03*
X1493273D03*
X1497997D03*
X1485399Y1566336D03*
X1490123D03*
X1494847D03*
X1499468Y889190D03*
Y895568D03*
Y908324D03*
Y901946D03*
Y921079D03*
Y914701D03*
Y927457D03*
Y940213D03*
Y933835D03*
Y946591D03*
Y952969D03*
Y965725D03*
Y959347D03*
Y978481D03*
Y972103D03*
Y997615D03*
Y1010371D03*
Y1003993D03*
X1500649Y1034433D03*
Y1040811D03*
Y1059945D03*
Y1053567D03*
Y1072701D03*
Y1066323D03*
Y1079079D03*
Y1085457D03*
Y1091835D03*
Y1098213D03*
Y1104591D03*
Y1110969D03*
Y1117347D03*
Y1130102D03*
Y1123725D03*
Y1136480D03*
Y1149236D03*
Y1142858D03*
Y1155614D03*
X1507446Y1549970D03*
X1512170D03*
X1502721D03*
X1509021Y1552698D03*
X1513745D03*
X1499572D03*
X1504296D03*
X1507446Y1563608D03*
X1512170D03*
X1502721D03*
X1509021Y1566336D03*
X1513745D03*
X1499572D03*
X1504296D03*
X1516895Y1549970D03*
X1521619D03*
X1526344D03*
X1518469Y1552698D03*
X1523194D03*
X1527918D03*
X1516895Y1563608D03*
X1521619D03*
X1526344D03*
X1518469Y1566336D03*
X1523194D03*
X1527918D03*
X1538326Y886001D03*
X1532775Y889190D03*
X1536476D03*
X1530925Y892379D03*
X1536476Y895568D03*
X1532775D03*
X1538326Y892379D03*
X1536476Y908324D03*
X1530925Y911512D03*
X1538326Y898757D03*
X1532775Y901946D03*
X1536476D03*
X1530925Y905134D03*
X1538326D03*
X1532775Y908324D03*
X1538326Y911512D03*
X1530925Y898757D03*
X1538326Y917890D03*
X1532775Y921079D03*
X1536476D03*
X1530925Y924268D03*
X1538326D03*
X1536476Y914701D03*
X1532775D03*
X1530925Y917890D03*
X1532775Y927457D03*
X1536476D03*
X1530925Y930646D03*
X1538326Y937024D03*
X1532775Y940213D03*
X1536476D03*
Y933835D03*
X1532775D03*
X1538326Y930646D03*
X1530925Y937024D03*
Y943402D03*
X1538326D03*
X1532775Y946591D03*
X1536476D03*
X1530925Y949780D03*
X1538326Y956158D03*
X1536476Y952969D03*
X1532775D03*
X1538326Y949780D03*
X1530925Y956158D03*
X1538326Y962536D03*
X1532775Y965725D03*
X1536476D03*
X1530925Y968914D03*
X1532775Y959347D03*
X1536476D03*
X1530925Y962536D03*
X1538326Y968914D03*
X1532775Y984859D03*
X1538326Y975292D03*
X1532775Y978481D03*
X1536476D03*
X1530925Y981670D03*
X1536476Y972103D03*
X1532775D03*
X1530925Y975292D03*
Y988048D03*
X1538326Y994426D03*
X1536476Y997615D03*
X1532775D03*
X1530925Y1000804D03*
X1538326D03*
Y988048D03*
X1532775Y991237D03*
X1536476Y1010371D03*
X1538326Y1007182D03*
X1536476Y1003993D03*
X1532775D03*
X1530925Y1007182D03*
X1532106Y1031244D03*
X1533956Y1034433D03*
X1537657D03*
X1539507Y1037622D03*
X1532106D03*
X1533956Y1040811D03*
X1537657D03*
X1532106Y1044000D03*
Y1050378D03*
X1537657Y1059945D03*
X1533956Y1047189D03*
X1539507Y1050378D03*
X1537657Y1053567D03*
Y1072701D03*
X1532106Y1063134D03*
X1539507D03*
X1533956Y1066323D03*
X1532106Y1069512D03*
X1539507D03*
X1533956Y1072701D03*
X1537657Y1066323D03*
X1532106Y1075890D03*
X1539507D03*
X1533956Y1079079D03*
X1537657D03*
X1532106Y1082268D03*
X1539507D03*
X1533956Y1085457D03*
X1539507Y1088646D03*
X1532106D03*
X1537657Y1085457D03*
X1539507Y1101402D03*
X1533956Y1104591D03*
X1537657Y1091835D03*
X1532106Y1095024D03*
X1539507D03*
X1533956Y1098213D03*
X1537657D03*
X1532106Y1101402D03*
X1537657Y1104591D03*
X1533956Y1091835D03*
X1537657Y1110969D03*
X1532106Y1114158D03*
X1539507D03*
X1533956Y1117347D03*
X1537657D03*
X1539507Y1107780D03*
X1532106D03*
X1533956Y1110969D03*
X1532106Y1120536D03*
X1539507D03*
X1533956Y1123725D03*
X1537657Y1130102D03*
X1532106Y1133292D03*
X1539507D03*
Y1126914D03*
X1532106D03*
X1537657Y1123725D03*
X1533956Y1130102D03*
Y1136480D03*
X1537657D03*
X1532106Y1139669D03*
X1539507D03*
X1533956Y1142858D03*
X1537657Y1149236D03*
X1539507Y1146047D03*
X1532106D03*
X1537657Y1142858D03*
X1533956Y1149236D03*
X1532106Y1152425D03*
X1539507D03*
X1533956Y1155614D03*
X1531068Y1549970D03*
X1532643Y1552698D03*
X1531068Y1563608D03*
X1532643Y1566336D03*
X1588264Y1549970D03*
Y1563608D03*
X1592988Y1549970D03*
X1597713D03*
X1602437D03*
X1589839Y1552698D03*
X1594563D03*
X1599287D03*
X1592988Y1563608D03*
X1597713D03*
X1602437D03*
X1589839Y1566336D03*
X1594563D03*
X1599287D03*
X1607161Y1549970D03*
X1611886D03*
X1616610D03*
X1604012Y1552698D03*
X1608736D03*
X1613461D03*
X1607161Y1563608D03*
X1611886D03*
X1616610D03*
X1604012Y1566336D03*
X1608736D03*
X1613461D03*
X1621335Y1549970D03*
X1626059D03*
X1630783D03*
X1618185Y1552698D03*
X1622909D03*
X1627634D03*
X1632358D03*
X1621335Y1563608D03*
X1626059D03*
X1630783D03*
X1618185Y1566336D03*
X1622909D03*
X1627634D03*
X1632358D03*
X1635508Y1549970D03*
X1640232D03*
X1644957D03*
X1637083Y1552698D03*
X1641807D03*
X1646531D03*
X1635508Y1563608D03*
X1640232D03*
X1644957D03*
X1637083Y1566336D03*
X1641807D03*
X1646531D03*
X1649681Y1549970D03*
X1654406D03*
X1659130D03*
X1651256Y1552698D03*
X1655980D03*
X1660705D03*
X1649681Y1563608D03*
X1654406D03*
X1659130D03*
X1651256Y1566336D03*
X1655980D03*
X1660705D03*
G54D49*
X676509Y145866D03*
G54D34*
X230905Y1649173D03*
Y1653897D03*
Y1663346D03*
Y1668070D03*
Y1677519D03*
Y1682244D03*
Y1691692D03*
Y1696417D03*
Y1705866D03*
Y1710590D03*
Y1720039D03*
Y1724763D03*
Y1734212D03*
X238779Y1643661D03*
X246653Y1649173D03*
Y1653897D03*
X238779Y1653110D03*
Y1657834D03*
X246653Y1663346D03*
Y1668070D03*
X238779Y1667283D03*
Y1672007D03*
X246653Y1677519D03*
Y1682244D03*
X238779Y1681456D03*
Y1686180D03*
X246653Y1691692D03*
Y1696417D03*
X238779Y1695629D03*
Y1700354D03*
X246653Y1705866D03*
Y1710590D03*
X238779Y1709803D03*
Y1714527D03*
X246653Y1720039D03*
Y1724763D03*
X238779Y1723976D03*
Y1728700D03*
X246653Y1734212D03*
X254527Y1643661D03*
Y1653110D03*
Y1657834D03*
Y1667283D03*
Y1672007D03*
Y1681456D03*
Y1686180D03*
Y1695629D03*
Y1700354D03*
Y1709803D03*
Y1714527D03*
Y1723976D03*
Y1728700D03*
X270275Y1643661D03*
X262401Y1649173D03*
X270275Y1653110D03*
X262401Y1653897D03*
X270275Y1657834D03*
X262401Y1663346D03*
X270275Y1667283D03*
X262401Y1668070D03*
X270275Y1672007D03*
X262401Y1677519D03*
X270275Y1681456D03*
X262401Y1682244D03*
X270275Y1686180D03*
X262401Y1691692D03*
X270275Y1695629D03*
X262401Y1696417D03*
X270275Y1700354D03*
X262401Y1705866D03*
X270275Y1709803D03*
X262401Y1710590D03*
X270275Y1714527D03*
X262401Y1720039D03*
X270275Y1723976D03*
X262401Y1724763D03*
X270275Y1728700D03*
X262401Y1734212D03*
X286023Y1643661D03*
X278149Y1649173D03*
X286023Y1653110D03*
X278149Y1653897D03*
X286023Y1657834D03*
X278149Y1663346D03*
X286023Y1667283D03*
X278149Y1668070D03*
X286023Y1672007D03*
X278149Y1677519D03*
X286023Y1681456D03*
X278149Y1682244D03*
X286023Y1686180D03*
X278149Y1691692D03*
X286023Y1695629D03*
X278149Y1696417D03*
X286023Y1700354D03*
X278149Y1705866D03*
X286023Y1709803D03*
X278149Y1710590D03*
X286023Y1714527D03*
X278149Y1720039D03*
X286023Y1723976D03*
X278149Y1724763D03*
X286023Y1728700D03*
X278149Y1734212D03*
X305709Y1672007D03*
X297835Y1677519D03*
X305709Y1681456D03*
X297835Y1682244D03*
X305709Y1686180D03*
X297835Y1691692D03*
X305709Y1695629D03*
X297835Y1696417D03*
X305709Y1700354D03*
X297835Y1705866D03*
X305709Y1709803D03*
X297835Y1710590D03*
X305709Y1714527D03*
X297835Y1720039D03*
X305709Y1723976D03*
X297835Y1724763D03*
X305709Y1728700D03*
X297835Y1734212D03*
X321457Y1672007D03*
X313583Y1677519D03*
X321457Y1681456D03*
X313583Y1682244D03*
X321457Y1686180D03*
X313583Y1691692D03*
X321457Y1695629D03*
X313583Y1696417D03*
X321457Y1700354D03*
X313583Y1705866D03*
X321457Y1709803D03*
X313583Y1710590D03*
X321457Y1714527D03*
X313583Y1720039D03*
X321457Y1723976D03*
X313583Y1724763D03*
X321457Y1728700D03*
X313583Y1734212D03*
X329331Y1677519D03*
Y1682244D03*
Y1691692D03*
Y1696417D03*
Y1705866D03*
Y1710590D03*
Y1720039D03*
Y1724763D03*
Y1734212D03*
X337205Y1672007D03*
X345079Y1677519D03*
Y1682244D03*
X337205Y1681456D03*
Y1686180D03*
X345079Y1691692D03*
Y1696417D03*
X337205Y1695629D03*
Y1700354D03*
X345079Y1705866D03*
Y1710590D03*
X337205Y1709803D03*
Y1714527D03*
X345079Y1720039D03*
Y1724763D03*
X337205Y1723976D03*
Y1728700D03*
X345079Y1734212D03*
X352953Y1672007D03*
Y1681456D03*
Y1686180D03*
Y1695629D03*
Y1700354D03*
Y1709803D03*
Y1714527D03*
Y1723976D03*
Y1728700D03*
X495078Y1677519D03*
Y1682244D03*
Y1691692D03*
Y1696417D03*
Y1705866D03*
Y1710590D03*
Y1720039D03*
Y1724763D03*
Y1734212D03*
X502952Y1672007D03*
X510826Y1677519D03*
Y1682244D03*
X502952Y1681456D03*
Y1686180D03*
X510826Y1691692D03*
Y1696417D03*
X502952Y1695629D03*
Y1700354D03*
X510826Y1705866D03*
Y1710590D03*
X502952Y1709803D03*
Y1714527D03*
X510826Y1720039D03*
Y1724763D03*
X502952Y1723976D03*
Y1728700D03*
X510826Y1734212D03*
X518700Y1672007D03*
Y1681456D03*
Y1686180D03*
X526574Y1677519D03*
Y1682244D03*
X518700Y1695629D03*
Y1700354D03*
X526574Y1691692D03*
Y1696417D03*
X518700Y1709803D03*
Y1714527D03*
X526574Y1705866D03*
Y1710590D03*
X518700Y1723976D03*
Y1728700D03*
X526574Y1720039D03*
Y1724763D03*
Y1734212D03*
X534448Y1672007D03*
X542322Y1677519D03*
Y1682244D03*
X534448Y1681456D03*
Y1686180D03*
X542322Y1691692D03*
Y1696417D03*
X534448Y1695629D03*
Y1700354D03*
X542322Y1705866D03*
Y1710590D03*
X534448Y1709803D03*
Y1714527D03*
X542322Y1720039D03*
Y1724763D03*
X534448Y1723976D03*
Y1728700D03*
X542322Y1734212D03*
X550196Y1672007D03*
Y1681456D03*
Y1686180D03*
Y1695629D03*
Y1700354D03*
Y1709803D03*
Y1714527D03*
Y1723976D03*
Y1728700D03*
X569882Y1672007D03*
X562008Y1677519D03*
X569882Y1681456D03*
X562008Y1682244D03*
X569882Y1686180D03*
X562008Y1691692D03*
X569882Y1695629D03*
X562008Y1696417D03*
X569882Y1700354D03*
X562008Y1705866D03*
X569882Y1709803D03*
X562008Y1710590D03*
X569882Y1714527D03*
X562008Y1720039D03*
X569882Y1723976D03*
X562008Y1724763D03*
X569882Y1728700D03*
X562008Y1734212D03*
X585630Y1672007D03*
X577756Y1677519D03*
X585630Y1681456D03*
X577756Y1682244D03*
X585630Y1686180D03*
X577756Y1691692D03*
X585630Y1695629D03*
X577756Y1696417D03*
X585630Y1700354D03*
X577756Y1705866D03*
X585630Y1709803D03*
X577756Y1710590D03*
X585630Y1714527D03*
X577756Y1720039D03*
X585630Y1723976D03*
X577756Y1724763D03*
X585630Y1728700D03*
X577756Y1734212D03*
X601378Y1672007D03*
X593504Y1677519D03*
X601378Y1681456D03*
X593504Y1682244D03*
X601378Y1686180D03*
X593504Y1691692D03*
X601378Y1695629D03*
X593504Y1696417D03*
X601378Y1700354D03*
X593504Y1705866D03*
X601378Y1709803D03*
X593504Y1710590D03*
X601378Y1714527D03*
X593504Y1720039D03*
X601378Y1723976D03*
X593504Y1724763D03*
X601378Y1728700D03*
X593504Y1734212D03*
X617126Y1672007D03*
X609252Y1677519D03*
X617126Y1681456D03*
X609252Y1682244D03*
X617126Y1686180D03*
X609252Y1691692D03*
X617126Y1695629D03*
X609252Y1696417D03*
X617126Y1700354D03*
X609252Y1705866D03*
X617126Y1709803D03*
X609252Y1710590D03*
X617126Y1714527D03*
X609252Y1720039D03*
X617126Y1723976D03*
X609252Y1724763D03*
X617126Y1728700D03*
X609252Y1734212D03*
X1238778Y1677519D03*
Y1682244D03*
Y1691692D03*
Y1696417D03*
Y1705866D03*
Y1710590D03*
Y1720039D03*
Y1724763D03*
Y1734212D03*
X1246652Y1672007D03*
X1254526Y1677519D03*
Y1682244D03*
X1246652Y1681456D03*
Y1686180D03*
X1254526Y1691692D03*
Y1696417D03*
X1246652Y1695629D03*
Y1700354D03*
X1254526Y1705866D03*
Y1710590D03*
X1246652Y1709803D03*
Y1714527D03*
X1254526Y1720039D03*
Y1724763D03*
X1246652Y1723976D03*
Y1728700D03*
X1254526Y1734212D03*
X1262400Y1672007D03*
Y1681456D03*
Y1686180D03*
X1270274Y1677519D03*
Y1682244D03*
X1262400Y1695629D03*
Y1700354D03*
X1270274Y1691692D03*
Y1696417D03*
X1262400Y1709803D03*
Y1714527D03*
X1270274Y1705866D03*
Y1710590D03*
X1262400Y1723976D03*
Y1728700D03*
X1270274Y1720039D03*
Y1724763D03*
Y1734212D03*
X1278148Y1672007D03*
X1286022Y1677519D03*
Y1682244D03*
X1278148Y1681456D03*
Y1686180D03*
X1286022Y1691692D03*
Y1696417D03*
X1278148Y1695629D03*
Y1700354D03*
X1286022Y1705866D03*
Y1710590D03*
X1278148Y1709803D03*
Y1714527D03*
X1286022Y1720039D03*
Y1724763D03*
X1278148Y1723976D03*
Y1728700D03*
X1286022Y1734212D03*
X1293896Y1672007D03*
Y1681456D03*
Y1686180D03*
Y1695629D03*
Y1700354D03*
Y1709803D03*
Y1714527D03*
Y1723976D03*
Y1728700D03*
X1313582Y1672007D03*
X1305708Y1677519D03*
X1313582Y1681456D03*
X1305708Y1682244D03*
X1313582Y1686180D03*
X1305708Y1691692D03*
X1313582Y1695629D03*
X1305708Y1696417D03*
X1313582Y1700354D03*
X1305708Y1705866D03*
X1313582Y1709803D03*
X1305708Y1710590D03*
X1313582Y1714527D03*
X1305708Y1720039D03*
X1313582Y1723976D03*
X1305708Y1724763D03*
X1313582Y1728700D03*
X1305708Y1734212D03*
X1329330Y1672007D03*
X1321456Y1677519D03*
X1329330Y1681456D03*
X1321456Y1682244D03*
X1329330Y1686180D03*
X1321456Y1691692D03*
X1329330Y1695629D03*
X1321456Y1696417D03*
X1329330Y1700354D03*
X1321456Y1705866D03*
X1329330Y1709803D03*
X1321456Y1710590D03*
X1329330Y1714527D03*
X1321456Y1720039D03*
X1329330Y1723976D03*
X1321456Y1724763D03*
X1329330Y1728700D03*
X1321456Y1734212D03*
X1345078Y1672007D03*
X1337204Y1677519D03*
X1345078Y1681456D03*
X1337204Y1682244D03*
X1345078Y1686180D03*
X1337204Y1691692D03*
X1345078Y1695629D03*
X1337204Y1696417D03*
X1345078Y1700354D03*
X1337204Y1705866D03*
X1345078Y1709803D03*
X1337204Y1710590D03*
X1345078Y1714527D03*
X1337204Y1720039D03*
X1345078Y1723976D03*
X1337204Y1724763D03*
X1345078Y1728700D03*
X1337204Y1734212D03*
X1360826Y1672007D03*
X1352952Y1677519D03*
X1360826Y1681456D03*
X1352952Y1682244D03*
X1360826Y1686180D03*
X1352952Y1691692D03*
X1360826Y1695629D03*
X1352952Y1696417D03*
X1360826Y1700354D03*
X1352952Y1705866D03*
X1360826Y1709803D03*
X1352952Y1710590D03*
X1360826Y1714527D03*
X1352952Y1720039D03*
X1360826Y1723976D03*
X1352952Y1724763D03*
X1360826Y1728700D03*
X1352952Y1734212D03*
X1510826Y1672007D03*
X1502952Y1677519D03*
X1510826Y1681456D03*
X1502952Y1682244D03*
X1510826Y1686180D03*
X1502952Y1691692D03*
X1510826Y1695629D03*
X1502952Y1696417D03*
X1510826Y1700354D03*
X1502952Y1705866D03*
X1510826Y1709803D03*
X1502952Y1710590D03*
X1510826Y1714527D03*
X1502952Y1720039D03*
X1510826Y1723976D03*
X1502952Y1724763D03*
X1510826Y1728700D03*
X1502952Y1734212D03*
X1526574Y1672007D03*
X1518700Y1677519D03*
X1526574Y1681456D03*
X1518700Y1682244D03*
X1526574Y1686180D03*
X1518700Y1691692D03*
X1526574Y1695629D03*
X1518700Y1696417D03*
X1526574Y1700354D03*
X1518700Y1705866D03*
X1526574Y1709803D03*
X1518700Y1710590D03*
X1526574Y1714527D03*
X1518700Y1720039D03*
X1526574Y1723976D03*
X1518700Y1724763D03*
X1526574Y1728700D03*
X1518700Y1734212D03*
X1542322Y1672007D03*
X1534448Y1677519D03*
X1542322Y1681456D03*
X1534448Y1682244D03*
X1542322Y1686180D03*
X1534448Y1691692D03*
X1542322Y1695629D03*
X1534448Y1696417D03*
X1542322Y1700354D03*
X1534448Y1705866D03*
X1542322Y1709803D03*
X1534448Y1710590D03*
X1542322Y1714527D03*
X1534448Y1720039D03*
X1542322Y1723976D03*
X1534448Y1724763D03*
X1542322Y1728700D03*
X1534448Y1734212D03*
X1558070Y1672007D03*
X1550196Y1677519D03*
X1558070Y1681456D03*
X1550196Y1682244D03*
X1558070Y1686180D03*
X1550196Y1691692D03*
X1558070Y1695629D03*
X1550196Y1696417D03*
X1558070Y1700354D03*
X1550196Y1705866D03*
X1558070Y1709803D03*
X1550196Y1710590D03*
X1558070Y1714527D03*
X1550196Y1720039D03*
X1558070Y1723976D03*
X1550196Y1724763D03*
X1558070Y1728700D03*
X1550196Y1734212D03*
X1569882Y1677519D03*
Y1682244D03*
Y1691692D03*
Y1696417D03*
Y1705866D03*
Y1710590D03*
Y1720039D03*
Y1724763D03*
Y1734212D03*
X1577756Y1672007D03*
X1585630Y1677519D03*
Y1682244D03*
X1577756Y1681456D03*
Y1686180D03*
X1585630Y1691692D03*
Y1696417D03*
X1577756Y1695629D03*
Y1700354D03*
X1585630Y1705866D03*
Y1710590D03*
X1577756Y1709803D03*
Y1714527D03*
X1585630Y1720039D03*
Y1724763D03*
X1577756Y1723976D03*
Y1728700D03*
X1585630Y1734212D03*
X1593504Y1672007D03*
Y1681456D03*
Y1686180D03*
X1601378Y1677519D03*
Y1682244D03*
X1593504Y1695629D03*
Y1700354D03*
X1601378Y1691692D03*
Y1696417D03*
X1593504Y1709803D03*
Y1714527D03*
X1601378Y1705866D03*
Y1710590D03*
X1593504Y1723976D03*
Y1728700D03*
X1601378Y1720039D03*
Y1724763D03*
Y1734212D03*
X1609252Y1672007D03*
X1617126Y1677519D03*
Y1682244D03*
X1609252Y1681456D03*
Y1686180D03*
X1617126Y1691692D03*
Y1696417D03*
X1609252Y1695629D03*
Y1700354D03*
X1617126Y1705866D03*
Y1710590D03*
X1609252Y1709803D03*
Y1714527D03*
X1617126Y1720039D03*
Y1724763D03*
X1609252Y1723976D03*
Y1728700D03*
X1617126Y1734212D03*
X1625000Y1672007D03*
Y1681456D03*
Y1686180D03*
Y1695629D03*
Y1700354D03*
Y1709803D03*
Y1714527D03*
Y1723976D03*
Y1728700D03*
G54D73*
X1859986Y1403418D03*
X1859706Y1709011D03*
X1871790Y476573D03*
X1861790D03*
X1870648Y783729D03*
X1860648D03*
X1862295Y850767D03*
X1872295D03*
X1871790Y1158071D03*
X1861790D03*
X1869986Y1403418D03*
X1869706Y1709011D03*
X1881862Y107291D03*
X1882340Y410829D03*
X1882711Y476864D03*
X1882240Y783474D03*
X1883273Y850816D03*
X1882579Y1158348D03*
X1881223Y1404467D03*
X1881177Y1709323D03*
X1891862Y107291D03*
X1892340Y410829D03*
X1892711Y476864D03*
X1892240Y783474D03*
X1893273Y850816D03*
X1892579Y1158348D03*
X1891223Y1404467D03*
X1891177Y1709323D03*
X2082012Y108312D03*
X2072012D03*
X2071128Y410829D03*
X2081128D03*
G54D13*
X27559Y87795D03*
X40708Y631889D03*
Y1368908D03*
X51180Y1714961D03*
X373622Y87795D03*
X395671Y1714960D03*
X661024Y631890D03*
X707677Y1714960D03*
X800787Y87795D03*
X931693Y757874D03*
X931692Y1072835D03*
X931693Y1387795D03*
X1045866Y87795D03*
X1155709Y1714961D03*
X1271260Y631890D03*
X1461806Y1714961D03*
X1499606Y87795D03*
X1806298Y1714961D03*
X1829921Y87795D03*
X1816772Y631889D03*
Y1368897D03*
G54D36*
X277098Y185236D03*
X395208D03*
G54D64*
X1183858Y217205D03*
X1173858D03*
X1193858D03*
G54D46*
X443467Y594259D03*
X1425533Y601230D03*
G54D16*
X27048Y1533228D03*
X79590Y1369350D03*
X137284Y1533228D03*
X215418Y658055D03*
X276440Y1357539D03*
X420125Y656008D03*
X443764Y1339823D03*
X523173Y578174D03*
X681440Y1385138D03*
X791678D03*
X873622Y1145275D03*
X983858D03*
X1052960Y1369350D03*
X1249812Y1357539D03*
X1370284Y582303D03*
X1417134Y1339823D03*
X1533552Y682342D03*
X1629732Y1383523D03*
X1664890Y642972D03*
X1714330Y1570984D03*
X1739968Y1383527D03*
X1761575Y159134D03*
X1824566Y1570988D03*
X1838150Y201929D03*
G54D51*
X757184Y1702772D03*
X1072863Y1409176D03*
X1080970Y1640958D03*
G54D65*
X1225530Y60384D03*
G54D72*
X1835198Y1601502D03*
G54D76*
X1864986Y1390234D03*
X1886862Y94107D03*
X1887711Y463680D03*
X1888273Y837632D03*
G54D74*
X1866790Y463389D03*
X1867295Y837583D03*
X1886223Y1391283D03*
X2077012Y95128D03*
G54D38*
X303154Y879624D03*
Y886002D03*
X305004Y882813D03*
X303154Y892380D03*
Y898758D03*
X310555Y873246D03*
X317957Y879624D03*
X310555D03*
X319807Y876435D03*
X314256Y873246D03*
X310555Y886002D03*
X314256D03*
X316107Y882813D03*
Y889191D03*
X308705D03*
X319807Y882813D03*
X314256Y892380D03*
X308705Y895569D03*
Y882813D03*
X314256Y898758D03*
X316107Y901947D03*
X308705D03*
Y908325D03*
X314256Y911513D03*
X316107Y908325D03*
X314256Y917891D03*
X308705Y914702D03*
Y921080D03*
X316107D03*
Y940214D03*
X308705Y927458D03*
X316107D03*
X308705Y933836D03*
X314256Y930647D03*
Y937025D03*
X308705Y940214D03*
X314256Y949781D03*
X316107Y946592D03*
X308705D03*
Y952970D03*
X314256Y956159D03*
X316107Y959348D03*
X308705D03*
Y965726D03*
X316107D03*
X314256Y968915D03*
X317957Y981671D03*
X308705Y978482D03*
X316107D03*
X314256Y975293D03*
X308705Y972104D03*
X316107Y984860D03*
X308705D03*
X312406D03*
X319807D03*
X308705Y991238D03*
X310555Y988049D03*
X314256D03*
X316107Y997616D03*
X308705D03*
X314256Y994427D03*
X316107Y1003994D03*
X314256Y1007183D03*
X316107Y1010372D03*
X308705D03*
Y1003994D03*
X327209Y876435D03*
X332760Y879624D03*
X325358D03*
X334598Y872066D03*
X334610Y882813D03*
X321658Y886002D03*
X325358D03*
X330910Y882813D03*
X329059Y886002D03*
X334610Y889191D03*
X327209D03*
X334610Y895569D03*
X321658Y892380D03*
X327209Y895569D03*
X329059Y892380D03*
X334610Y901947D03*
X321658Y898758D03*
X327209Y901947D03*
X329059Y898758D03*
X321658Y905135D03*
Y911513D03*
X329059Y905135D03*
Y911513D03*
X327209Y908325D03*
X334610Y908324D03*
Y914702D03*
X321658Y917891D03*
X327209Y914702D03*
X329059Y917891D03*
X334610Y921080D03*
X321658Y924269D03*
X329059D03*
X327209Y921080D03*
X334610Y927458D03*
Y933836D03*
X321658Y930647D03*
X327209Y927458D03*
Y933836D03*
X329059Y930647D03*
X334610Y940214D03*
X321658Y937025D03*
X327209Y940214D03*
X329059Y937025D03*
Y956159D03*
X334610Y946592D03*
X321658Y943403D03*
Y949781D03*
X329059Y943403D03*
Y949781D03*
X327209Y946592D03*
X334610Y952970D03*
X321658Y956159D03*
X327209Y952970D03*
X334610Y959348D03*
Y965726D03*
X329059Y962537D03*
X327209Y965726D03*
X321658Y962537D03*
X327209Y959348D03*
X321658Y968915D03*
X329059D03*
X334610Y972104D03*
Y978482D03*
X321658Y975293D03*
Y981671D03*
X329059Y975293D03*
X327209Y972104D03*
X332760Y981671D03*
X329059D03*
X327209Y978482D03*
X334610Y984860D03*
X327209D03*
X330910D03*
X334610Y991238D03*
Y997616D03*
X321658Y988049D03*
Y994427D03*
X327209Y991238D03*
X329059Y988049D03*
Y994427D03*
X327209Y997616D03*
X321658Y1000805D03*
X329059D03*
X334610Y1003994D03*
Y1010372D03*
X321658Y1007183D03*
X327209Y1010372D03*
X329059Y1007183D03*
X327209Y1003994D03*
X343862Y879624D03*
X340162Y879568D03*
X345713Y882813D03*
X336461Y886002D03*
X340162D03*
X347563D03*
X342012Y882813D03*
X347563Y892380D03*
X342012Y889191D03*
X340162Y892380D03*
X347563Y898758D03*
Y905135D03*
Y911513D03*
X342012Y901947D03*
X340162Y898758D03*
Y911513D03*
X342012Y908325D03*
X347563Y917891D03*
Y924269D03*
X340162Y917891D03*
X342012Y921080D03*
X347563Y930647D03*
Y937025D03*
X342012Y927458D03*
X340162Y930647D03*
X342012Y940214D03*
X340162Y937025D03*
X347563Y943403D03*
Y949781D03*
Y956159D03*
X340162Y949781D03*
X342012Y946592D03*
X340162Y956159D03*
X347563Y962537D03*
Y968915D03*
X342012Y959348D03*
Y965726D03*
X340162Y968915D03*
X347563Y975293D03*
Y981671D03*
X345713Y984860D03*
X340162Y975293D03*
X343862Y981671D03*
X342012Y978482D03*
Y984860D03*
X347563Y988049D03*
Y994427D03*
Y1000805D03*
X340162Y988049D03*
X342012Y997616D03*
X340162Y994427D03*
X347563Y1007183D03*
X342012Y1010372D03*
X340162Y1007183D03*
X342012Y1003994D03*
X351265Y879568D03*
X360516Y876435D03*
X354965Y879624D03*
X356803Y872066D03*
X351264Y886002D03*
X362366D03*
X356815Y882813D03*
X360516D03*
X353114D03*
X354965Y886002D03*
Y892380D03*
X360516Y889191D03*
Y895569D03*
X353114Y889191D03*
Y895569D03*
X354965Y898758D03*
X360516Y901947D03*
X353114D03*
X354965Y911513D03*
Y905135D03*
X360516Y908325D03*
X353114Y908324D03*
X354965Y917891D03*
X360516Y914702D03*
X353114D03*
X354965Y924269D03*
X360516Y921080D03*
X353114D03*
X354965Y930647D03*
X360516Y927458D03*
Y933836D03*
X353114D03*
Y927458D03*
X354965Y937025D03*
X360516Y940214D03*
X353114D03*
X360516Y946592D03*
X353114D03*
X360516Y952970D03*
X353114D03*
X354965Y956159D03*
Y943403D03*
Y949781D03*
X360516Y959348D03*
Y965726D03*
X353114Y959348D03*
Y965726D03*
X354965Y962537D03*
Y968915D03*
Y975293D03*
Y981671D03*
X360516Y972104D03*
Y978482D03*
X358665Y981671D03*
X353114Y972104D03*
Y978482D03*
X360516Y984860D03*
X356815D03*
X353114D03*
X360516Y997616D03*
Y991238D03*
X353114D03*
Y997616D03*
X354965Y988049D03*
Y994427D03*
Y1000805D03*
Y1007183D03*
X360516Y1003994D03*
X353114D03*
X360516Y1010372D03*
X353114D03*
X369768Y879624D03*
X373469D03*
X375319Y876435D03*
X377169Y879624D03*
X366067Y886002D03*
Y892380D03*
X367917Y889191D03*
X373469Y892380D03*
X367917Y882813D03*
X373469Y886002D03*
X379020Y882813D03*
X377169Y886002D03*
X379020Y895569D03*
X366067Y898758D03*
Y911513D03*
X367917Y901947D03*
X373469Y898758D03*
X379020Y908325D03*
X373469Y911513D03*
Y905135D03*
X367917Y908324D03*
X366067Y917891D03*
X373469D03*
X367917Y921080D03*
X373469Y924269D03*
X379020Y921080D03*
X366067Y930647D03*
Y937025D03*
X367917Y927458D03*
X379020Y933836D03*
X373469Y930647D03*
X367917Y940214D03*
X373469Y937025D03*
X379020Y940214D03*
X366067Y949781D03*
Y956159D03*
X367917Y946592D03*
X373469Y943403D03*
Y949781D03*
Y956159D03*
X379020Y952970D03*
X366067Y968915D03*
X367917Y959348D03*
Y965726D03*
X373469Y962537D03*
Y968915D03*
X379020Y965726D03*
X366067Y975293D03*
X369768Y981671D03*
X367917Y978482D03*
X373469Y975293D03*
Y981671D03*
X367917Y984860D03*
X379020D03*
X371618D03*
X379020Y978482D03*
X366067Y994427D03*
Y988049D03*
X367917Y997616D03*
X379020Y991238D03*
X373469Y988049D03*
X379020Y997616D03*
X373469Y994427D03*
Y1000805D03*
X366067Y1007183D03*
X373469D03*
X367917Y1003994D03*
X379020D03*
X367917Y1010372D03*
X386421Y876435D03*
X388272Y879624D03*
X384571Y873246D03*
X382721Y882813D03*
Y889191D03*
X380870Y892380D03*
X384571Y886002D03*
X386421Y882813D03*
X393823D03*
X388272Y886002D03*
X390122Y882813D03*
X391973Y892380D03*
X390122Y895569D03*
X386421Y889191D03*
X393823D03*
X382721Y901947D03*
X380870Y898758D03*
Y911513D03*
Y905135D03*
X393823Y901947D03*
X391973Y898758D03*
X390122Y901947D03*
X386421D03*
X391973Y905135D03*
Y911513D03*
X390122Y908325D03*
X382721Y914702D03*
X380870Y917891D03*
Y924269D03*
X386421Y914702D03*
X391973Y917891D03*
X393823Y914702D03*
X390122D03*
Y921080D03*
X391973Y924269D03*
X382721Y927458D03*
Y933836D03*
X380870Y930647D03*
X386421Y927458D03*
Y933836D03*
X393823Y927458D03*
X390122D03*
X393823Y933836D03*
X391973Y930647D03*
X390122Y933836D03*
Y940214D03*
X382721Y946592D03*
X380870Y943403D03*
Y949781D03*
Y956159D03*
X386421Y946592D03*
X391973Y943403D03*
Y949781D03*
X393823Y946592D03*
X390122D03*
X391973Y956159D03*
X390122Y952970D03*
X382721Y959348D03*
X380870Y962537D03*
Y968915D03*
X393823Y959348D03*
X390122D03*
Y965726D03*
X386421Y959348D03*
X391973Y962537D03*
Y968915D03*
X386421Y984860D03*
X382721Y972104D03*
X380870Y975293D03*
X393823Y972104D03*
X390122D03*
Y978482D03*
X384571Y981671D03*
X391973D03*
Y975293D03*
X386421Y972104D03*
X393823Y984860D03*
X391973Y988049D03*
X384571Y994427D03*
Y988049D03*
X391973Y994427D03*
X393823Y991238D03*
X386421D03*
Y997616D03*
X391973Y1000805D03*
X384571D03*
X393823Y997616D03*
X386421Y1003994D03*
X382721Y1010372D03*
X390122D03*
X391973Y1007183D03*
X393823Y1003994D03*
X395673Y1007183D03*
X384571D03*
X410477Y873246D03*
X397524Y876435D03*
X399374Y873246D03*
Y879624D03*
X397524Y882813D03*
Y889191D03*
X401225Y882813D03*
X408626D03*
X404925D03*
X401225Y895569D03*
X408626Y889191D03*
X404925D03*
X403075Y892380D03*
X397524Y901947D03*
X401225D03*
X408626D03*
X404925D03*
X403075Y898758D03*
Y905135D03*
Y911513D03*
X401225Y908324D03*
X397524Y914702D03*
X401225D03*
X408626D03*
X403075Y917891D03*
X404925Y914702D03*
X401225Y921080D03*
X403075Y924269D03*
X401225Y933836D03*
X408626Y927458D03*
X404925D03*
X403075Y930647D03*
X401225Y940214D03*
X397524Y927458D03*
Y933836D03*
X401225Y927458D03*
X397524Y946592D03*
X401225D03*
X403075Y943403D03*
X408626Y946592D03*
X403075Y949781D03*
X404925Y946592D03*
X401225Y952970D03*
X403075Y956159D03*
X397524Y959348D03*
X401225Y965726D03*
Y959348D03*
X408626D03*
X404925D03*
X403075Y962537D03*
Y968915D03*
X397524Y972104D03*
X401225D03*
X408626D03*
X404925D03*
X399374Y981671D03*
X406776D03*
X401225Y978482D03*
X403075Y975293D03*
X401225Y984860D03*
X408626D03*
Y991238D03*
X399374Y988049D03*
Y994427D03*
X406776Y988049D03*
X401225Y991238D03*
Y997616D03*
X399374Y1000805D03*
X397524Y1010372D03*
X399374Y1007183D03*
X401225Y1003994D03*
X421579Y873246D03*
X412327Y882813D03*
Y895569D03*
X414177Y892380D03*
X419729Y882813D03*
X416028D03*
X423429Y895569D03*
X425280Y892380D03*
X416028Y889191D03*
X419729D03*
X412327Y901947D03*
X414177Y898758D03*
Y905135D03*
Y911513D03*
X412327Y908325D03*
X423429Y901947D03*
X425280Y898758D03*
X419729Y901947D03*
X416028D03*
X425280Y905135D03*
Y911513D03*
X423429Y908324D03*
X414177Y917891D03*
X412327Y914702D03*
X414177Y924269D03*
X412327Y921080D03*
X423429Y914702D03*
X419729D03*
X416028D03*
X425280Y917891D03*
Y924269D03*
X423429Y921080D03*
X412327Y927458D03*
Y933836D03*
X414177Y930647D03*
X412327Y940214D03*
X414177Y937025D03*
X423429Y927458D03*
X419729D03*
X423429Y933836D03*
X425280Y930647D03*
X419729Y933836D03*
X416028Y927458D03*
Y933836D03*
X425280Y937025D03*
X423429Y940214D03*
X414177Y949781D03*
X412327Y946592D03*
X414177Y943403D03*
X412327Y952970D03*
X414177Y956159D03*
X416028Y946592D03*
X425280Y943403D03*
Y949781D03*
X423429Y946592D03*
X419729D03*
X423429Y952970D03*
X425280Y956159D03*
X412327Y965726D03*
Y959348D03*
X414177Y962537D03*
Y968915D03*
X423429Y965726D03*
X416028Y959348D03*
X423429D03*
X419729D03*
X425280Y962537D03*
Y968915D03*
X416028Y972104D03*
X423429D03*
X419729D03*
X416028Y984860D03*
X423429D03*
X412327Y978482D03*
X414177Y981671D03*
Y975293D03*
X412327Y972104D03*
X423429Y978482D03*
X421579Y981671D03*
X425280Y975293D03*
X414177Y988049D03*
X421579D03*
X423429Y991238D03*
X416028D03*
X434532Y876435D03*
X432681Y879624D03*
X430831Y882813D03*
X427130D03*
X430831Y889191D03*
X427130D03*
X434532Y895569D03*
Y889191D03*
X428981Y905135D03*
X434532Y901947D03*
X432681Y905135D03*
X434532Y908325D03*
X428981Y917891D03*
X432681D03*
X434532Y914702D03*
Y921080D03*
X428981Y930647D03*
Y937025D03*
X432681Y930647D03*
X434532Y927458D03*
Y933836D03*
X432681Y937025D03*
X434532Y940214D03*
X428981Y949781D03*
X432681D03*
X434532Y946592D03*
Y952970D03*
X428981Y962537D03*
X432681D03*
X434532Y959348D03*
Y965726D03*
X428981Y981671D03*
Y975293D03*
X430831Y984860D03*
X434532Y972104D03*
X432681Y975293D03*
X434532Y978482D03*
X430831Y991238D03*
X428981Y988049D03*
X445609Y876435D03*
X447460Y879624D03*
X445609Y882813D03*
Y889191D03*
Y895569D03*
X453011Y882813D03*
X449310Y889191D03*
X453011D03*
X454861Y892380D03*
X445609Y901947D03*
Y908325D03*
X454861Y898758D03*
X451160Y905135D03*
X454861D03*
Y911513D03*
X447460Y905135D03*
X445609Y914702D03*
Y921080D03*
X447460Y917891D03*
X451160D03*
X454861D03*
Y924269D03*
Y930647D03*
X447460Y937025D03*
X451160D03*
X454861D03*
X445609Y927458D03*
Y933836D03*
Y940214D03*
X447460Y930647D03*
X451160D03*
X445609Y946592D03*
Y952970D03*
X447460Y949781D03*
X454861Y943403D03*
X451160Y949781D03*
X454861D03*
Y956159D03*
X445609Y959348D03*
Y965726D03*
X454861Y962537D03*
X451160D03*
X447460D03*
X454861Y968915D03*
X445609Y972104D03*
Y978482D03*
Y984860D03*
X447460Y981671D03*
X454861D03*
X451160Y975293D03*
X447460D03*
X454861D03*
X453011Y984860D03*
X445609Y991238D03*
X453011D03*
X454861Y988049D03*
X447460D03*
X460412Y876435D03*
X469664Y879624D03*
X460412Y889191D03*
X456712Y895569D03*
X467814Y882813D03*
X465964Y892380D03*
X467814Y895569D03*
X464113Y889191D03*
X456712Y908324D03*
X465964Y911513D03*
X456712Y901947D03*
X460412D03*
X465964Y898758D03*
X467814Y901947D03*
X464113D03*
X467814Y908325D03*
X465964Y905135D03*
X460412Y914702D03*
X456712D03*
Y921080D03*
X467814Y914702D03*
X464113D03*
X465964Y917891D03*
X467814Y921080D03*
X465964Y924269D03*
X460412Y927458D03*
X456712D03*
Y933836D03*
X460412D03*
X456712Y940214D03*
X467814Y927458D03*
Y933836D03*
X464113Y927458D03*
Y933836D03*
X467814Y940214D03*
X465964Y937025D03*
X460412Y946592D03*
X456712D03*
Y952970D03*
X467814Y946592D03*
X464113D03*
X465964Y943403D03*
Y949781D03*
X467814Y952970D03*
X465964Y956159D03*
X456712Y965726D03*
X460412Y959348D03*
X456712D03*
X467814Y965726D03*
Y959348D03*
X465964Y962537D03*
X464113Y959348D03*
X465964Y968915D03*
X456712Y972104D03*
Y978482D03*
X462263Y981671D03*
X460412Y972104D03*
Y984860D03*
X469664Y981671D03*
X467814Y978482D03*
Y972104D03*
X465964Y975293D03*
X464113Y972104D03*
X467814Y984860D03*
X460412Y991238D03*
X462263Y988049D03*
X469664D03*
X467814Y991238D03*
X471515Y876435D03*
X480767Y873246D03*
Y879624D03*
X482617Y876435D03*
X478916Y882813D03*
X475215D03*
X471515D03*
X478916Y895569D03*
X477066Y892380D03*
X475215Y889191D03*
X471515D03*
X482617Y882813D03*
Y889191D03*
X478916Y901947D03*
X471515D03*
X475215D03*
X477066Y898758D03*
X478916Y908325D03*
X477066Y905135D03*
Y911513D03*
X482617Y901947D03*
X478916Y914702D03*
X477066Y917891D03*
X475215Y914702D03*
X471515D03*
X478916Y921080D03*
X477066Y924269D03*
X482617Y914702D03*
X478916Y927458D03*
Y933836D03*
X475215Y927458D03*
X471515D03*
X477066Y930647D03*
X478916Y940214D03*
X482617Y927458D03*
Y933836D03*
X478916Y946592D03*
X477066Y943403D03*
X475215Y946592D03*
X471515D03*
X477066Y949781D03*
X478916Y952970D03*
X477066Y956159D03*
X482617Y946592D03*
X478916Y965726D03*
Y959348D03*
X475215D03*
X471515D03*
X477066Y962537D03*
Y968915D03*
X482617Y959348D03*
X478916Y978482D03*
Y972104D03*
X477066Y981671D03*
Y975293D03*
X475215Y972104D03*
X471515D03*
X475215Y984860D03*
X484467Y981671D03*
X482617Y972104D03*
Y984860D03*
X477066Y994427D03*
X475215Y991238D03*
X477066Y988049D03*
Y1000805D03*
X484467Y994427D03*
Y988049D03*
X482617Y991238D03*
Y997616D03*
X484467Y1000805D03*
X477066Y1007183D03*
X484467D03*
X482617Y1010372D03*
Y1003994D03*
X493719Y876435D03*
X491869Y879624D03*
X493719Y882813D03*
X490019D03*
X486318D03*
X493719Y889191D03*
X486318D03*
X490019Y895569D03*
X488168Y892380D03*
X497420Y889191D03*
X499271Y892380D03*
X493719Y901947D03*
X486318D03*
X490019D03*
X488168Y898758D03*
Y905135D03*
Y911513D03*
X497420Y901947D03*
X499271Y898758D03*
Y905135D03*
Y911513D03*
X490019Y908324D03*
X493719Y914702D03*
X488168Y917891D03*
X490019Y914702D03*
X486318D03*
X490019Y921080D03*
X488168Y924269D03*
X499271Y917891D03*
X497420Y914702D03*
X499271Y924269D03*
X493719Y927458D03*
X486318D03*
X490019D03*
X493719Y933836D03*
X490019D03*
X486318D03*
X488168Y930647D03*
X490019Y940214D03*
X497420Y927458D03*
Y933836D03*
X499271Y930647D03*
X488168Y943403D03*
X493719Y946592D03*
X490019D03*
X486318D03*
X488168Y949781D03*
X490019Y952970D03*
X488168Y956159D03*
X497420Y946592D03*
X499271Y943403D03*
Y949781D03*
Y956159D03*
X490019Y965726D03*
X493719Y959348D03*
X490019D03*
X486318D03*
X488168Y962537D03*
Y968915D03*
X499271Y962537D03*
X497420Y959348D03*
X499271Y968915D03*
X491869Y981671D03*
X490019Y978482D03*
X493719Y972104D03*
X488168Y975293D03*
X490019Y972104D03*
X486318D03*
X490019Y984860D03*
X497420Y972104D03*
X499271Y975293D03*
Y981671D03*
X497420Y984860D03*
X491869Y994427D03*
Y988049D03*
X490019Y997616D03*
Y991238D03*
X491869Y1000805D03*
X497420Y991238D03*
Y997616D03*
X499271Y988049D03*
Y994427D03*
Y1000805D03*
X491869Y1007183D03*
X490019Y1010372D03*
Y1003994D03*
X497420Y1010372D03*
Y1003994D03*
X499271Y1007183D03*
X502971Y879624D03*
X501133Y872118D03*
X508523Y882813D03*
X506672Y886002D03*
X502971D03*
X504822Y882813D03*
X506672Y892380D03*
X501121Y895569D03*
X512223Y882813D03*
X514074Y886002D03*
X512223Y889191D03*
X514074Y892380D03*
X506672Y898758D03*
Y905135D03*
Y911513D03*
X501121Y908325D03*
X512223Y901947D03*
X514074Y898758D03*
Y911513D03*
X512223Y908325D03*
X506672Y917891D03*
X501121Y921080D03*
X506672Y924269D03*
X514074Y917891D03*
X512223Y921080D03*
X506672Y930647D03*
X501121Y933836D03*
X506672Y937025D03*
X501121Y940214D03*
X512223Y927458D03*
X514074Y930647D03*
X512223Y940214D03*
X514074Y937025D03*
X506672Y943403D03*
Y949781D03*
X501121Y952970D03*
X506672Y956159D03*
X514074Y949781D03*
X512223Y946592D03*
X514074Y956159D03*
X506672Y962537D03*
X501121Y965726D03*
X506672Y968915D03*
X512223Y959348D03*
Y965726D03*
X514074Y968915D03*
X510373Y981671D03*
X506672Y975293D03*
Y981671D03*
X501121Y978482D03*
X508523Y984860D03*
X514074Y975293D03*
X512223Y978482D03*
Y984860D03*
X506672Y988049D03*
Y994427D03*
Y1000805D03*
X514074Y988049D03*
Y994427D03*
X512223Y997616D03*
X506672Y1007183D03*
X514074D03*
X512223Y1003994D03*
X525176Y879624D03*
X515924Y876435D03*
X525176Y873246D03*
Y886002D03*
X523326Y882813D03*
X517775Y886002D03*
X519625Y882813D03*
X527027Y895569D03*
Y889191D03*
X525176Y892380D03*
X519625Y889191D03*
Y895569D03*
X528877Y886002D03*
X527027Y901947D03*
X525176Y898758D03*
X519625Y901947D03*
X525176Y905135D03*
Y911513D03*
X519625Y908325D03*
X527027Y908324D03*
X525176Y917891D03*
X519625Y914702D03*
X527027D03*
Y921080D03*
X525176Y924269D03*
X519625Y921080D03*
X525176Y937025D03*
X527027Y927458D03*
Y933836D03*
X525176Y930647D03*
X519625Y927458D03*
Y933836D03*
X527027Y940214D03*
X519625D03*
X527027Y946592D03*
X519625D03*
X525176Y943403D03*
Y949781D03*
X527027Y952970D03*
X525176Y956159D03*
X519625Y952970D03*
X527027Y959348D03*
Y965726D03*
X525176Y962537D03*
X519625Y959348D03*
Y965726D03*
X525176Y968915D03*
X521475Y981671D03*
X519625Y978482D03*
X527027Y984860D03*
X523326D03*
X519625D03*
X527027Y972104D03*
Y978482D03*
X525176Y975293D03*
Y981671D03*
X519625Y972104D03*
X527027Y991238D03*
Y997616D03*
X525176Y988049D03*
Y994427D03*
X519625Y991238D03*
Y997616D03*
X525176Y1000805D03*
X527027Y1010372D03*
Y1003994D03*
X525176Y1007183D03*
X519625Y1010372D03*
Y1003994D03*
X534428Y876435D03*
X539979Y879624D03*
X532578D03*
X541830Y876435D03*
X543680Y879624D03*
X538129Y889191D03*
X539979Y892380D03*
X532578D03*
X543680Y886002D03*
X538129Y882813D03*
X532578Y886002D03*
X534428Y882813D03*
X538129Y901947D03*
X539979Y898758D03*
X532578D03*
X539979Y911513D03*
X538129Y908325D03*
X532578Y905135D03*
Y911513D03*
X539979Y917891D03*
X532578D03*
X538129Y921080D03*
X532578Y924269D03*
X538129Y927458D03*
X539979Y930647D03*
X532578D03*
X539979Y937025D03*
X538129Y940214D03*
X532578Y937025D03*
X539979Y949781D03*
X538129Y946592D03*
X532578Y943403D03*
Y949781D03*
X539979Y956159D03*
X532578D03*
X538129Y959348D03*
Y965726D03*
X532578Y962537D03*
X539979Y968915D03*
X532578D03*
X539979Y975293D03*
X532578D03*
X538129Y978482D03*
X536279Y981671D03*
X532578D03*
X538129Y984860D03*
X534428D03*
X532578Y994427D03*
X539979Y988049D03*
X532578D03*
X539979Y994427D03*
X538129Y997616D03*
X532578Y1000805D03*
X539978Y1007184D03*
X538129Y1003994D03*
X532578Y1007183D03*
X545531Y876435D03*
X552932D03*
X556633D03*
X551082Y879624D03*
X545543Y872085D03*
X554783Y886002D03*
X549231Y882813D03*
X558483Y892380D03*
X545531Y889191D03*
Y895569D03*
X552932Y889191D03*
X551082Y892380D03*
X552932Y895569D03*
X558483Y886002D03*
X545531Y882813D03*
X551082Y886002D03*
X558483Y898758D03*
X545531Y901947D03*
X552932D03*
X551082Y898758D03*
X558483Y905135D03*
Y911513D03*
X551082Y905135D03*
Y911513D03*
X552932Y908325D03*
X545531Y908324D03*
X558483Y917891D03*
X551082D03*
X552932Y914702D03*
X545531D03*
X558483Y924269D03*
X551082D03*
X552932Y921080D03*
X545531D03*
X558483Y930647D03*
X545531Y927458D03*
Y933836D03*
X552932Y927458D03*
Y933836D03*
X551082Y930647D03*
X558483Y937025D03*
X545531Y940214D03*
X551082Y937025D03*
X552932Y940214D03*
X558483Y943403D03*
Y949781D03*
X545531Y946592D03*
X551082Y943403D03*
Y949781D03*
X552932Y946592D03*
X558483Y956159D03*
X545531Y952970D03*
X552932D03*
X551082Y956159D03*
X558483Y962537D03*
X545531Y959348D03*
Y965726D03*
X552932Y959348D03*
X551082Y962537D03*
X552932Y965726D03*
X558483Y968915D03*
X551082D03*
X558483Y975293D03*
Y981671D03*
X545531Y972104D03*
Y978482D03*
X547381Y981671D03*
X551082Y975293D03*
X552932Y972104D03*
X551082Y981671D03*
X552932Y978482D03*
Y984860D03*
X549231D03*
X545531D03*
X558483Y988049D03*
Y994427D03*
X552932Y991238D03*
X551082Y994427D03*
X552932Y997616D03*
X545531Y991238D03*
Y997616D03*
X551082Y988049D03*
X558483Y1000805D03*
X551082D03*
X558483Y1007183D03*
X545531Y1010372D03*
Y1003994D03*
X552932Y1010372D03*
X551082Y1007183D03*
X552932Y1003994D03*
X562184Y879624D03*
X569586Y873246D03*
X560334Y882813D03*
X564034D03*
X569586Y886002D03*
X571436Y882813D03*
Y889191D03*
X564034D03*
X565885Y892380D03*
X571436Y895569D03*
X564034Y901947D03*
X571436D03*
X565885Y898758D03*
X564034Y908325D03*
X571436D03*
X565885Y911513D03*
Y917891D03*
X571436Y914702D03*
X564034Y921080D03*
X571436D03*
X564034Y927458D03*
X571436D03*
X565885Y930647D03*
X571436Y933836D03*
X565885Y937025D03*
X564034Y940214D03*
X571436D03*
X565885Y949781D03*
X564034Y946592D03*
X571436D03*
Y952970D03*
X565885Y956159D03*
X564034Y959348D03*
X571436D03*
X564034Y965726D03*
X571436D03*
X565885Y968915D03*
X562184Y981671D03*
X565885Y975293D03*
X571436Y972104D03*
X564034Y978482D03*
X571436D03*
X567735Y984860D03*
X560334D03*
X564034D03*
X571436D03*
X569586Y988049D03*
X571436Y991238D03*
X565885Y994427D03*
X564034Y997616D03*
X571436D03*
X565885Y988049D03*
X571436Y1010372D03*
X565885Y1007183D03*
X564034Y1003994D03*
X571436D03*
X576987Y879624D03*
X575137Y882813D03*
X576987Y886002D03*
Y892380D03*
Y898758D03*
X1286697Y873245D03*
Y879623D03*
X1279296D03*
X1284847Y895568D03*
Y882812D03*
X1286697Y886001D03*
X1281146Y882812D03*
X1279296Y886001D03*
X1284847Y889190D03*
X1279296Y892379D03*
X1284847Y901946D03*
X1279296Y898757D03*
X1284847Y908324D03*
Y914701D03*
Y921079D03*
Y927457D03*
Y933835D03*
Y940213D03*
Y946591D03*
Y952969D03*
Y959347D03*
Y965725D03*
Y972103D03*
Y978481D03*
Y984859D03*
X1288548D03*
X1284847Y991237D03*
X1286697Y988048D03*
X1284847Y997615D03*
Y1010371D03*
Y1003993D03*
X1290398Y873245D03*
X1301500Y879623D03*
X1303351Y876434D03*
X1294099Y879623D03*
X1295949Y876434D03*
X1303351Y895568D03*
X1290398Y886001D03*
Y892379D03*
X1292249Y882812D03*
X1297800Y886001D03*
X1301500D03*
X1295949Y882812D03*
X1292249Y889190D03*
X1303351D03*
X1297800Y892379D03*
X1290398Y898757D03*
Y911512D03*
X1292249Y901946D03*
X1297800Y898757D03*
X1303351Y901946D03*
X1292249Y908324D03*
X1297800Y905134D03*
Y911512D03*
X1303351Y908324D03*
X1290398Y917890D03*
X1297800D03*
X1303351Y914701D03*
Y921079D03*
X1297800Y924268D03*
X1292249Y921079D03*
X1297800Y930646D03*
X1303351Y927457D03*
Y933835D03*
X1292249Y927457D03*
X1303351Y940213D03*
X1297800Y937024D03*
X1292249Y940213D03*
X1290398Y930646D03*
Y937024D03*
Y949780D03*
Y956158D03*
X1297800Y949780D03*
X1303351Y946591D03*
X1292249D03*
X1297800Y943402D03*
X1303351Y952969D03*
X1297800Y956158D03*
X1290398Y968914D03*
X1297800Y962536D03*
X1303351Y959347D03*
Y965725D03*
X1292249Y959347D03*
Y965725D03*
X1297800Y968914D03*
X1290398Y975292D03*
X1297800Y981670D03*
Y975292D03*
X1303351Y972103D03*
Y978481D03*
X1294099Y981670D03*
X1292249Y978481D03*
X1303351Y984859D03*
X1295949D03*
X1292249D03*
X1290398Y988048D03*
Y994426D03*
X1297800D03*
Y988048D03*
X1303351Y991237D03*
Y997615D03*
X1292249D03*
X1297800Y1000804D03*
X1290398Y1007182D03*
X1292249Y1010371D03*
X1297800Y1007182D03*
X1303351Y1010371D03*
Y1003993D03*
X1292249D03*
X1314453Y876434D03*
X1308902Y873245D03*
Y879623D03*
X1310752Y895568D03*
X1307052Y882812D03*
X1305201Y886001D03*
Y892379D03*
X1310752Y882812D03*
X1312603Y886001D03*
X1316304D03*
X1318154Y882812D03*
X1310752Y889190D03*
X1318154D03*
X1316304Y892379D03*
X1305201Y898757D03*
Y905134D03*
Y911512D03*
X1310752Y901946D03*
X1318154D03*
X1316304Y898757D03*
Y911512D03*
X1318154Y908324D03*
X1310752Y908323D03*
X1305201Y917890D03*
Y924268D03*
X1310752Y914701D03*
X1316304Y917890D03*
X1318154Y921079D03*
X1310752D03*
X1305201Y930646D03*
Y937024D03*
X1310752Y927457D03*
Y933835D03*
X1318154Y927457D03*
X1316304Y930646D03*
Y937024D03*
X1310752Y940213D03*
X1318154D03*
X1305201Y943402D03*
Y949780D03*
Y956158D03*
X1310752Y946591D03*
X1316304Y949780D03*
X1318154Y946591D03*
X1310752Y952969D03*
X1316304Y956158D03*
X1318154Y959347D03*
Y965725D03*
X1316304Y968914D03*
X1305201Y962536D03*
Y968914D03*
X1310752Y959347D03*
Y965725D03*
X1305201Y975292D03*
Y981670D03*
X1307052Y984859D03*
X1310752Y972103D03*
Y978481D03*
X1316304Y975292D03*
X1318154Y978481D03*
X1308902Y981670D03*
X1310752Y984859D03*
X1318154D03*
X1305201Y988048D03*
Y994426D03*
Y1000804D03*
X1310752Y991237D03*
Y997615D03*
X1316304Y988048D03*
X1318154Y997615D03*
X1316304Y994426D03*
X1305201Y1007182D03*
X1310752Y1003993D03*
Y1010371D03*
X1318154D03*
X1316304Y1007182D03*
X1318154Y1003993D03*
X1320004Y879623D03*
X1331107Y873245D03*
X1325556Y876434D03*
X1331107Y879623D03*
X1321855Y882812D03*
X1323705Y886001D03*
X1329256Y882812D03*
X1332957D03*
X1331107Y886001D03*
X1327406D03*
X1323705Y892379D03*
X1329256Y889190D03*
X1331107Y892379D03*
X1329256Y895568D03*
X1323705Y898757D03*
X1331107D03*
X1329256Y901946D03*
X1331107Y911512D03*
X1323705D03*
Y905134D03*
X1331107D03*
X1329256Y908323D03*
Y914701D03*
X1323705Y917890D03*
X1331107D03*
X1323705Y924268D03*
X1329256Y921079D03*
X1331107Y924268D03*
Y930646D03*
X1329256Y933835D03*
X1323705Y930646D03*
X1329256Y927457D03*
X1331107Y937024D03*
X1329256Y940213D03*
X1323705Y937024D03*
X1331107Y943402D03*
X1329256Y946591D03*
X1331107Y949780D03*
X1323705Y943402D03*
Y949780D03*
X1329256Y952969D03*
X1331107Y956158D03*
X1323705D03*
X1329256Y959347D03*
X1331107Y962536D03*
X1329256Y965725D03*
X1323705Y962536D03*
X1331107Y968914D03*
X1323705D03*
X1320004Y981670D03*
X1321855Y984859D03*
X1323705Y975292D03*
Y981670D03*
X1329256Y972103D03*
X1331107Y975292D03*
X1329256Y978481D03*
X1331107Y981670D03*
X1334807D03*
X1329256Y984859D03*
X1332957D03*
X1323705Y1000804D03*
Y988048D03*
Y994426D03*
X1329256Y997615D03*
X1331107Y988048D03*
X1329256Y991237D03*
X1331107Y994426D03*
Y1000804D03*
X1323705Y1007182D03*
X1329256Y1003993D03*
X1331107Y1007182D03*
X1329256Y1010371D03*
X1336658Y876434D03*
X1345910Y879623D03*
X1349611D03*
X1338508Y886001D03*
X1336658Y882812D03*
Y889190D03*
Y895568D03*
X1342209Y886001D03*
X1349611D03*
X1344059Y882812D03*
Y889190D03*
X1342209Y892379D03*
X1349611D03*
X1336658Y901946D03*
Y908324D03*
X1342209Y898757D03*
X1349611D03*
X1344059Y901946D03*
X1349611Y905134D03*
X1342209Y911512D03*
X1349611D03*
X1344059Y908323D03*
X1336658Y914701D03*
Y921079D03*
X1342209Y917890D03*
X1349611D03*
X1344059Y921079D03*
X1349611Y924268D03*
X1336658Y933835D03*
Y927457D03*
Y940213D03*
X1344059Y927457D03*
X1342209Y930646D03*
X1349611D03*
X1344059Y940213D03*
X1342209Y937024D03*
X1349611D03*
Y943402D03*
X1344059Y946591D03*
X1349611Y949780D03*
X1342209D03*
X1349611Y956158D03*
X1342209D03*
X1336658Y946591D03*
Y952969D03*
Y965725D03*
Y959347D03*
X1344059D03*
X1349611Y962536D03*
X1344059Y965725D03*
X1349611Y968914D03*
X1342209D03*
X1336658Y972103D03*
Y978481D03*
Y984859D03*
X1349611Y975292D03*
X1342209D03*
X1344059Y978481D03*
X1349611Y981670D03*
X1345910D03*
X1344059Y984859D03*
X1347760D03*
X1336658Y997615D03*
Y991237D03*
X1349611Y988048D03*
Y994426D03*
X1342209D03*
X1344059Y997615D03*
X1342209Y988048D03*
X1349611Y1000804D03*
X1336658Y1010371D03*
X1344059D03*
X1336658Y1003993D03*
X1344059D03*
X1342209Y1007182D03*
X1349611D03*
X1351461Y876434D03*
X1353311Y879623D03*
X1364414D03*
X1360713Y873245D03*
X1362563Y876434D03*
X1353311Y886001D03*
X1362563Y882812D03*
X1358863D03*
X1364414Y886001D03*
X1360713D03*
X1355162Y882812D03*
X1357012Y892379D03*
X1355162Y895568D03*
X1362563Y889190D03*
X1358863D03*
X1357012Y898757D03*
X1362563Y901946D03*
X1358863D03*
X1357012Y905134D03*
Y911512D03*
X1355162Y908324D03*
X1358863Y914701D03*
X1362563D03*
X1357012Y917890D03*
X1355162Y921079D03*
X1357012Y924268D03*
X1362563Y933835D03*
X1358863D03*
X1355162D03*
X1362563Y927457D03*
X1358863D03*
X1357012Y930646D03*
X1355162Y940213D03*
X1357012Y943402D03*
X1358863Y946591D03*
X1362563D03*
X1357012Y949780D03*
Y956158D03*
X1355162Y952969D03*
X1358863Y959347D03*
X1362563D03*
X1357012Y962536D03*
X1355162Y965725D03*
X1357012Y968914D03*
X1358863Y972103D03*
X1362563D03*
X1357012Y975292D03*
X1360713Y981670D03*
X1355162Y978481D03*
X1362563Y984859D03*
X1355162D03*
Y991237D03*
Y997615D03*
X1362563Y991237D03*
Y997615D03*
X1360713Y994426D03*
Y988048D03*
Y1000804D03*
X1358863Y1010371D03*
X1360713Y1007182D03*
X1362563Y1003993D03*
X1355162D03*
X1373666Y876434D03*
X1375516Y873245D03*
Y879623D03*
X1369965Y882812D03*
X1366264D03*
X1369965Y889190D03*
X1368115Y892379D03*
X1366264Y895568D03*
X1373666Y882812D03*
X1377367D03*
X1379217Y892379D03*
X1377367Y895568D03*
X1373666Y889190D03*
X1368115Y898757D03*
X1369965Y901946D03*
X1366264D03*
X1368115Y905134D03*
Y911512D03*
X1366264Y908324D03*
X1379217Y898757D03*
X1377367Y901946D03*
X1373666D03*
X1379217Y905134D03*
X1377367Y908324D03*
X1379217Y911512D03*
X1369965Y914701D03*
X1368115Y917890D03*
X1366264Y914701D03*
X1368115Y924268D03*
X1366264Y921079D03*
X1377367Y914701D03*
X1373666D03*
X1379217Y917890D03*
X1377367Y921079D03*
X1379217Y924268D03*
X1366264Y933835D03*
X1369965Y927457D03*
X1368115Y930646D03*
X1369965Y933835D03*
X1366264Y927457D03*
Y940213D03*
X1377367Y927457D03*
X1373666D03*
X1379217Y930646D03*
X1377367Y933835D03*
X1373666D03*
X1377367Y940213D03*
X1368115Y943402D03*
X1369965Y946591D03*
X1368115Y949780D03*
X1366264Y946591D03*
X1368115Y956158D03*
X1366264Y952969D03*
X1379217Y943402D03*
X1373666Y946591D03*
X1377367D03*
X1379217Y949780D03*
X1377367Y952969D03*
X1379217Y956158D03*
X1366264Y959347D03*
X1369965D03*
X1368115Y962536D03*
X1366264Y965725D03*
X1368115Y968914D03*
X1373666Y959347D03*
X1377367Y965725D03*
Y959347D03*
X1379217Y962536D03*
Y968914D03*
X1369965Y972103D03*
X1368115Y975292D03*
Y981670D03*
X1366264Y972103D03*
Y978481D03*
X1369965Y984859D03*
X1373666Y972103D03*
X1377367D03*
X1379217Y975292D03*
X1375516Y981670D03*
X1377367Y978481D03*
Y984859D03*
X1369965Y991237D03*
Y997615D03*
X1368115Y994426D03*
Y988048D03*
Y1000804D03*
X1375516Y994426D03*
X1377367Y991237D03*
Y997615D03*
X1375516Y988048D03*
Y1000804D03*
X1369965Y1003993D03*
X1368115Y1007182D03*
X1366264Y1010371D03*
X1373666D03*
X1375516Y1007182D03*
X1371815D03*
X1377367Y1003993D03*
X1386619Y879623D03*
X1382918Y873245D03*
X1384768Y876434D03*
X1394020Y873245D03*
X1384768Y882812D03*
X1381067D03*
Y889190D03*
X1384768D03*
X1392170Y882812D03*
X1388469D03*
Y895568D03*
X1392170Y889190D03*
X1390319Y892379D03*
X1381067Y901946D03*
X1384768D03*
X1388469D03*
X1390319Y898757D03*
X1392170Y901946D03*
X1388469Y908324D03*
X1390319Y911512D03*
Y905134D03*
X1381067Y914701D03*
X1384768D03*
X1390319Y917890D03*
X1388469Y914701D03*
X1392170D03*
X1388469Y921079D03*
X1390319Y924268D03*
X1381067Y927457D03*
X1384768D03*
X1388469D03*
Y933835D03*
X1392170Y927457D03*
X1390319Y930646D03*
X1392170Y933835D03*
X1388469Y940213D03*
X1390319Y937024D03*
X1381067Y946591D03*
X1384768D03*
X1388469D03*
X1390319Y943402D03*
X1392170Y946591D03*
X1390319Y949780D03*
X1388469Y952969D03*
X1390319Y956158D03*
X1381067Y959347D03*
X1384768D03*
X1388469Y965725D03*
Y959347D03*
X1392170D03*
X1390319Y962536D03*
Y968914D03*
X1388469Y978481D03*
X1381067Y972103D03*
X1384768D03*
X1382918Y981670D03*
X1384768Y984859D03*
X1388469Y972103D03*
X1392170D03*
X1390319Y981670D03*
Y975292D03*
X1392170Y984859D03*
X1384768Y991237D03*
X1382918Y988048D03*
X1392170Y991237D03*
X1390319Y988048D03*
X1397721Y873245D03*
Y879623D03*
X1395871Y876434D03*
X1408823Y879623D03*
X1399571Y882812D03*
X1395871D03*
X1401422Y892379D03*
X1399571Y895568D03*
X1395871Y889190D03*
X1403272Y882812D03*
X1406973D03*
X1403272Y889190D03*
X1406973D03*
X1399571Y901946D03*
X1395871D03*
X1401422Y905134D03*
Y911512D03*
X1405123Y905134D03*
X1408823D03*
X1401422Y898757D03*
X1399571Y908323D03*
Y914701D03*
X1401422Y917890D03*
X1395871Y914701D03*
X1399571Y921079D03*
X1401422Y924268D03*
X1405123Y917890D03*
X1408823D03*
X1395871Y927457D03*
Y933835D03*
X1399571Y927457D03*
X1401422Y930646D03*
X1399571Y933835D03*
Y940213D03*
X1401422Y937024D03*
X1405123Y930646D03*
X1408823D03*
X1405123Y937024D03*
X1408823D03*
X1401422Y943402D03*
X1399571Y946591D03*
X1401422Y949780D03*
X1399571Y952969D03*
X1401422Y956158D03*
X1408823Y949780D03*
X1405123D03*
X1395871Y946591D03*
X1399571Y965725D03*
X1395871Y959347D03*
X1399571D03*
X1401422Y962536D03*
Y968914D03*
X1408823Y962536D03*
X1405123D03*
X1397721Y981670D03*
X1399571Y978481D03*
X1395871Y972103D03*
X1399571D03*
X1401422Y975292D03*
X1399571Y984859D03*
X1405123Y981670D03*
X1408823Y975292D03*
X1405123D03*
X1406973Y984859D03*
X1399571Y991237D03*
X1397721Y988048D03*
X1406973Y991237D03*
X1405123Y988048D03*
X1410674Y876434D03*
X1423602Y879623D03*
X1421751Y876434D03*
X1410674Y882812D03*
Y889190D03*
Y895568D03*
X1421751Y882812D03*
Y895568D03*
Y889190D03*
X1410674Y901946D03*
Y908324D03*
X1421751Y901946D03*
X1423602Y905134D03*
X1421751Y908324D03*
X1410674Y914701D03*
Y921079D03*
X1423602Y917890D03*
X1421751Y914701D03*
Y921079D03*
Y940213D03*
X1410674Y927457D03*
Y933835D03*
Y940213D03*
X1423602Y930646D03*
X1421751Y927457D03*
Y933835D03*
X1423602Y937024D03*
X1410674Y946591D03*
Y952969D03*
X1423602Y949780D03*
X1421751Y946591D03*
Y952969D03*
X1410674Y959347D03*
Y965725D03*
X1423602Y962536D03*
X1421751Y959347D03*
Y965725D03*
X1410674Y972103D03*
Y978481D03*
X1423602Y981670D03*
Y975292D03*
X1421751Y972103D03*
Y978481D03*
Y984859D03*
X1423602Y988048D03*
X1421751Y991237D03*
X1436554Y876434D03*
X1429153Y882812D03*
X1425452Y889190D03*
X1429153D03*
X1431003Y892379D03*
X1432854Y895568D03*
X1436554Y889190D03*
X1432854Y901946D03*
X1431003Y898757D03*
Y911512D03*
Y905134D03*
X1427302D03*
X1436554Y901946D03*
X1432854Y908323D03*
Y914701D03*
X1431003Y917890D03*
X1427302D03*
X1432854Y921079D03*
X1431003Y924268D03*
X1436554Y914701D03*
X1432854Y927457D03*
X1431003Y930646D03*
X1427302D03*
X1432854Y933835D03*
Y940213D03*
X1431003Y937024D03*
X1427302D03*
X1436554Y927457D03*
Y933835D03*
X1431003Y943402D03*
Y949780D03*
X1427302D03*
X1432854Y946591D03*
Y952969D03*
X1431003Y956158D03*
X1436554Y946591D03*
X1432854Y959347D03*
X1427302Y962536D03*
X1431003D03*
X1432854Y965725D03*
X1431003Y968914D03*
X1436554Y959347D03*
X1432854Y978481D03*
X1431003Y981670D03*
X1432854Y972103D03*
X1431003Y975292D03*
X1427302D03*
X1429153Y984859D03*
X1438405Y981670D03*
X1436554Y972103D03*
Y984859D03*
X1431003Y988048D03*
X1429153Y991237D03*
X1436554D03*
X1438405Y988048D03*
X1447657Y876434D03*
X1445806Y879623D03*
X1443956Y882812D03*
X1447657D03*
X1440255Y889190D03*
X1447657D03*
X1442106Y892379D03*
X1443956Y895568D03*
X1451357Y882812D03*
X1451358Y889190D03*
X1453208Y892379D03*
X1442106Y898757D03*
X1440255Y901946D03*
X1447657D03*
X1443956D03*
X1442106Y905134D03*
X1443956Y908324D03*
X1442106Y911512D03*
X1451358Y901946D03*
X1453208Y898757D03*
Y905134D03*
Y911512D03*
X1440255Y914701D03*
X1443956D03*
X1447657D03*
X1442106Y917890D03*
X1443956Y921079D03*
X1442106Y924268D03*
X1451357Y914701D03*
X1453208Y917890D03*
Y924268D03*
X1440255Y927457D03*
X1443956D03*
X1447657D03*
X1440255Y933835D03*
X1443956D03*
X1442106Y937024D03*
X1443956Y940213D03*
X1453208Y930646D03*
X1451357Y927457D03*
X1447657Y946591D03*
X1442106Y943402D03*
X1440255Y946591D03*
X1442106Y949780D03*
X1443956Y946591D03*
Y952969D03*
X1442106Y956158D03*
X1451357Y946591D03*
X1453208Y943402D03*
Y949780D03*
Y956158D03*
X1440255Y959347D03*
X1443956D03*
X1447657D03*
X1443956Y965725D03*
X1442106Y962536D03*
Y968914D03*
X1451357Y959347D03*
X1453208Y962536D03*
Y968914D03*
X1445806Y981670D03*
X1443956Y978481D03*
Y972103D03*
X1447657D03*
X1442106Y975292D03*
X1440255Y972103D03*
X1443956Y984859D03*
X1453208Y981670D03*
X1451357Y972103D03*
X1453208Y975292D03*
X1451357Y984859D03*
X1445806Y988048D03*
X1443956Y991237D03*
X1453208Y988048D03*
Y994426D03*
X1451357Y991237D03*
X1453208Y1000804D03*
Y1007182D03*
X1456909Y873245D03*
Y879623D03*
X1458759Y876434D03*
X1468011Y879623D03*
X1455058Y882812D03*
X1462460D03*
X1466161D03*
X1458759D03*
Y889190D03*
X1455058Y895568D03*
X1464310Y892379D03*
X1466161Y895568D03*
X1462460Y889190D03*
X1464310Y898757D03*
X1455058Y901946D03*
X1458759D03*
X1466161D03*
X1462460D03*
X1464310Y905134D03*
X1455058Y908324D03*
X1464310Y911512D03*
X1466161Y908323D03*
X1458759Y914701D03*
X1464310Y917890D03*
Y924268D03*
X1455058Y921079D03*
X1466161D03*
X1455058Y914701D03*
X1462460D03*
X1466161D03*
X1455058Y927457D03*
X1458759D03*
X1466161D03*
X1462460D03*
X1455058Y933835D03*
X1464310Y930646D03*
X1462460Y933835D03*
X1466161D03*
X1458759D03*
X1455058Y940213D03*
X1466161D03*
X1462460Y946591D03*
X1466161D03*
X1458759D03*
X1466161Y952969D03*
X1464310Y956158D03*
X1455058Y952969D03*
X1464310Y943402D03*
X1455058Y946591D03*
X1464310Y949780D03*
X1455058Y965725D03*
X1466161D03*
X1455058Y959347D03*
X1462460D03*
X1466161D03*
X1458759D03*
X1464310Y962536D03*
Y968914D03*
X1460609Y981670D03*
X1455058Y978481D03*
X1466161D03*
X1455058Y972103D03*
X1462460D03*
X1466161D03*
X1458759D03*
X1464310Y975292D03*
X1458759Y984859D03*
X1466161D03*
X1468011Y981670D03*
X1458759Y997615D03*
X1466161D03*
X1460609Y988048D03*
Y994426D03*
X1458759Y991237D03*
X1466161D03*
X1460609Y1000804D03*
X1468011Y988048D03*
Y994426D03*
Y1000804D03*
X1458759Y1003993D03*
X1466161D03*
Y1010371D03*
X1458759D03*
X1460609Y1007182D03*
X1468011D03*
X1479113Y873245D03*
X1469861Y876434D03*
X1479113Y879623D03*
X1482814Y886001D03*
X1480964Y882812D03*
X1469861D03*
X1479113Y886001D03*
X1482814Y892379D03*
X1469861Y889190D03*
X1473562D03*
X1475413Y892379D03*
X1477263Y895568D03*
X1482814Y898757D03*
X1469861Y901946D03*
X1475413Y898757D03*
X1473562Y901946D03*
X1482814Y905134D03*
Y911512D03*
X1477263Y908324D03*
X1475413Y911512D03*
Y905134D03*
X1482814Y917890D03*
X1469861Y914701D03*
X1473562D03*
X1475413Y917890D03*
Y924268D03*
X1482814D03*
X1477263Y921079D03*
X1469861Y933835D03*
X1473562D03*
X1482814Y930646D03*
X1475413D03*
X1477263Y933835D03*
X1473562Y927457D03*
X1469861D03*
X1482814Y937024D03*
X1477263Y940213D03*
X1482814Y943402D03*
Y949780D03*
X1475413Y943402D03*
X1469861Y946591D03*
X1473562D03*
X1475413Y949780D03*
X1482814Y956158D03*
X1477263Y952969D03*
X1475413Y956158D03*
X1482814Y962536D03*
X1469861Y959347D03*
X1473562D03*
X1475413Y962536D03*
X1477263Y965725D03*
X1482814Y968914D03*
X1475413D03*
X1482814Y975292D03*
Y981670D03*
X1469861Y972103D03*
X1473562D03*
X1475413Y975292D03*
X1477263Y978481D03*
X1475413Y981670D03*
X1473562Y984859D03*
X1475413Y1000804D03*
X1482814Y988048D03*
Y994426D03*
X1473562Y991237D03*
Y997615D03*
X1475413Y988048D03*
Y994426D03*
X1482814Y1000804D03*
Y1007182D03*
X1473562Y1003993D03*
Y1010371D03*
X1475413Y1007182D03*
X1492066Y876434D03*
X1490216Y886001D03*
X1484665Y882812D03*
X1488365D03*
X1495767D03*
X1493917Y886001D03*
X1488365Y889190D03*
X1495767D03*
X1490216Y892379D03*
X1495767Y895568D03*
X1490216Y898757D03*
X1488365Y901946D03*
X1495767D03*
X1488365Y908324D03*
X1490216Y911512D03*
X1495767Y908324D03*
Y914701D03*
X1490216Y917890D03*
X1488365Y921079D03*
X1495767D03*
X1490216Y930646D03*
X1495767Y933835D03*
X1488365Y927457D03*
X1495767D03*
X1488365Y940213D03*
X1495767D03*
X1490216Y937024D03*
X1488365Y946591D03*
X1490216Y949780D03*
X1495767Y946591D03*
Y952969D03*
X1490216Y956158D03*
X1488365Y965725D03*
X1495767Y959347D03*
Y965725D03*
X1488365Y959347D03*
X1490216Y968914D03*
X1495767Y972103D03*
X1490216Y975292D03*
X1486515Y981670D03*
X1488365Y978481D03*
X1495767D03*
X1497617Y981670D03*
X1484665Y984859D03*
X1488365D03*
X1495767D03*
X1490216Y988048D03*
X1488365Y997615D03*
X1490216Y994426D03*
X1495767Y991237D03*
Y997615D03*
X1488365Y1003993D03*
X1490216Y1007182D03*
X1495767Y1003993D03*
Y1010371D03*
X1501318Y873245D03*
Y879623D03*
X1510570Y876434D03*
X1508720Y879623D03*
X1501318Y886001D03*
X1510570Y882812D03*
X1508720Y886001D03*
X1503169Y889190D03*
Y895568D03*
X1501318Y892379D03*
X1508720D03*
X1499468Y882812D03*
X1505019Y886001D03*
X1501318Y898757D03*
X1508720D03*
X1503169Y901946D03*
X1501318Y905134D03*
X1508720D03*
X1501318Y911512D03*
X1508720D03*
X1503169Y908323D03*
Y914701D03*
X1501318Y917890D03*
X1508720D03*
X1503169Y921079D03*
X1501318Y924268D03*
X1508720D03*
X1503169Y927457D03*
X1501318Y930646D03*
X1503169Y933835D03*
X1508720Y930646D03*
Y937024D03*
X1503169Y940213D03*
X1501318Y937024D03*
Y943402D03*
X1508720D03*
X1503169Y946591D03*
X1501318Y949780D03*
X1508720D03*
X1503169Y952969D03*
X1501318Y956158D03*
X1508720D03*
X1503169Y959347D03*
Y965725D03*
X1501318Y962536D03*
X1508720D03*
X1501318Y968914D03*
X1508720D03*
X1510570Y984859D03*
X1512421Y981670D03*
X1503169Y972103D03*
X1501318Y975292D03*
X1503169Y978481D03*
X1501318Y981670D03*
X1508720Y975292D03*
Y981670D03*
X1499468Y984859D03*
X1503169D03*
Y991237D03*
X1501318Y988048D03*
X1503169Y997615D03*
X1501318Y994426D03*
X1508720Y988048D03*
Y994426D03*
X1501318Y1000804D03*
X1508720D03*
X1501318Y1007182D03*
X1503169Y1010371D03*
X1508720Y1007182D03*
X1503169Y1003993D03*
X1521673Y876434D03*
X1517972D03*
X1519822Y879623D03*
X1527224D03*
X1516121D03*
X1523523Y873245D03*
X1514271Y882812D03*
Y889190D03*
X1521673Y882812D03*
X1519822Y886001D03*
X1525373Y882812D03*
X1527224Y886001D03*
X1521673Y889190D03*
Y895568D03*
X1527224Y892379D03*
X1516121D03*
X1514271Y901946D03*
Y908324D03*
X1521673Y901946D03*
X1527224Y898757D03*
X1516121D03*
X1527224Y911512D03*
Y905134D03*
X1516121Y911512D03*
X1521673Y908323D03*
X1514271Y921079D03*
X1521673Y914701D03*
X1527224Y917890D03*
X1516121D03*
X1521673Y921079D03*
X1527224Y924268D03*
X1514271Y927457D03*
Y940213D03*
X1516121Y930646D03*
X1521673Y927457D03*
Y933835D03*
X1527224Y930646D03*
X1516121Y937024D03*
X1527224D03*
X1521673Y940213D03*
X1514271Y946591D03*
X1516121Y949780D03*
X1521673Y946591D03*
X1527224Y943402D03*
Y949780D03*
X1521673Y952969D03*
X1527224Y956158D03*
X1516121D03*
X1514271Y959347D03*
Y965725D03*
X1521673Y959347D03*
Y965725D03*
X1527224Y962536D03*
Y968914D03*
X1516121D03*
X1514271Y978481D03*
Y984859D03*
X1521673Y972103D03*
X1523523Y981670D03*
X1521673Y978481D03*
X1527224Y975292D03*
Y981670D03*
X1516121Y975292D03*
X1521673Y984859D03*
X1525373D03*
X1514271Y997615D03*
X1521673Y991237D03*
Y997615D03*
X1527224Y988048D03*
Y994426D03*
X1516121Y988048D03*
Y994426D03*
X1527224Y1000804D03*
X1514271Y1003993D03*
X1516121Y1007182D03*
X1521673Y1003993D03*
Y1010371D03*
X1527224Y1007182D03*
X1529074Y876434D03*
X1538326Y879623D03*
X1530925Y886001D03*
X1529074Y889190D03*
Y895568D03*
X1540176Y882812D03*
X1536476D03*
X1534625Y886001D03*
X1540176Y889190D03*
X1542027Y892379D03*
X1534625D03*
X1529074Y901946D03*
Y908324D03*
X1542027Y898757D03*
X1540176Y901946D03*
X1534625Y898757D03*
X1540176Y908324D03*
X1542027Y911512D03*
X1534625Y905134D03*
Y911512D03*
X1529074Y914701D03*
Y921079D03*
X1542027Y917890D03*
X1534625D03*
X1540176Y921079D03*
X1534625Y924268D03*
X1529074Y927457D03*
Y933835D03*
Y940213D03*
X1540176Y927457D03*
X1542027Y930646D03*
X1534625D03*
X1542027Y937024D03*
X1540176Y940213D03*
X1534625Y937024D03*
X1529074Y946591D03*
Y952969D03*
X1540176Y946591D03*
X1542027Y949780D03*
X1534625Y943402D03*
Y949780D03*
Y956158D03*
X1542027D03*
X1529074Y959347D03*
Y965725D03*
X1540176Y959347D03*
Y965725D03*
X1534625Y962536D03*
X1542027Y968914D03*
X1534625D03*
X1538326Y981670D03*
X1542027Y975292D03*
X1540176Y978481D03*
X1534625Y975292D03*
Y981670D03*
X1536476Y984859D03*
X1540176D03*
X1529074Y972103D03*
Y978481D03*
Y984859D03*
Y991237D03*
Y997615D03*
X1542027Y988048D03*
X1540176Y997615D03*
X1542027Y994426D03*
X1534625Y988048D03*
Y994426D03*
Y1000804D03*
X1542027Y1007182D03*
X1534625D03*
X1529074Y1003993D03*
Y1010371D03*
X1540176Y1003993D03*
X1545728Y873245D03*
X1553129Y879623D03*
X1545728Y886001D03*
X1547578Y882812D03*
X1553129Y886001D03*
X1551279Y882812D03*
X1547578Y889190D03*
Y895568D03*
X1553129Y892379D03*
X1547578Y901946D03*
X1553129Y898757D03*
X1547578Y908324D03*
Y914701D03*
Y921079D03*
Y927457D03*
Y933835D03*
Y940213D03*
Y946591D03*
Y952969D03*
Y959347D03*
Y965725D03*
X1543877Y984859D03*
X1547578Y972103D03*
Y978481D03*
Y984859D03*
X1545728Y988048D03*
X1547578Y991237D03*
Y997615D03*
Y1003993D03*
Y1010371D03*
G54D59*
X928740Y321654D03*
G54D35*
X250326Y185236D03*
X368437D03*
G54D60*
X916546Y309460D03*
X911495Y321654D03*
X916546Y333848D03*
X928740Y304409D03*
Y338899D03*
X940934Y309460D03*
X945985Y321654D03*
X940934Y333848D03*
G54D71*
X1766929Y1714960D03*
G54D11*
X19685Y-29134D03*
Y1803261D03*
X2081889Y-29134D03*
Y1803261D03*
G54D27*
X117933Y605376D03*
X763602Y605413D03*
X1094076Y605378D03*
X1739745Y605411D03*
G54D18*
X44000Y154200D03*
X31818Y1424257D03*
X441043Y1672205D03*
Y1718465D03*
X1416437Y1672205D03*
Y1718465D03*
X1800449Y126194D03*
X1804650Y1667292D03*
G54D52*
X791280Y1704890D03*
X1066280D03*
G54D33*
X230905Y1644448D03*
Y1658621D03*
Y1672795D03*
Y1686968D03*
Y1701141D03*
Y1715314D03*
Y1729488D03*
X246653Y1644448D03*
X238779Y1648385D03*
X246653Y1658621D03*
X238779Y1662558D03*
X246653Y1672795D03*
X238779Y1676732D03*
X246653Y1686968D03*
X238779Y1690905D03*
X246653Y1701141D03*
X238779Y1705078D03*
X246653Y1715314D03*
X238779Y1719251D03*
X246653Y1729488D03*
X238779Y1733425D03*
X254527Y1648385D03*
Y1662558D03*
Y1676732D03*
Y1690905D03*
Y1705078D03*
Y1719251D03*
Y1733425D03*
X262401Y1644448D03*
X270275Y1648385D03*
X262401Y1658621D03*
X270275Y1662558D03*
X262401Y1672795D03*
X270275Y1676732D03*
X262401Y1686968D03*
X270275Y1690905D03*
X262401Y1701141D03*
X270275Y1705078D03*
X262401Y1715314D03*
X270275Y1719251D03*
X262401Y1729488D03*
X270275Y1733425D03*
X278149Y1644448D03*
X286023Y1648385D03*
X278149Y1658621D03*
X286023Y1662558D03*
X278149Y1672795D03*
X286023Y1676732D03*
X278149Y1686968D03*
X286023Y1690905D03*
X278149Y1701141D03*
X286023Y1705078D03*
X278149Y1715314D03*
X286023Y1719251D03*
X278149Y1729488D03*
X286023Y1733425D03*
X297835Y1672795D03*
X305709Y1676732D03*
X297835Y1686968D03*
X305709Y1690905D03*
X297835Y1701141D03*
X305709Y1705078D03*
X297835Y1715314D03*
X305709Y1719251D03*
X297835Y1729488D03*
X305709Y1733425D03*
X313583Y1672795D03*
X321457Y1676732D03*
X313583Y1686968D03*
X321457Y1690905D03*
X313583Y1701141D03*
X321457Y1705078D03*
X313583Y1715314D03*
X321457Y1719251D03*
X313583Y1729488D03*
X321457Y1733425D03*
X329331Y1672795D03*
Y1686968D03*
Y1701141D03*
Y1715314D03*
Y1729488D03*
X345079Y1672795D03*
X337205Y1676732D03*
X345079Y1686968D03*
X337205Y1690905D03*
X345079Y1701141D03*
X337205Y1705078D03*
X345079Y1715314D03*
X337205Y1719251D03*
X345079Y1729488D03*
X337205Y1733425D03*
X352953Y1676732D03*
Y1690905D03*
Y1705078D03*
Y1719251D03*
Y1733425D03*
X495078Y1672795D03*
Y1686968D03*
Y1701141D03*
Y1715314D03*
Y1729488D03*
X510826Y1672795D03*
X502952Y1676732D03*
X510826Y1686968D03*
X502952Y1690905D03*
X510826Y1701141D03*
X502952Y1705078D03*
X510826Y1715314D03*
X502952Y1719251D03*
X510826Y1729488D03*
X502952Y1733425D03*
X526574Y1672795D03*
X518700Y1676732D03*
X526574Y1686968D03*
X518700Y1690905D03*
X526574Y1701141D03*
X518700Y1705078D03*
X526574Y1715314D03*
X518700Y1719251D03*
X526574Y1729488D03*
X518700Y1733425D03*
X542322Y1672795D03*
X534448Y1676732D03*
X542322Y1686968D03*
X534448Y1690905D03*
X542322Y1701141D03*
X534448Y1705078D03*
X542322Y1715314D03*
X534448Y1719251D03*
X542322Y1729488D03*
X534448Y1733425D03*
X550196Y1676732D03*
Y1690905D03*
Y1705078D03*
Y1719251D03*
Y1733425D03*
X562008Y1672795D03*
X569882Y1676732D03*
X562008Y1686968D03*
X569882Y1690905D03*
X562008Y1701141D03*
X569882Y1705078D03*
X562008Y1715314D03*
X569882Y1719251D03*
X562008Y1729488D03*
X569882Y1733425D03*
X577756Y1672795D03*
X585630Y1676732D03*
X577756Y1686968D03*
X585630Y1690905D03*
X577756Y1701141D03*
X585630Y1705078D03*
X577756Y1715314D03*
X585630Y1719251D03*
X577756Y1729488D03*
X585630Y1733425D03*
X593504Y1672795D03*
X601378Y1676732D03*
X593504Y1686968D03*
X601378Y1690905D03*
X593504Y1701141D03*
X601378Y1705078D03*
X593504Y1715314D03*
X601378Y1719251D03*
X593504Y1729488D03*
X601378Y1733425D03*
X609252Y1672795D03*
X617126Y1676732D03*
X609252Y1686968D03*
X617126Y1690905D03*
X609252Y1701141D03*
X617126Y1705078D03*
X609252Y1715314D03*
X617126Y1719251D03*
X609252Y1729488D03*
X617126Y1733425D03*
X1238778Y1672795D03*
Y1686968D03*
Y1701141D03*
Y1715314D03*
Y1729488D03*
X1254526Y1672795D03*
X1246652Y1676732D03*
X1254526Y1686968D03*
X1246652Y1690905D03*
X1254526Y1701141D03*
X1246652Y1705078D03*
X1254526Y1715314D03*
X1246652Y1719251D03*
X1254526Y1729488D03*
X1246652Y1733425D03*
X1270274Y1672795D03*
X1262400Y1676732D03*
X1270274Y1686968D03*
X1262400Y1690905D03*
X1270274Y1701141D03*
X1262400Y1705078D03*
X1270274Y1715314D03*
X1262400Y1719251D03*
X1270274Y1729488D03*
X1262400Y1733425D03*
X1286022Y1672795D03*
X1278148Y1676732D03*
X1286022Y1686968D03*
X1278148Y1690905D03*
X1286022Y1701141D03*
X1278148Y1705078D03*
X1286022Y1715314D03*
X1278148Y1719251D03*
X1286022Y1729488D03*
X1278148Y1733425D03*
X1305708Y1672795D03*
Y1686968D03*
X1293896Y1676732D03*
X1305708Y1701141D03*
X1293896Y1690905D03*
X1305708Y1715314D03*
X1293896Y1705078D03*
X1305708Y1729488D03*
X1293896Y1719251D03*
Y1733425D03*
X1313582Y1676732D03*
Y1690905D03*
Y1705078D03*
Y1719251D03*
Y1733425D03*
X1321456Y1672795D03*
X1329330Y1676732D03*
X1321456Y1686968D03*
X1329330Y1690905D03*
X1321456Y1701141D03*
X1329330Y1705078D03*
X1321456Y1715314D03*
X1329330Y1719251D03*
X1321456Y1729488D03*
X1329330Y1733425D03*
X1337204Y1672795D03*
X1345078Y1676732D03*
X1337204Y1686968D03*
X1345078Y1690905D03*
X1337204Y1701141D03*
X1345078Y1705078D03*
X1337204Y1715314D03*
X1345078Y1719251D03*
X1337204Y1729488D03*
X1345078Y1733425D03*
X1352952Y1672795D03*
X1360826Y1676732D03*
X1352952Y1686968D03*
X1360826Y1690905D03*
X1352952Y1701141D03*
X1360826Y1705078D03*
X1352952Y1715314D03*
X1360826Y1719251D03*
X1352952Y1729488D03*
X1360826Y1733425D03*
X1502952Y1672795D03*
X1510826Y1676732D03*
X1502952Y1686968D03*
X1510826Y1690905D03*
X1502952Y1701141D03*
X1510826Y1705078D03*
X1502952Y1715314D03*
X1510826Y1719251D03*
X1502952Y1729488D03*
X1510826Y1733425D03*
X1518700Y1672795D03*
X1526574Y1676732D03*
X1518700Y1686968D03*
X1526574Y1690905D03*
X1518700Y1701141D03*
X1526574Y1705078D03*
X1518700Y1715314D03*
X1526574Y1719251D03*
X1518700Y1729488D03*
X1526574Y1733425D03*
X1534448Y1672795D03*
X1542322Y1676732D03*
X1534448Y1686968D03*
X1542322Y1690905D03*
X1534448Y1701141D03*
X1542322Y1705078D03*
X1534448Y1715314D03*
X1542322Y1719251D03*
X1534448Y1729488D03*
X1542322Y1733425D03*
X1550196Y1672795D03*
X1558070Y1676732D03*
X1550196Y1686968D03*
X1558070Y1690905D03*
X1550196Y1701141D03*
X1558070Y1705078D03*
X1550196Y1715314D03*
X1558070Y1719251D03*
X1550196Y1729488D03*
X1558070Y1733425D03*
X1569882Y1672795D03*
Y1686968D03*
Y1701141D03*
Y1715314D03*
Y1729488D03*
X1585630Y1672795D03*
X1577756Y1676732D03*
X1585630Y1686968D03*
X1577756Y1690905D03*
X1585630Y1701141D03*
X1577756Y1705078D03*
X1585630Y1715314D03*
X1577756Y1719251D03*
X1585630Y1729488D03*
X1577756Y1733425D03*
X1601378Y1672795D03*
X1593504Y1676732D03*
X1601378Y1686968D03*
X1593504Y1690905D03*
X1601378Y1701141D03*
X1593504Y1705078D03*
X1601378Y1715314D03*
X1593504Y1719251D03*
X1601378Y1729488D03*
X1593504Y1733425D03*
X1617126Y1672795D03*
X1609252Y1676732D03*
X1617126Y1686968D03*
X1609252Y1690905D03*
X1617126Y1701141D03*
X1609252Y1705078D03*
X1617126Y1715314D03*
X1609252Y1719251D03*
X1617126Y1729488D03*
X1609252Y1733425D03*
X1625000Y1676732D03*
Y1690905D03*
Y1705078D03*
Y1719251D03*
Y1733425D03*
G54D45*
X441043Y1698268D03*
X1416437D03*
G54D54*
X805690Y204724D03*
X1057659D03*
G54D15*
X17292Y290137D03*
X35689Y301357D03*
X33822Y1462075D03*
Y1459075D03*
Y1456075D03*
X36822D03*
Y1459075D03*
Y1462075D03*
X33822Y1465075D03*
X36822D03*
X37671Y1515214D03*
X34704Y1515235D03*
X47892Y290137D03*
X49400Y384392D03*
X49250Y396332D03*
X47618Y412613D03*
X47619Y421655D03*
X42822Y1462075D03*
Y1459075D03*
Y1456075D03*
Y1465075D03*
X47138Y1513072D03*
X47089Y1510268D03*
X50642Y1557451D03*
X45633Y1592481D03*
X50133D03*
X38426Y1654079D03*
X41427Y1668587D03*
X38426Y1659059D03*
X44583Y1672433D03*
Y1677613D03*
X66289Y301357D03*
X61340Y384362D03*
X61250Y396142D03*
X56542Y589521D03*
X66822Y1462075D03*
Y1459075D03*
Y1456075D03*
X57822Y1462075D03*
Y1459075D03*
Y1456075D03*
X66822Y1465075D03*
X57822D03*
X63990Y1562177D03*
Y1567627D03*
Y1564727D03*
X63915Y1558805D03*
Y1556254D03*
X63990Y1570427D03*
X61225Y1570283D03*
X58564Y1570209D03*
X65767Y1609405D03*
X59767D03*
X53767D03*
X65767Y1615405D03*
X65943Y1621405D03*
X59767D03*
X53767Y1615405D03*
Y1621405D03*
X59427Y1644410D03*
X53648Y1653088D03*
X77790Y520108D03*
X77733Y526764D03*
X77790Y537808D03*
X77733Y544464D03*
X81822Y1462075D03*
Y1456075D03*
Y1465075D03*
X68427Y1644410D03*
X73427D03*
X80000Y1702450D03*
X79500Y1720450D03*
X88722Y1462075D03*
X85722D03*
X88722Y1456075D03*
X85722D03*
X88722Y1465075D03*
X85722D03*
X85621Y1551969D03*
X82974Y1552051D03*
X83340Y1654353D03*
X89466Y1663138D03*
Y1667127D03*
X83340Y1659333D03*
X85395Y1670331D03*
Y1675311D03*
X102096Y1555442D03*
X100439Y1667361D03*
X106573Y1660235D03*
X100915Y1679564D03*
X105069Y1685763D03*
X102243Y1682263D03*
Y1689263D03*
X120016Y300654D03*
Y320631D03*
X114973Y1660235D03*
X113469Y1685763D03*
X133120Y1454751D03*
X137120D03*
X141028Y1454705D03*
X140775Y1638035D03*
X146982Y526997D03*
X145028Y1454705D03*
X152449Y1623572D03*
Y1628528D03*
X151611Y1663933D03*
X159427Y1687843D03*
X151510Y1676811D03*
X163113Y1477590D03*
Y1499490D03*
X164730Y1521561D03*
X161239Y1636147D03*
Y1631191D03*
X162995Y1661377D03*
X160011Y1663933D03*
X163003Y1666462D03*
X159910Y1676811D03*
X162848Y1679357D03*
X162840Y1674272D03*
X187250Y129674D03*
X189410Y388180D03*
X200754Y595174D03*
Y603274D03*
X192951Y1560498D03*
X196081Y1639349D03*
X195504Y1645359D03*
X203754Y595174D03*
Y603274D03*
X207968Y1653130D03*
X203800Y1646832D03*
X272242Y523076D03*
X276085Y1509654D03*
X270720Y1531073D03*
X273220D03*
X275720D03*
X281147Y521803D03*
X280621Y1478082D03*
X291175Y1477590D03*
X283221Y1484772D03*
Y1479992D03*
X278021Y1484772D03*
Y1479992D03*
X283221Y1493392D03*
X280621Y1491482D03*
X278021Y1493392D03*
X291175Y1499490D03*
X283221Y1498172D03*
X278021D03*
X291619Y1536606D03*
X291593Y1529402D03*
Y1531902D03*
X284800Y1526750D03*
X277572Y1536763D03*
X280072D03*
X291619Y1539106D03*
X292792Y1521561D03*
X297323Y1651172D03*
X318660Y24989D03*
X307255Y1641150D03*
X339914Y165170D03*
X384668Y471926D03*
X410701Y99148D03*
X396977Y216685D03*
X399625Y479119D03*
X408683Y1478082D03*
Y1491482D03*
X406083Y1479992D03*
Y1484772D03*
Y1493392D03*
Y1498172D03*
X404147Y1509654D03*
X398782Y1531073D03*
X401282D03*
X403782D03*
X411800Y220200D03*
X413425Y479042D03*
X411283Y1479992D03*
Y1484772D03*
Y1493392D03*
Y1498172D03*
X412862Y1526750D03*
X436090Y120007D03*
X429997Y166400D03*
X441997D03*
X439299Y220046D03*
X427225Y478965D03*
X440159Y966741D03*
Y981741D03*
Y974241D03*
X427286Y1477590D03*
Y1499490D03*
X428746Y1521727D03*
X427730Y1536606D03*
X427704Y1531902D03*
Y1529402D03*
X427730Y1539106D03*
X428500Y1650000D03*
X465997Y166400D03*
X457997D03*
X466041Y1664913D03*
X483467Y209755D03*
X514418Y145171D03*
Y149171D03*
Y153171D03*
X513360Y169190D03*
X511771Y199576D03*
X506261Y865338D03*
X522418Y153171D03*
X516572Y865327D03*
X530418Y145171D03*
Y149171D03*
Y153171D03*
X531280Y210922D03*
X544794Y1478082D03*
Y1491482D03*
X542194Y1479992D03*
Y1484772D03*
Y1493392D03*
X537694Y1504872D03*
X542194Y1498172D03*
X543759Y1536882D03*
X540193Y1531073D03*
X537693D03*
X535193D03*
X541259Y1536882D03*
X555348Y1477590D03*
X547394Y1479992D03*
Y1484772D03*
Y1493392D03*
X555348Y1499490D03*
X547394Y1498172D03*
X556965Y1521561D03*
X556642Y1529389D03*
X554715Y1531564D03*
X550540Y1526910D03*
X556197Y1536687D03*
Y1539187D03*
X561248Y106985D03*
Y100399D03*
X562208Y387227D03*
Y376427D03*
Y401158D03*
X568433Y415846D03*
X581985Y379577D03*
Y390377D03*
Y404308D03*
X588723Y423949D03*
X593975Y164440D03*
X598208Y387227D03*
Y376427D03*
X599164Y432209D03*
X604718Y257562D03*
X617985Y379577D03*
Y398578D03*
Y390377D03*
X610935Y409996D03*
X615075Y443000D03*
X633882Y587488D03*
X646285Y297171D03*
X640317Y391085D03*
X634566Y407848D03*
X639482Y587488D03*
X645446Y587300D03*
X653821Y90326D03*
X653013Y443200D03*
X664170Y445711D03*
X651046Y587300D03*
X672856Y1478082D03*
Y1491482D03*
X675112Y1479602D03*
X675456Y1484772D03*
Y1493392D03*
X670256Y1479992D03*
Y1484772D03*
Y1493392D03*
X665756Y1504872D03*
X675456Y1498172D03*
X670256D03*
X680710Y1520284D03*
X683674Y1522287D03*
X695796Y418358D03*
X708395Y430957D03*
X702095Y421508D03*
X698946Y437256D03*
X702095Y449854D03*
X708395Y474971D03*
X698946Y468672D03*
X695796Y487570D03*
X706172Y1552082D03*
X698003Y1684692D03*
X711544Y421508D03*
X720993Y443555D03*
Y446705D03*
X717843D03*
Y440405D03*
X720993Y449854D03*
Y462373D03*
Y459223D03*
Y456074D03*
X717843Y459223D03*
Y465523D03*
X711544Y484420D03*
X722141Y1405912D03*
X721916Y1414339D03*
Y1416939D03*
X722141Y1408412D03*
X721916Y1428989D03*
Y1431589D03*
X733512Y427807D03*
X727292Y421508D03*
X736661Y443555D03*
X733512Y446705D03*
Y443555D03*
X727292Y446705D03*
Y443555D03*
X724143D03*
Y462373D03*
X727292D03*
X733512Y459223D03*
X727292D03*
X733512Y462373D03*
X736661D03*
X727292Y474971D03*
X736661Y484420D03*
X724143D03*
X752409Y421508D03*
X739811Y443555D03*
Y446705D03*
X742961Y440405D03*
X739811Y449854D03*
Y456074D03*
Y459223D03*
Y462373D03*
X742961Y465523D03*
X752409Y484420D03*
X746082Y1506931D03*
X751030Y1668583D03*
X765008Y418358D03*
X758709Y437256D03*
X755559Y456074D03*
X758709Y468672D03*
X765008Y487570D03*
X758179Y1482049D03*
X758163Y1526223D03*
X758179Y1534963D03*
X779014Y1343262D03*
Y1340062D03*
X782014D03*
Y1337062D03*
Y1343262D03*
X780000Y1353500D03*
X779014Y1346462D03*
Y1349862D03*
X782014Y1346462D03*
Y1349862D03*
X780000Y1357500D03*
Y1363500D03*
Y1360500D03*
X780111Y1405366D03*
X782758Y1405249D03*
X795421Y1331257D03*
X785014Y1350862D03*
X804099Y1333835D03*
X801171Y1343278D03*
X810986Y1361684D03*
X819115Y115223D03*
X824499Y145198D03*
X820405Y311830D03*
X831115Y115223D03*
X829115Y150273D03*
X838670Y1518558D03*
X841310Y1518608D03*
X838630Y1521538D03*
X841270Y1521588D03*
X854578Y99651D03*
X856397Y339751D03*
X847007Y1521458D03*
X844367Y1521408D03*
Y1518784D03*
X847007Y1518834D03*
X855853Y1521308D03*
X853213Y1521258D03*
X850146Y1521261D03*
Y1518637D03*
X853213Y1518634D03*
X855853Y1518684D03*
X860152Y328399D03*
X865132D03*
X861377Y339751D03*
X872986Y753451D03*
X858581Y1518568D03*
X858567Y1521416D03*
X876133Y73580D03*
Y95580D03*
Y117580D03*
X919272Y989932D03*
X921289Y1663187D03*
X942779Y277731D03*
X936693Y1462328D03*
X939507Y1462497D03*
X945195Y1459453D03*
X942056Y1459650D03*
X939416Y1459600D03*
Y1456976D03*
X942056Y1457026D03*
X945195Y1456829D03*
X951099Y632206D03*
X956693Y1459805D03*
X953630Y1456760D03*
X958383Y1462447D03*
X950902Y1459500D03*
X948262Y1459450D03*
X953616Y1459608D03*
X948262Y1456826D03*
X950902Y1456876D03*
X955350Y1532760D03*
X961350D03*
X958350D03*
X953520Y1567570D03*
X950520D03*
X959520D03*
X956520D03*
X953520Y1582570D03*
X950520D03*
Y1579570D03*
X953520D03*
Y1576570D03*
X950520D03*
X953520Y1573570D03*
X950520D03*
Y1570570D03*
X953520D03*
X959520Y1582570D03*
X956520D03*
Y1579570D03*
X959520D03*
Y1576570D03*
X956520D03*
X959520Y1573570D03*
X956520D03*
Y1570570D03*
X959520D03*
X953520Y1588570D03*
X950520D03*
Y1585570D03*
X953520D03*
X959520Y1588570D03*
X956520D03*
Y1585570D03*
X959520D03*
X977150Y1052684D03*
X966000Y1300000D03*
X968500D03*
X971000D03*
X967350Y1532760D03*
X964350D03*
X991280D03*
X988280D03*
X988160Y1567710D03*
X991160D03*
X985160D03*
X988160Y1582710D03*
X991160D03*
X985160D03*
Y1579710D03*
X991160D03*
X988160D03*
X991160Y1570710D03*
X988160D03*
Y1573710D03*
X991160D03*
X988160Y1576710D03*
X991160D03*
X985160Y1570710D03*
Y1573710D03*
Y1576710D03*
X988160Y1588710D03*
X991160D03*
X985160D03*
Y1585710D03*
X991160D03*
X988160D03*
X994280Y1532760D03*
X997280D03*
X1000280D03*
X1014206Y510304D03*
X1013306Y526146D03*
X1019440Y1532930D03*
X1016750Y1567710D03*
X1019750D03*
X1016750Y1576710D03*
Y1573710D03*
Y1570710D03*
X1019750Y1576710D03*
Y1573710D03*
Y1570710D03*
Y1579710D03*
X1016750D03*
Y1582710D03*
X1019750D03*
Y1585710D03*
X1016750D03*
Y1588710D03*
X1019750D03*
X1025440Y1532930D03*
X1022440D03*
X1031440D03*
X1028440D03*
X1022750Y1567710D03*
Y1576710D03*
Y1573710D03*
Y1570710D03*
Y1579710D03*
Y1582710D03*
Y1585710D03*
Y1588710D03*
X1045254Y521074D03*
X1037212Y510940D03*
X1051110Y1532850D03*
X1048219Y1567883D03*
X1051219D03*
X1048219Y1576883D03*
Y1573883D03*
Y1570883D03*
X1051219Y1576883D03*
Y1573883D03*
Y1570883D03*
Y1579883D03*
X1048219D03*
Y1582883D03*
X1051219D03*
Y1585883D03*
X1048219D03*
Y1588883D03*
X1051219D03*
X1055934Y385488D03*
X1057110Y1532850D03*
X1054110D03*
X1063110D03*
X1060110D03*
X1054219Y1567883D03*
Y1576883D03*
Y1573883D03*
Y1570883D03*
Y1579883D03*
Y1582883D03*
Y1585883D03*
Y1588883D03*
X1068143Y383688D03*
X1073204Y383417D03*
X1083819Y353094D03*
X1090300Y1532660D03*
X1087300D03*
X1096300D03*
X1093300D03*
X1119067Y1551457D03*
X1133765Y1572102D03*
X1170986Y1510590D03*
Y1532490D03*
X1183354Y77685D03*
X1176972Y86788D03*
X1200824Y1593498D03*
X1192612Y1680410D03*
X1207954Y1680419D03*
X1209879Y1700359D03*
X1230094Y314216D03*
X1226094Y305216D03*
X1216875Y1705826D03*
X1216738Y1720861D03*
X1277732Y236594D03*
Y246594D03*
Y241594D03*
Y251594D03*
X1288494Y1511082D03*
X1285894Y1512992D03*
Y1517772D03*
X1288494Y1524482D03*
X1285894Y1531172D03*
Y1526392D03*
X1283958Y1542654D03*
X1278593Y1564073D03*
X1281093D03*
X1283593D03*
X1287945Y1569763D03*
X1285445D03*
X1302365Y1418702D03*
X1292522Y1421596D03*
X1303943Y1430729D03*
X1299048Y1510590D03*
X1291094Y1512992D03*
Y1517772D03*
X1299048Y1532490D03*
X1291094Y1531172D03*
Y1526392D03*
X1299466Y1562402D03*
Y1564902D03*
X1292673Y1559750D03*
X1299492Y1572106D03*
Y1569606D03*
X1307766Y563013D03*
X1308700Y590300D03*
X1317266Y592522D03*
X1308700Y587800D03*
X1313109Y1195398D03*
Y1200898D03*
X1325366Y592522D03*
X1339488Y1202295D03*
X1340483Y1209006D03*
X1336861Y1222119D03*
X1350809Y1202323D03*
X1368137Y1222298D03*
Y1227798D03*
X1383800Y1685398D03*
X1406655Y1564073D03*
X1409155D03*
X1399940Y1637127D03*
X1414619Y244450D03*
X1416301Y966740D03*
Y981740D03*
Y974240D03*
X1416556Y1511082D03*
X1419156Y1512992D03*
Y1517772D03*
X1413956Y1512992D03*
Y1517772D03*
X1416556Y1524482D03*
X1419156Y1531172D03*
Y1526392D03*
X1413956Y1531172D03*
Y1526392D03*
X1412020Y1542654D03*
X1420735Y1559750D03*
X1411655Y1564073D03*
X1435160Y1510590D03*
Y1532490D03*
X1435578Y1564902D03*
Y1562402D03*
X1436940Y1554277D03*
X1435604Y1572106D03*
Y1569606D03*
X1445985Y116953D03*
X1441390Y163944D03*
X1442993Y176204D03*
X1462405Y61563D03*
X1461242Y128242D03*
X1463017Y136368D03*
X1465832Y535330D03*
X1542767Y1564073D03*
X1552668Y1511082D03*
X1555268Y1512992D03*
Y1517772D03*
X1550068Y1512992D03*
Y1517772D03*
X1552668Y1524482D03*
X1555268Y1531172D03*
Y1526392D03*
X1550068Y1531172D03*
Y1526392D03*
X1548132Y1542654D03*
X1556847Y1559750D03*
X1545267Y1564073D03*
X1547767D03*
X1552118Y1569763D03*
X1549618D03*
X1563222Y1510590D03*
Y1532490D03*
X1564581Y1562316D03*
X1562613Y1564816D03*
X1564128Y1572225D03*
X1562621Y1569761D03*
X1602270Y229530D03*
X1629597Y221842D03*
X1619909Y306746D03*
X1643283Y1425541D03*
X1648337Y1451313D03*
X1654419Y233062D03*
X1655383Y1425541D03*
X1656997Y1708609D03*
Y1723759D03*
X1665100Y156762D03*
Y166762D03*
X1673223Y220857D03*
X1673630Y1533092D03*
Y1537872D03*
X1684925Y118762D03*
Y149762D03*
Y161762D03*
Y153762D03*
X1684942Y234000D03*
X1683587Y1433425D03*
X1680430Y1511198D03*
X1682760Y1512169D03*
X1683330Y1517772D03*
X1678130Y1512992D03*
Y1517772D03*
X1680730Y1524482D03*
X1683330Y1531172D03*
Y1526392D03*
X1678130Y1531172D03*
Y1526392D03*
X1688584Y1553284D03*
X1691548Y1555287D03*
X1686857Y1683918D03*
X1684733Y1698952D03*
X1695102Y1698947D03*
X1691357Y1688418D03*
X1691997Y1708609D03*
X1733083Y654034D03*
X1737606Y1539807D03*
X1736579Y1587480D03*
X1723929Y1654456D03*
X1723963Y1658965D03*
Y1663465D03*
Y1667965D03*
X1731117Y1705115D03*
Y1720265D03*
X1741329Y1482405D03*
Y1485405D03*
Y1491405D03*
Y1488405D03*
X1740058Y1537419D03*
X1744866Y1539589D03*
X1742165Y1539620D03*
X1740979Y1577905D03*
X1743681Y1626750D03*
X1750681D03*
X1747181D03*
X1743481Y1616550D03*
X1750481D03*
X1746981D03*
X1747963Y1641965D03*
X1764029Y1485405D03*
Y1482405D03*
Y1491405D03*
Y1488405D03*
X1756329Y1485405D03*
Y1482405D03*
Y1491405D03*
Y1488405D03*
X1769054Y1585705D03*
X1753079Y1596650D03*
Y1606550D03*
Y1603050D03*
Y1600150D03*
X1761839Y1634223D03*
X1757763Y1643365D03*
X1761494Y1661947D03*
X1779029Y1482405D03*
Y1485405D03*
Y1491405D03*
Y1488405D03*
X1772904Y1585005D03*
X1773863Y1661465D03*
X1774940Y1669037D03*
X1773738Y1672965D03*
X1773963Y1680965D03*
X1793070Y25001D03*
X1788029Y1485405D03*
Y1482405D03*
Y1491405D03*
Y1488405D03*
X1789379Y1588478D03*
X1805525Y146716D03*
X1812029Y1485405D03*
Y1482405D03*
X1803029D03*
Y1485405D03*
X1812029Y1491405D03*
Y1488405D03*
X1803029Y1491405D03*
Y1488405D03*
X1801789Y1536742D03*
X1807408Y1539223D03*
X1810408D03*
X1812078Y1596725D03*
X1812003Y1607375D03*
Y1603875D03*
X1812078Y1600225D03*
X1809179Y1616550D03*
X1809254Y1613775D03*
X1812570Y159275D03*
X1827029Y1488405D03*
Y1491405D03*
Y1485405D03*
Y1482405D03*
X1815344Y1539373D03*
X1818344D03*
X1823112Y1538659D03*
X1812679Y1616550D03*
X1816179D03*
X1812754Y1613775D03*
X1816254D03*
X1837641Y159275D03*
X1840700Y326201D03*
Y348201D03*
Y370201D03*
Y392201D03*
Y414201D03*
Y436201D03*
Y458201D03*
Y480201D03*
Y502201D03*
Y524201D03*
Y546201D03*
Y568201D03*
Y590201D03*
Y656201D03*
Y678201D03*
Y700201D03*
Y722201D03*
Y744201D03*
Y766201D03*
Y788201D03*
Y810201D03*
Y832201D03*
Y854201D03*
Y876201D03*
Y898201D03*
Y920201D03*
Y942201D03*
Y964201D03*
Y986201D03*
Y1008201D03*
Y1030201D03*
Y1052201D03*
Y1074201D03*
Y1096201D03*
Y1118201D03*
Y1140201D03*
Y1162201D03*
Y1184201D03*
Y1206201D03*
Y1228201D03*
Y1250201D03*
Y1272201D03*
Y1294201D03*
Y1316201D03*
Y1338201D03*
Y1404201D03*
Y1448201D03*
Y1470201D03*
Y1492201D03*
Y1514201D03*
Y1536201D03*
Y1558201D03*
Y1580201D03*
X1828889Y1622578D03*
Y1644578D03*
Y1666578D03*
Y1688578D03*
X1854479Y66461D03*
Y110461D03*
Y132461D03*
Y154461D03*
X1847866Y159124D03*
X1854479Y176461D03*
Y198461D03*
Y220461D03*
Y242461D03*
Y264461D03*
Y286461D03*
G54D58*
X922441Y154311D03*
Y243799D03*
G54D12*
X21569Y49379D03*
X21345Y387760D03*
X21309Y395712D03*
X36500Y323500D03*
X33686Y383944D03*
X27309Y383926D03*
X29962Y401000D03*
X36524Y398013D03*
X26771Y398811D03*
X30680Y438142D03*
X35852Y664480D03*
Y686410D03*
Y683910D03*
X43569Y49379D03*
X45423Y197224D03*
Y212224D03*
Y202224D03*
Y207224D03*
X40000Y323500D03*
X55190Y360862D03*
X42809D03*
X46834D03*
X39410Y384582D03*
X39226Y395346D03*
X53825Y421746D03*
X49848Y524210D03*
X49889Y531149D03*
X50880Y1421963D03*
X52405Y1514835D03*
X49405D03*
X52405Y1511986D03*
X49405D03*
X52330Y1509137D03*
X49330D03*
X52796Y1526469D03*
X52905Y1523335D03*
X47760Y1529506D03*
X65347Y66847D03*
X60367D03*
X65347Y71839D03*
X60367D03*
X58457Y69340D03*
X67575Y287500D03*
X56620Y303500D03*
X64150Y434972D03*
X53800Y435451D03*
X54762Y444993D03*
X56800Y524220D03*
X56719Y531120D03*
X64923Y795316D03*
Y832127D03*
Y868938D03*
Y905750D03*
Y942561D03*
Y1089805D03*
Y1126616D03*
Y1163427D03*
Y1200238D03*
Y1237049D03*
X58349Y1412731D03*
X55755Y1511885D03*
X55905Y1514835D03*
X57281Y1523287D03*
X66081D03*
X59881D03*
X63481D03*
X55789Y1509224D03*
X57281Y1526394D03*
X66081D03*
X65281Y1529501D03*
X59881Y1526394D03*
X63481D03*
X62681Y1529501D03*
X64235Y1533150D03*
X61755D03*
X59275D03*
X67196Y1552869D03*
X64235Y1538750D03*
X61755D03*
X59275D03*
X63802Y1579997D03*
X58602D03*
X61302D03*
X75928Y3001D03*
X81159Y17045D03*
X72087Y25977D03*
X74087Y23981D03*
X79043D03*
X81043Y25977D03*
X79192Y19541D03*
X81159Y22037D03*
X73025Y37106D03*
X80111D03*
X73025Y48720D03*
X80111D03*
X69453Y75343D03*
X82367Y71839D03*
X80457Y69340D03*
X82367Y66847D03*
X76347Y72850D03*
X71367D03*
X76347Y77842D03*
X71367D03*
X71779Y157194D03*
Y161194D03*
X71772Y421746D03*
X68365Y443677D03*
X80915Y756766D03*
X73873D03*
Y760266D03*
X69323Y776911D03*
X80915Y763766D03*
X80015Y786950D03*
X69323Y783604D03*
X81065Y791970D03*
X80015Y796989D03*
X69323Y807029D03*
Y813722D03*
Y820415D03*
X80015Y823761D03*
Y833800D03*
X81065Y828781D03*
X69323Y843840D03*
Y850533D03*
X80015Y860572D03*
X81065Y865592D03*
X69323Y857226D03*
X80015Y870611D03*
X69323Y880651D03*
Y887344D03*
Y894037D03*
X80015Y907423D03*
Y897383D03*
X81065Y902403D03*
X69323Y924155D03*
Y917462D03*
X81065Y939214D03*
X80015Y934194D03*
X69323Y930848D03*
X80015Y944234D03*
X69323Y954273D03*
Y960966D03*
Y967659D03*
Y974352D03*
Y981045D03*
Y987737D03*
Y994430D03*
Y1004470D03*
Y1034588D03*
Y1041281D03*
Y1047974D03*
Y1054667D03*
Y1071399D03*
Y1061360D03*
X80015Y1081438D03*
X81065Y1086458D03*
X69323Y1078092D03*
X80015Y1091478D03*
X69323Y1101517D03*
X80015Y1118249D03*
X69323Y1114903D03*
Y1108210D03*
X80015Y1128289D03*
X81065Y1123269D03*
X69323Y1145021D03*
Y1138328D03*
X80015Y1165100D03*
X81065Y1160080D03*
X80015Y1155060D03*
X69323Y1151714D03*
Y1175139D03*
Y1181832D03*
X80015Y1191871D03*
X69323Y1188525D03*
X81065Y1196891D03*
X80015Y1201911D03*
X69323Y1211950D03*
Y1218643D03*
X80015Y1238722D03*
Y1228682D03*
X81065Y1233702D03*
X69323Y1225336D03*
Y1248761D03*
Y1255454D03*
X76378Y1406622D03*
X74325Y1523303D03*
X68870Y1523147D03*
X71359Y1523186D03*
X81868Y1511285D03*
X81405Y1516835D03*
X81905Y1513835D03*
X81405Y1519835D03*
Y1522835D03*
X78808Y1522839D03*
X81905Y1508698D03*
X74440Y1526385D03*
X74462Y1529665D03*
X82696Y1529095D03*
X76806Y1593265D03*
X80400Y1602225D03*
X86139Y17045D03*
X95333D03*
X88148Y19541D03*
X95216Y25977D03*
X86260D03*
X93216Y23981D03*
X88260D03*
X86139Y22037D03*
X95333D03*
X93365Y19541D03*
X94284Y37106D03*
X87198D03*
Y48720D03*
X94284D03*
X87347Y71839D03*
Y66847D03*
X91457Y75340D03*
X93367Y72847D03*
Y77839D03*
X89150Y154494D03*
X93717Y159053D03*
X87654Y376026D03*
X87520Y386502D03*
X85465Y773564D03*
Y780257D03*
Y803682D03*
X94624Y795316D03*
X85465Y810375D03*
Y817068D03*
X94624Y832127D03*
X85465Y840493D03*
Y847186D03*
Y853879D03*
Y877304D03*
X94624Y868938D03*
X85465Y890690D03*
Y883997D03*
X94624Y905750D03*
X85465Y920808D03*
Y914115D03*
Y927501D03*
Y950926D03*
X94624Y942561D03*
X85465Y957619D03*
Y971005D03*
Y964312D03*
Y984391D03*
Y977698D03*
Y991084D03*
Y997777D03*
Y1004470D03*
Y1044627D03*
Y1031241D03*
Y1037934D03*
Y1051320D03*
Y1058013D03*
Y1068052D03*
Y1074745D03*
X94624Y1089805D03*
X85465Y1098171D03*
Y1104863D03*
Y1111556D03*
X94624Y1126616D03*
X85465Y1134982D03*
Y1148367D03*
Y1141675D03*
X94624Y1163427D03*
X85465Y1178486D03*
Y1171793D03*
Y1185178D03*
Y1208604D03*
X94624Y1200238D03*
X85465Y1215297D03*
Y1221989D03*
X94624Y1237049D03*
X85465Y1252108D03*
Y1245415D03*
X90501Y1338952D03*
X92791Y1341302D03*
X96191Y1337721D03*
X92941Y1346172D03*
X91000Y1350300D03*
X88500D03*
X84000Y1408000D03*
Y1412500D03*
Y1417000D03*
X97530Y1410247D03*
X93000Y1430500D03*
X84000Y1421500D03*
Y1426000D03*
X93000Y1435500D03*
Y1440000D03*
X84500D03*
X95624Y1523287D03*
X85368Y1511285D03*
X85405Y1513835D03*
X88868Y1511285D03*
X88905Y1513835D03*
X93024Y1523287D03*
X85405Y1508698D03*
X88905D03*
X97498Y1533150D03*
X95624Y1526394D03*
X95018Y1533150D03*
X88696Y1526769D03*
X93024Y1526394D03*
X88696Y1523769D03*
X97498Y1538750D03*
X95018D03*
X93029Y1705225D03*
X97683Y1722477D03*
X97928Y3001D03*
X100313Y17045D03*
X109506D03*
X109389Y25977D03*
X100433D03*
X107389Y23981D03*
X102433D03*
X100313Y22037D03*
X102321Y19541D03*
X109506Y22037D03*
X107538Y19541D03*
X108458Y37106D03*
X101371D03*
Y48720D03*
X108458D03*
X98347Y72847D03*
X104367Y71839D03*
X109347D03*
X102457Y69340D03*
X104367Y66847D03*
X109347D03*
X98347Y77839D03*
X104829Y151191D03*
X107931Y158767D03*
X99754Y155807D03*
X110616Y756766D03*
X103574D03*
Y760266D03*
X99024Y776911D03*
X110616Y763766D03*
X103574Y767266D03*
X99024Y783604D03*
X109716Y786950D03*
X110766Y791970D03*
X99024Y807029D03*
X109716Y796989D03*
X99024Y813722D03*
Y820415D03*
X109716Y823761D03*
Y833800D03*
X110766Y828781D03*
X99024Y843840D03*
Y850533D03*
Y857226D03*
X109716Y860572D03*
X110766Y865592D03*
X99024Y880651D03*
X109716Y870611D03*
X99024Y887344D03*
Y894037D03*
X109716Y897383D03*
X110766Y902403D03*
X109716Y907423D03*
X99024Y924155D03*
Y917462D03*
Y930848D03*
X110766Y939214D03*
X109716Y934194D03*
X99024Y954273D03*
X109716Y944234D03*
X99024Y960966D03*
Y967659D03*
Y974352D03*
Y981045D03*
Y987737D03*
Y994430D03*
Y1004470D03*
Y1034588D03*
Y1041281D03*
Y1047974D03*
Y1054667D03*
Y1071399D03*
Y1061360D03*
Y1078092D03*
X109716Y1081438D03*
X110766Y1086458D03*
X99024Y1101517D03*
X109716Y1091478D03*
X99024Y1114903D03*
Y1108210D03*
X109716Y1118249D03*
Y1128289D03*
X110766Y1123269D03*
X99024Y1145021D03*
Y1138328D03*
Y1151714D03*
X109716Y1165100D03*
X110766Y1160080D03*
X109716Y1155060D03*
X99024Y1175139D03*
Y1181832D03*
Y1188525D03*
X109716Y1191871D03*
X110766Y1196891D03*
X109716Y1201911D03*
X99024Y1211950D03*
Y1218643D03*
Y1225336D03*
X109716Y1228682D03*
Y1238722D03*
X110766Y1233702D03*
X99024Y1248761D03*
Y1255454D03*
X99211Y1337771D03*
X112677Y1357409D03*
X110077D03*
X107477D03*
X104877D03*
X111581Y1372872D03*
X106721Y1367272D03*
Y1372872D03*
X109151D03*
X112677Y1363473D03*
X110077D03*
X112677Y1360516D03*
X110077D03*
X107477D03*
X104877D03*
X100347Y1361417D03*
X109151Y1367272D03*
X111581D03*
X111630Y1385287D03*
X101995Y1388247D03*
X98492Y1523287D03*
X100922D03*
X109635Y1523158D03*
X106713Y1523098D03*
X103513D03*
X99978Y1533150D03*
X98492Y1526394D03*
X98424Y1529501D03*
X100922Y1526394D03*
X101024Y1529501D03*
X108861Y1528840D03*
Y1526410D03*
X101396Y1552769D03*
X99978Y1538750D03*
X106448Y1696436D03*
X119928Y3001D03*
X114486Y17045D03*
X123683D03*
X123563Y25977D03*
X114607D03*
X116607Y23981D03*
X121563D03*
X114486Y22037D03*
X116494Y19541D03*
X121712D03*
X123683Y22037D03*
X122631Y37106D03*
X115544D03*
Y48720D03*
X122631D03*
X113457Y75340D03*
X115367Y72847D03*
X120347D03*
X126367Y71842D03*
X124457Y69343D03*
X126367Y66850D03*
X115367Y77839D03*
X120347D03*
X115166Y773564D03*
Y780257D03*
X124324Y795316D03*
X115166Y803682D03*
Y810375D03*
Y817068D03*
X124324Y832127D03*
X115166Y840493D03*
Y847186D03*
Y853879D03*
Y877304D03*
X124324Y868938D03*
X115166Y890690D03*
Y883997D03*
X124324Y905750D03*
X115166Y920808D03*
Y914115D03*
Y927501D03*
Y950926D03*
X124324Y942561D03*
X115166Y957619D03*
Y971005D03*
Y964312D03*
Y984391D03*
Y977698D03*
Y991084D03*
Y997777D03*
Y1004470D03*
Y1031241D03*
Y1037934D03*
Y1044627D03*
Y1051320D03*
Y1058013D03*
Y1068052D03*
Y1074745D03*
X124324Y1089805D03*
X115166Y1098171D03*
Y1104863D03*
Y1111556D03*
X124324Y1126616D03*
X115166Y1134982D03*
Y1148367D03*
Y1141675D03*
X124324Y1163427D03*
X115166Y1178486D03*
Y1171793D03*
Y1185178D03*
Y1208604D03*
X124324Y1200238D03*
X115166Y1215297D03*
Y1221989D03*
X124324Y1237049D03*
X115166Y1252108D03*
Y1245415D03*
X124071Y1337843D03*
X126671D03*
X115277Y1357409D03*
X126491Y1354871D03*
X125241Y1357371D03*
X126491Y1352271D03*
X123891Y1354871D03*
Y1352271D03*
X120221Y1357425D03*
X126491Y1349671D03*
X123891D03*
X117777Y1357409D03*
X121207Y1360686D03*
X114405Y1509335D03*
Y1516335D03*
Y1512835D03*
Y1519835D03*
Y1522835D03*
X116905D03*
Y1519835D03*
Y1512835D03*
Y1516335D03*
Y1509335D03*
Y1526335D03*
X120052Y1712450D03*
X141928Y3001D03*
X128663Y17045D03*
X130668Y19541D03*
X128663Y22037D03*
X129718Y37106D03*
Y48720D03*
X135457Y75340D03*
X137367Y72847D03*
X142347D03*
X131347Y71842D03*
Y66850D03*
X137367Y77839D03*
X142347D03*
X128367Y202241D03*
Y207241D03*
Y197241D03*
Y212241D03*
X139440Y439000D03*
X138090Y441900D03*
X140800Y441920D03*
X134812Y530955D03*
X131861Y664958D03*
X139869Y686582D03*
X140316Y756766D03*
X133124D03*
Y760266D03*
X128724Y776911D03*
X140316Y763766D03*
X133124Y767266D03*
X139416Y786950D03*
X128724Y783604D03*
X140466Y791970D03*
X128724Y807029D03*
X139416Y796989D03*
X128724Y813722D03*
Y820415D03*
X139416Y823761D03*
Y833800D03*
X140466Y828781D03*
X128724Y843840D03*
Y850533D03*
Y857226D03*
X139416Y860572D03*
X140466Y865592D03*
X128724Y880651D03*
X139416Y870611D03*
X128724Y887344D03*
Y894037D03*
X139416Y897383D03*
X140466Y902403D03*
X139416Y907423D03*
X128724Y924155D03*
Y917462D03*
X140466Y939214D03*
X139416Y934194D03*
X128724Y930848D03*
Y954273D03*
X139416Y944234D03*
X128724Y960966D03*
Y967659D03*
Y974352D03*
Y981045D03*
Y987737D03*
Y994430D03*
Y1004470D03*
Y1034588D03*
Y1041281D03*
Y1047974D03*
Y1054667D03*
Y1071399D03*
Y1061360D03*
X139416Y1081438D03*
X140466Y1086458D03*
X128724Y1078092D03*
Y1101517D03*
X139416Y1091478D03*
X128724Y1114903D03*
X139416Y1118249D03*
X128724Y1108210D03*
X139416Y1128289D03*
X140466Y1123269D03*
X128724Y1145021D03*
Y1138328D03*
X139416Y1165100D03*
X140466Y1160080D03*
X139416Y1155060D03*
X128724Y1151714D03*
Y1175139D03*
Y1181832D03*
X139416Y1191871D03*
X128724Y1188525D03*
X140466Y1196891D03*
X139416Y1201911D03*
X128724Y1211950D03*
Y1218643D03*
Y1225336D03*
X139416Y1228682D03*
X140466Y1233702D03*
X139416Y1238722D03*
X128724Y1248761D03*
Y1255454D03*
X137551Y1337771D03*
X131791Y1337811D03*
X140077Y1357409D03*
X137477D03*
X139321Y1367272D03*
Y1372872D03*
X141751D03*
X140077Y1360516D03*
X137477D03*
X132947Y1361417D03*
X141751Y1367272D03*
X130492Y1384789D03*
X132150Y1386740D03*
X132643Y1711846D03*
X150473Y25977D03*
X157429Y23981D03*
X152473D03*
X151410Y37106D03*
Y48720D03*
X153347Y71842D03*
X148367D03*
X153347Y66850D03*
X148367D03*
X146453Y69343D03*
X150318Y233536D03*
X142660Y438930D03*
X143720Y441960D03*
X145960Y438800D03*
X146930Y441870D03*
X149210Y438640D03*
X149830Y441920D03*
X149672Y665500D03*
X152705Y683218D03*
X144866Y773564D03*
Y780257D03*
X154025Y795316D03*
X144866Y803682D03*
Y810375D03*
Y817068D03*
X154025Y832127D03*
X144866Y840493D03*
Y847186D03*
Y853879D03*
Y877304D03*
X154025Y868938D03*
X144866Y890690D03*
Y883997D03*
X154025Y905750D03*
X144866Y920808D03*
Y914115D03*
Y927501D03*
X154025Y942561D03*
X144866Y950926D03*
Y957619D03*
Y971005D03*
Y964312D03*
Y984391D03*
Y977698D03*
Y991084D03*
Y997777D03*
Y1004470D03*
Y1031241D03*
Y1037934D03*
Y1044627D03*
Y1051320D03*
Y1058013D03*
Y1068052D03*
Y1074745D03*
X154025Y1089805D03*
X144866Y1098171D03*
Y1104863D03*
Y1111556D03*
X154025Y1126616D03*
X144866Y1134982D03*
Y1148367D03*
Y1141675D03*
X154025Y1163427D03*
X144866Y1178486D03*
Y1171793D03*
Y1185178D03*
Y1208604D03*
X154025Y1200238D03*
X144866Y1215297D03*
Y1221989D03*
X154025Y1237049D03*
X144866Y1252108D03*
Y1245415D03*
X156491Y1354871D03*
Y1352271D03*
X152821Y1357425D03*
X156491Y1349671D03*
X145277Y1357409D03*
X147877D03*
X142677D03*
X150377D03*
X144181Y1367272D03*
X153767Y1360456D03*
Y1363413D03*
X144181Y1372872D03*
X142677Y1360516D03*
X145277Y1363473D03*
X142677D03*
X145277Y1360516D03*
X144230Y1385287D03*
X150900Y1433500D03*
Y1429500D03*
X143478Y1440000D03*
X151082Y1436653D03*
X146978Y1440000D03*
X147277Y1712791D03*
X152815Y1705500D03*
X155740Y1729726D03*
X163928Y3001D03*
X164525Y17045D03*
X159545D03*
X159429Y25977D03*
X164646D03*
X171602Y23981D03*
X166646D03*
X157578Y19541D03*
X166534D03*
X171751D03*
X164525Y22037D03*
X159545D03*
X158497Y37106D03*
X165584D03*
X158497Y48720D03*
X165584D03*
X158661Y75340D03*
X160571Y72847D03*
X165551D03*
X171571Y71839D03*
X169661Y69340D03*
X171571Y66847D03*
X160571Y77839D03*
X165551D03*
X172120Y416600D03*
X168950Y412950D03*
X168910Y415930D03*
X170500Y441420D03*
X167580Y441380D03*
X164870Y441360D03*
X169440Y438390D03*
X166220Y438460D03*
X162975Y760266D03*
Y756766D03*
X170017D03*
X158425Y776911D03*
X170017Y763766D03*
X162975Y767266D03*
X158425Y783604D03*
X169117Y786950D03*
X170167Y791970D03*
X158425Y807029D03*
X169117Y796989D03*
X158425Y813722D03*
Y820415D03*
X169117Y823761D03*
Y833800D03*
X170167Y828781D03*
X158425Y843840D03*
Y850533D03*
Y857226D03*
X169117Y860572D03*
X170167Y865592D03*
X158425Y880651D03*
X169117Y870611D03*
X158425Y887344D03*
Y894037D03*
X169117Y897383D03*
X170167Y902403D03*
X169117Y907423D03*
X158425Y924155D03*
Y917462D03*
Y930848D03*
X170167Y939214D03*
X169117Y934194D03*
X158425Y954273D03*
X169117Y944234D03*
X158425Y960966D03*
Y967659D03*
Y974352D03*
Y981045D03*
Y987737D03*
Y994430D03*
Y1004470D03*
Y1034588D03*
Y1041281D03*
Y1047974D03*
Y1054667D03*
Y1071399D03*
Y1061360D03*
Y1078092D03*
X169117Y1081438D03*
X170167Y1086458D03*
X158425Y1101517D03*
X169117Y1091478D03*
X158425Y1114903D03*
Y1108210D03*
X169117Y1118249D03*
Y1128289D03*
X170167Y1123269D03*
X158425Y1145021D03*
Y1138328D03*
X169117Y1165100D03*
X170167Y1160080D03*
X169117Y1155060D03*
X158425Y1151714D03*
Y1175139D03*
Y1181832D03*
Y1188525D03*
X169117Y1191871D03*
X170167Y1196891D03*
X169117Y1201911D03*
X158425Y1211950D03*
Y1218643D03*
Y1225336D03*
X169117Y1238722D03*
Y1228682D03*
X170167Y1233702D03*
X158425Y1248761D03*
Y1255454D03*
X171481Y1337853D03*
X164481Y1337813D03*
X161881D03*
X170177Y1357409D03*
X159091Y1354871D03*
X157841Y1357371D03*
X159091Y1352271D03*
Y1349671D03*
X172021Y1367272D03*
Y1372872D03*
X170177Y1360516D03*
X165647Y1361417D03*
X163192Y1384789D03*
X164850Y1386740D03*
X168661Y1459995D03*
X166751Y1462595D03*
X168661Y1465195D03*
X164650Y1529350D03*
Y1540250D03*
X171925Y1708428D03*
X167500Y1712864D03*
X171925Y1727581D03*
X157860Y1718500D03*
X185928Y3001D03*
X173719Y17045D03*
X178699D03*
X173602Y25977D03*
X173719Y22037D03*
X178699D03*
X180707Y19541D03*
X172670Y37106D03*
X179757D03*
X172670Y48720D03*
X179757D03*
X176551Y71839D03*
Y66847D03*
X180657Y75343D03*
X182571Y72850D03*
Y77842D03*
X182548Y147260D03*
X176610Y441380D03*
X175990Y438100D03*
X173710Y441330D03*
X172740Y438260D03*
X173299Y664958D03*
X172802Y682036D03*
X174567Y773564D03*
Y780257D03*
Y803682D03*
X183726Y795316D03*
X174567Y810375D03*
Y817068D03*
X183726Y832127D03*
X174567Y840493D03*
Y847186D03*
Y853879D03*
Y877304D03*
X183726Y868938D03*
X174567Y890690D03*
Y883997D03*
X183726Y905750D03*
X174567Y920808D03*
Y914115D03*
Y927501D03*
Y950926D03*
X183726Y942561D03*
X174567Y957619D03*
Y971005D03*
Y964312D03*
Y984391D03*
Y977698D03*
Y991084D03*
Y997777D03*
Y1004470D03*
Y1031241D03*
Y1037934D03*
Y1044627D03*
Y1051320D03*
Y1058013D03*
Y1068052D03*
Y1074745D03*
X183726Y1089805D03*
X174567Y1098171D03*
Y1104863D03*
Y1111556D03*
Y1134982D03*
X183726Y1126616D03*
X174567Y1148367D03*
Y1141675D03*
X183726Y1163427D03*
X174567Y1178486D03*
Y1171793D03*
Y1185178D03*
Y1208604D03*
X183726Y1200238D03*
X174567Y1215297D03*
Y1221989D03*
X183726Y1237049D03*
X174567Y1252108D03*
Y1245415D03*
X185701Y1337853D03*
X183101D03*
X174081D03*
X172777Y1357409D03*
X183077D03*
X185521Y1357425D03*
X175377Y1357409D03*
X177977D03*
X180577D03*
X176881Y1367272D03*
X174451D03*
X186467Y1360456D03*
Y1363413D03*
X172777Y1360516D03*
X176881Y1372872D03*
X174451D03*
X177977Y1363473D03*
X175377D03*
Y1360516D03*
X177977D03*
X176930Y1385287D03*
X173441Y1459995D03*
X173451Y1452895D03*
X180141Y1450295D03*
X175361D03*
X180141Y1455495D03*
X175361D03*
X173441Y1465195D03*
X186851Y1472295D03*
X177322Y1498320D03*
X173980Y1528731D03*
X185254Y1686870D03*
X179444Y1708810D03*
X184340Y1718000D03*
X194607Y25977D03*
X196607Y23981D03*
X201563D03*
X201712Y19541D03*
X195544Y37106D03*
Y48720D03*
X193571Y71839D03*
X198551D03*
X191661Y69340D03*
X193571Y66847D03*
X198551D03*
X187656Y72850D03*
Y77842D03*
X195979Y109462D03*
X203061Y131158D03*
X195690Y415390D03*
X195730Y412410D03*
X200405Y622385D03*
Y632385D03*
X192676Y760266D03*
Y756766D03*
X199718D03*
X192676Y767266D03*
X199718Y763766D03*
X188126Y776911D03*
X199868Y791970D03*
X198818Y786950D03*
X188126Y783604D03*
X198818Y796989D03*
X188126Y807029D03*
Y813722D03*
Y820415D03*
X199868Y828781D03*
X198818Y823761D03*
Y833800D03*
X188126Y843840D03*
Y850533D03*
X199868Y865592D03*
X198818Y860572D03*
X188126Y857226D03*
X198818Y870611D03*
X188126Y880651D03*
Y887344D03*
Y894037D03*
X199868Y902403D03*
X198818Y897383D03*
Y907423D03*
X188126Y917462D03*
Y924155D03*
X199868Y939214D03*
X198818Y934194D03*
X188126Y930848D03*
X198818Y944234D03*
X188126Y954273D03*
Y960966D03*
Y967659D03*
Y974352D03*
Y981045D03*
Y987737D03*
Y994430D03*
Y1004470D03*
Y1034588D03*
Y1041281D03*
Y1047974D03*
Y1054667D03*
Y1061360D03*
Y1071399D03*
X199868Y1086458D03*
X198818Y1081438D03*
X188126Y1078092D03*
X198818Y1091478D03*
X188126Y1101517D03*
X198818Y1118249D03*
X188126Y1108210D03*
Y1114903D03*
X199868Y1123269D03*
X198818Y1128289D03*
X188126Y1138328D03*
Y1145021D03*
X199868Y1160080D03*
X198818Y1155060D03*
Y1165100D03*
X188126Y1151714D03*
Y1175139D03*
X198818Y1191871D03*
X188126Y1181832D03*
Y1188525D03*
X199868Y1196891D03*
X198818Y1201911D03*
X188126Y1211950D03*
Y1218643D03*
X199868Y1233702D03*
X198818Y1228682D03*
Y1238722D03*
X188126Y1225336D03*
Y1248761D03*
Y1255454D03*
X195771Y1337903D03*
X193171D03*
X190541Y1357371D03*
X189191Y1354871D03*
Y1352271D03*
X191791Y1354871D03*
Y1352271D03*
X189191Y1349671D03*
X191791D03*
X198547Y1361417D03*
X196092Y1384789D03*
X197750Y1386740D03*
X193551Y1462595D03*
X200241Y1459995D03*
X195461D03*
X202161Y1450295D03*
X200251Y1452895D03*
X202161Y1455495D03*
X193541Y1469695D03*
X188761D03*
X193541Y1474895D03*
X188761D03*
X200241Y1465195D03*
X195461D03*
X197703Y1550897D03*
X192978Y1550797D03*
X188254D03*
X187388Y1594876D03*
X192344D03*
X199448D03*
X187388Y1589884D03*
X199448D03*
X192344D03*
X193418Y1604876D03*
Y1599884D03*
X198374D03*
Y1604876D03*
Y1611796D03*
X193418D03*
X198374Y1616788D03*
X193418D03*
X192344Y1626788D03*
X199448D03*
X192344Y1621796D03*
X199448D03*
X187388D03*
Y1626788D03*
X200848Y1655656D03*
X190242Y1656635D03*
X201120Y1668603D03*
X199040Y1666925D03*
X196366Y1664821D03*
X190271Y1671753D03*
X195153Y1679774D03*
X190391Y1701988D03*
X195300Y1694898D03*
X194000Y1712362D03*
X201531Y1715000D03*
X192745Y1707106D03*
X199547Y1704605D03*
X195150Y1723000D03*
X207928Y3001D03*
X208659Y17045D03*
X203679D03*
X208780Y25977D03*
X203563D03*
X210780Y23981D03*
X215736D03*
X210668Y19541D03*
X215885D03*
X208659Y22037D03*
X203679D03*
X202631Y37106D03*
X216804D03*
X209718D03*
X202631Y48720D03*
X209718D03*
X216804D03*
X202795Y75340D03*
X204705Y72847D03*
X209685D03*
X213791Y69343D03*
X215705Y66850D03*
Y71842D03*
X204705Y77839D03*
X209685D03*
X214107Y113022D03*
X205489Y142790D03*
X206760Y148760D03*
X206805Y622385D03*
X203605D03*
X206805Y632385D03*
X203605D03*
X204268Y773564D03*
Y780257D03*
X213427Y795316D03*
X204268Y803682D03*
Y810375D03*
Y817068D03*
X213427Y832127D03*
X204268Y840493D03*
Y847186D03*
Y853879D03*
X213427Y868938D03*
X204268Y877304D03*
Y883997D03*
Y890690D03*
X213427Y905750D03*
X204268Y914115D03*
Y920808D03*
Y927501D03*
X213427Y942561D03*
X204268Y950926D03*
Y957619D03*
Y964312D03*
Y971005D03*
Y977698D03*
Y984391D03*
Y991084D03*
Y997777D03*
Y1004470D03*
Y1031241D03*
Y1037934D03*
Y1044627D03*
Y1051320D03*
Y1058013D03*
Y1068052D03*
Y1074745D03*
X213427Y1089805D03*
X204268Y1098171D03*
Y1104863D03*
Y1111556D03*
X213427Y1126616D03*
X204268Y1134982D03*
Y1141675D03*
Y1148367D03*
X213427Y1163427D03*
X204268Y1171793D03*
Y1178486D03*
Y1185178D03*
X213427Y1200238D03*
X204268Y1208604D03*
Y1215297D03*
Y1221989D03*
X213427Y1237049D03*
X204268Y1245415D03*
Y1252108D03*
X215977Y1357409D03*
X210877D03*
X208277D03*
X213477D03*
X205677D03*
X203077D03*
X207351Y1367272D03*
X209781Y1372872D03*
X204921Y1367272D03*
Y1372872D03*
X207351D03*
X210877Y1363473D03*
X208277D03*
Y1360516D03*
X210877D03*
X205677D03*
X203077D03*
X209781Y1367272D03*
X209830Y1385287D03*
X213648Y1416262D03*
X206941Y1450295D03*
Y1455495D03*
X213651Y1472295D03*
X215561Y1469695D03*
Y1474895D03*
X216601Y1550697D03*
X202427D03*
X211876Y1550897D03*
X207152D03*
X211508Y1594876D03*
X204404D03*
X216464D03*
X211508Y1589884D03*
X204404D03*
X216464D03*
X210434Y1604876D03*
X205478D03*
X210434Y1599884D03*
X205478D03*
Y1611796D03*
X210434D03*
Y1616788D03*
X205478D03*
X211508Y1626788D03*
X216464D03*
X211508Y1621796D03*
X216464D03*
X204404Y1626788D03*
Y1621796D03*
X203807Y1681173D03*
Y1696366D03*
X211103Y1708988D03*
X229928Y3001D03*
X217853Y17045D03*
X222833D03*
X217736Y25977D03*
X217853Y22037D03*
X222833D03*
X224841Y19541D03*
X223891Y37106D03*
X230977D03*
X223891Y48720D03*
X230977D03*
X224795Y75340D03*
X226705Y72847D03*
X231685D03*
X220685Y66850D03*
Y71842D03*
X231685Y77839D03*
X226705D03*
X233653Y162074D03*
X222000Y160000D03*
X220687Y522453D03*
X226687D03*
X233493Y676906D03*
X227493D03*
X224493D03*
X230493D03*
X221493D03*
X222377Y760266D03*
Y756766D03*
X229419D03*
X222377Y767266D03*
X229419Y763119D03*
X217827Y776911D03*
X229569Y791970D03*
X228519Y786950D03*
X217827Y783604D03*
X228519Y796989D03*
X217827Y807029D03*
Y813722D03*
Y820415D03*
X229569Y828781D03*
X228519Y823761D03*
Y833800D03*
X217827Y843840D03*
Y850533D03*
X229569Y865592D03*
X228519Y860572D03*
X217827Y857226D03*
X228519Y870611D03*
X217827Y880651D03*
Y887344D03*
Y894037D03*
X229569Y902403D03*
X228519Y897383D03*
Y907423D03*
X217827Y917462D03*
Y924155D03*
X229569Y939214D03*
X228519Y934194D03*
X217827Y930848D03*
X228519Y944234D03*
X217827Y954273D03*
Y960966D03*
Y967659D03*
Y974352D03*
Y981045D03*
Y987737D03*
Y994430D03*
Y1004470D03*
Y1034588D03*
Y1041281D03*
Y1047974D03*
Y1054667D03*
Y1061360D03*
Y1071399D03*
X229569Y1086458D03*
X228519Y1081438D03*
X217827Y1078092D03*
Y1101517D03*
X228519Y1091478D03*
Y1118249D03*
X217827Y1108210D03*
Y1114903D03*
X229569Y1123269D03*
X228519Y1128289D03*
X217827Y1138328D03*
Y1145021D03*
X229569Y1160080D03*
X228519Y1155060D03*
Y1165100D03*
X217827Y1151714D03*
Y1175139D03*
X228519Y1191871D03*
X217827Y1181832D03*
Y1188525D03*
X229569Y1196891D03*
X228519Y1201911D03*
X217827Y1211950D03*
Y1218643D03*
X229569Y1233702D03*
X228519Y1228682D03*
Y1238722D03*
X217827Y1225336D03*
Y1248761D03*
Y1255454D03*
X224481Y1326418D03*
X221881D03*
X224481Y1323918D03*
X221881Y1321418D03*
X224481D03*
X221881Y1323918D03*
X230171Y1323904D03*
Y1321404D03*
X227871Y1338124D03*
X223941Y1338068D03*
X221341D03*
X230661Y1338124D03*
X224691Y1354871D03*
Y1352271D03*
X223441Y1357371D03*
X222091Y1354871D03*
Y1352271D03*
X218421Y1357425D03*
X224691Y1349671D03*
X222091D03*
X219367Y1360456D03*
Y1363413D03*
X231347Y1361417D03*
X228892Y1384789D03*
X230550Y1386740D03*
X228693Y1408885D03*
X224881Y1410685D03*
X220803Y1412115D03*
X217097Y1413863D03*
X227051Y1452895D03*
X220351Y1462595D03*
X228961Y1450295D03*
Y1455495D03*
X227041Y1459995D03*
X222261D03*
X220341Y1469695D03*
Y1474895D03*
X227041Y1465195D03*
X222261D03*
X226050Y1550897D03*
X221325Y1550797D03*
X230774Y1550897D03*
X228524Y1594876D03*
X223568D03*
Y1589884D03*
X228524D03*
X222494Y1604876D03*
X217538D03*
X222494Y1599884D03*
X217538D03*
X229598Y1604876D03*
Y1599884D03*
Y1611796D03*
X217538D03*
X222494D03*
X229598Y1616788D03*
X217538D03*
X222494D03*
X223568Y1626788D03*
X228524D03*
X223568Y1621796D03*
X228524D03*
X243486Y23005D03*
X244296Y59765D03*
X242251Y162515D03*
X246250Y204360D03*
X233438Y593556D03*
X236638D03*
X233456Y601598D03*
X236656D03*
X236674Y609640D03*
X233474D03*
X233969Y773564D03*
Y780257D03*
Y803682D03*
Y810375D03*
Y817068D03*
Y840493D03*
Y847186D03*
Y853879D03*
Y877304D03*
Y883997D03*
Y890690D03*
Y914115D03*
Y920808D03*
Y927501D03*
Y950926D03*
Y957619D03*
Y964312D03*
Y971005D03*
Y977698D03*
Y984391D03*
Y991084D03*
Y997777D03*
Y1004470D03*
Y1031241D03*
Y1037934D03*
Y1044627D03*
Y1051320D03*
Y1058013D03*
Y1068052D03*
Y1074745D03*
Y1098171D03*
Y1104863D03*
Y1111556D03*
Y1134982D03*
Y1141675D03*
Y1148367D03*
Y1171793D03*
Y1178486D03*
Y1185178D03*
Y1208604D03*
Y1215297D03*
Y1221989D03*
Y1245415D03*
Y1252108D03*
X232961Y1323904D03*
Y1321404D03*
X239561Y1338124D03*
X243677Y1357409D03*
X241077D03*
X238477D03*
X235877D03*
X246277D03*
X242581Y1367272D03*
X240151D03*
X243677Y1363473D03*
X241077D03*
Y1360516D03*
X243677D03*
X242581Y1372872D03*
X240151D03*
X237721D03*
Y1367272D03*
X238477Y1360516D03*
X235877D03*
X242630Y1385287D03*
X233194Y1407349D03*
X233741Y1450295D03*
Y1455495D03*
X240451Y1472295D03*
X242361Y1469695D03*
Y1474895D03*
X235499Y1550897D03*
X240223D03*
X244947Y1550697D03*
X240584Y1594876D03*
X235628D03*
Y1589884D03*
X240584D03*
X246614Y1604876D03*
Y1599884D03*
X234554Y1604876D03*
Y1599884D03*
X241658Y1604876D03*
Y1599884D03*
X246614Y1611796D03*
X241658D03*
X234554D03*
X246614Y1616788D03*
X241658D03*
X234554D03*
X235628Y1626788D03*
X240584D03*
X235628Y1621796D03*
X240584D03*
X251928Y3001D03*
X247716Y75865D03*
Y71865D03*
X251793Y100846D03*
X261383Y133786D03*
X258253D03*
X249735Y152694D03*
X254095Y209235D03*
X254671Y642138D03*
X258470Y775410D03*
X260671Y1338124D03*
X258071D03*
X247725Y1338141D03*
X257491Y1352271D03*
X256241Y1357371D03*
X257491Y1354871D03*
X254891Y1352271D03*
Y1354871D03*
X251221Y1357425D03*
X248777Y1357409D03*
X257491Y1349671D03*
X254891D03*
X252167Y1363413D03*
Y1360456D03*
X253851Y1452895D03*
X247151Y1462595D03*
X260541Y1450295D03*
X255761D03*
X260541Y1455495D03*
X255761D03*
X253841Y1459995D03*
X249061D03*
X253841Y1465195D03*
X249061D03*
X247141Y1469695D03*
Y1474895D03*
X259120Y1550797D03*
X254396Y1550897D03*
X249671D03*
X259748Y1594876D03*
X247688D03*
X252644D03*
X247688Y1589884D03*
X259748D03*
X252644D03*
X253718Y1604876D03*
X258674D03*
X253718Y1599884D03*
X258674D03*
Y1611796D03*
X253718D03*
X258674Y1616788D03*
X253718D03*
X252644Y1626788D03*
X259748D03*
X252644Y1621796D03*
X259748D03*
X247688Y1626788D03*
Y1621796D03*
X273928Y3001D03*
X272596Y27185D03*
X263276Y34625D03*
X271596Y40165D03*
X270364Y118415D03*
X272361Y120243D03*
X264574Y159206D03*
Y155206D03*
X267500Y220441D03*
X265100Y595078D03*
X270905Y608485D03*
X273905D03*
Y611485D03*
X272603Y692910D03*
Y695510D03*
X271491Y1291740D03*
X274091D03*
X272077Y1314370D03*
X269477D03*
X274677D03*
X272077Y1311263D03*
X269477D03*
X274677D03*
X271321Y1326726D03*
Y1321126D03*
X276181Y1326726D03*
X273751D03*
X274677Y1317327D03*
X264947Y1315271D03*
X276181Y1321126D03*
X273751D03*
X276230Y1339141D03*
X264085Y1339175D03*
X267251Y1452895D03*
X273941Y1450295D03*
X269161D03*
X273941Y1455495D03*
X269161D03*
X276637Y1523953D03*
X270139Y1548563D03*
X271808Y1594876D03*
X264704D03*
X271808Y1589884D03*
X264704D03*
X265778Y1604876D03*
X270734D03*
X265778Y1599790D03*
X270734D03*
Y1611796D03*
X265778D03*
X270734Y1616788D03*
X265778D03*
X271808Y1626788D03*
Y1621796D03*
X264704Y1626788D03*
Y1621796D03*
X291000Y14820D03*
X285896Y23965D03*
X291156Y21395D03*
X286716Y40020D03*
X285499Y53191D03*
X278989Y48720D03*
X286076D03*
X283949Y152506D03*
X288516Y157065D03*
X285260Y234000D03*
X279500Y234075D03*
X290865Y609470D03*
X277105Y608485D03*
X280305D03*
X277105Y611485D03*
X280305D03*
X286665Y609470D03*
X283705Y608485D03*
X284705Y605485D03*
X283705Y611485D03*
X287832Y674150D03*
X283921Y1291740D03*
X281321D03*
X284821Y1311279D03*
X282377Y1311263D03*
X279877D03*
X277277Y1314370D03*
Y1311263D03*
X288491Y1306125D03*
Y1308725D03*
X291091Y1306125D03*
Y1308725D03*
X288491Y1303525D03*
X291091D03*
X289841Y1311225D03*
X285767Y1314310D03*
Y1317267D03*
X277277Y1317327D03*
X283946Y1530595D03*
X286446D03*
X288824Y1594876D03*
X276764D03*
X283868D03*
Y1589884D03*
X276764D03*
X288824D03*
X277838Y1604876D03*
X282794D03*
X277838Y1599884D03*
X282794D03*
X289898Y1604876D03*
Y1599884D03*
Y1611796D03*
X282794D03*
X277838D03*
X289898Y1616788D03*
X282794D03*
X277838D03*
X283868Y1626788D03*
X288824D03*
X283868Y1621796D03*
X288824D03*
X276764Y1626788D03*
Y1621796D03*
X295928Y3001D03*
X296272Y69128D03*
X293443Y78576D03*
X293448Y82486D03*
Y85986D03*
X303043Y79376D03*
X299943Y79276D03*
X299653Y92506D03*
X299628Y149203D03*
X299624Y158706D03*
X294553Y153819D03*
X293000Y216500D03*
X294165Y609570D03*
X297838Y609585D03*
X300965Y609570D03*
X304449D03*
X305121Y726348D03*
X298991D03*
X294541Y1291378D03*
X291941D03*
X302373Y1314342D03*
X304973D03*
X302373Y1311235D03*
X304973D03*
X304217Y1326698D03*
Y1321098D03*
X297843Y1315243D03*
X295388Y1338615D03*
X297046Y1340566D03*
X305199Y1398269D03*
Y1400769D03*
X295116Y1398132D03*
Y1400632D03*
X292516D03*
Y1398132D03*
X301513Y1452895D03*
X294813Y1462595D03*
X303423Y1450295D03*
Y1455495D03*
X301503Y1459995D03*
X296723D03*
X301503Y1465195D03*
X296723D03*
X299950Y1499500D03*
X301550Y1518040D03*
Y1514420D03*
Y1510800D03*
X302042Y1528731D03*
X300884Y1594876D03*
X295928D03*
Y1589884D03*
X300884D03*
X294854Y1604876D03*
Y1599884D03*
X301958Y1604876D03*
Y1599884D03*
Y1611796D03*
X294854D03*
X301958Y1616788D03*
X294854D03*
X295928Y1626788D03*
X300884D03*
X295928Y1621796D03*
X300884D03*
X317928Y3001D03*
X306716Y39985D03*
X320053Y85806D03*
Y88806D03*
X310425Y243925D03*
X317240Y252970D03*
X308925Y260075D03*
X307865Y609570D03*
X311349Y609632D03*
X313961Y607088D03*
Y604588D03*
X319657Y696415D03*
X319621Y1291740D03*
X321387Y1306097D03*
Y1308697D03*
Y1303497D03*
X317717Y1311251D03*
X315273Y1311235D03*
X312773D03*
X307573Y1314342D03*
Y1311235D03*
X310173Y1314342D03*
Y1311235D03*
X318663Y1314282D03*
X309077Y1321098D03*
X306647D03*
X318663Y1317239D03*
X309077Y1326698D03*
X306647D03*
X307573Y1317299D03*
X310173D03*
X309126Y1339113D03*
X307799Y1400769D03*
Y1398269D03*
X318199Y1400549D03*
X314199D03*
X310399D03*
X308203Y1450295D03*
Y1455495D03*
X314913Y1472295D03*
X316823Y1469695D03*
Y1474895D03*
X321040Y1550797D03*
X316316D03*
X320048Y1594876D03*
X307988D03*
X312944D03*
X307988Y1589884D03*
X320048D03*
X312944D03*
X306914Y1604876D03*
Y1599884D03*
X314018Y1604876D03*
X318974D03*
X314018Y1599884D03*
X318974D03*
Y1611796D03*
X314018D03*
X306914D03*
X318974Y1616788D03*
X314018D03*
X306914D03*
X320048Y1626788D03*
X312944D03*
X320048Y1621796D03*
X312944D03*
X307988Y1626788D03*
Y1621796D03*
X329535Y49379D03*
X331000Y270260D03*
X328966Y543012D03*
X334744Y566086D03*
X333500Y582500D03*
Y578500D03*
X333988Y590633D03*
X329471Y1291778D03*
X322221Y1291740D03*
X326761Y1291778D03*
X335277Y1314285D03*
Y1311178D03*
X323987Y1303497D03*
Y1306097D03*
Y1308697D03*
X322737Y1311197D03*
X330747Y1315186D03*
X328292Y1338558D03*
X329950Y1340509D03*
X333830Y1396299D03*
Y1398899D03*
Y1401499D03*
Y1393799D03*
X324309Y1396599D03*
Y1399199D03*
Y1401799D03*
Y1394099D03*
X321999Y1400549D03*
X321613Y1462595D03*
X323523Y1459995D03*
X328303D03*
X328313Y1452895D03*
X335003Y1450295D03*
X330223D03*
X335003Y1455495D03*
X330223D03*
X328313Y1472295D03*
X323523Y1465195D03*
X328303D03*
X321603Y1469695D03*
Y1474895D03*
X325765Y1550897D03*
X330489Y1550697D03*
X335214Y1550897D03*
X332108Y1594876D03*
X325004D03*
X332108Y1589884D03*
X325004D03*
X326078Y1604876D03*
X331034D03*
X326078Y1599884D03*
X331034D03*
Y1611796D03*
X326078D03*
X331034Y1616788D03*
X326078D03*
X332108Y1626788D03*
X325004D03*
X332108Y1621796D03*
X325004D03*
X343036Y122525D03*
X342075Y287925D03*
X351157Y562415D03*
X345500Y574415D03*
X351157D03*
X338664Y699660D03*
X337030Y697750D03*
X340477Y1314285D03*
X337877D03*
Y1311178D03*
X340477D03*
X350621Y1311194D03*
X348177Y1311178D03*
X343077Y1314285D03*
X345677Y1311178D03*
X343077D03*
X341981Y1321041D03*
X339551D03*
X341981Y1326641D03*
X337121Y1321041D03*
X339551Y1326641D03*
X337121D03*
X340477Y1317242D03*
X343077D03*
X342030Y1339056D03*
X347110Y1398312D03*
X351110D03*
X341760Y1401449D03*
X337760D03*
X349760D03*
X345760D03*
X348413Y1462595D03*
X350323Y1459995D03*
X341713Y1472295D03*
X350323Y1465195D03*
X348403Y1469695D03*
X343623D03*
X348403Y1474895D03*
X343623D03*
X339938Y1550897D03*
X349387Y1550797D03*
X344663Y1550697D03*
X349124Y1594876D03*
X337064D03*
X344168D03*
Y1589884D03*
X337064D03*
X349124D03*
X338138Y1604876D03*
X343094D03*
X338138Y1599884D03*
X343094D03*
X350198Y1604876D03*
Y1599884D03*
Y1611796D03*
X343094D03*
X338138D03*
X350198Y1616788D03*
X343094D03*
X338138D03*
X344168Y1626788D03*
X349124D03*
X344168Y1621796D03*
X349124D03*
X337064Y1626788D03*
Y1621796D03*
X351535Y49379D03*
X366874Y135157D03*
X366771Y127665D03*
X359734Y288768D03*
X360433Y294030D03*
X355832Y297855D03*
X353700Y547893D03*
X356850D03*
X365593Y621622D03*
X364788Y1193918D03*
X364457Y1188109D03*
X359541Y1291918D03*
X362311Y1291968D03*
X356551Y1291880D03*
X353951D03*
X356891Y1306040D03*
Y1308640D03*
Y1303440D03*
X354291Y1306040D03*
Y1308640D03*
Y1303440D03*
X355641Y1311140D03*
X351567Y1314225D03*
Y1317182D03*
X363547Y1315386D03*
X361092Y1338758D03*
X362750Y1340709D03*
X355110Y1398312D03*
X359110D03*
X363110D03*
X357760Y1401449D03*
X353760D03*
X355113Y1452895D03*
X361803Y1450295D03*
X357023D03*
X361803Y1455495D03*
X357023D03*
X355103Y1459995D03*
Y1465195D03*
X354112Y1550897D03*
X358836D03*
X363561D03*
X361184Y1594876D03*
X356228D03*
Y1589884D03*
X361184D03*
X355154Y1604876D03*
Y1599884D03*
X362258Y1604876D03*
Y1599790D03*
Y1611796D03*
X355154D03*
X362258Y1616788D03*
X355154D03*
X356228Y1626788D03*
X361184D03*
X356228Y1621796D03*
X361184D03*
X373535Y49379D03*
X375920Y146577D03*
X380012Y243615D03*
X379200Y298772D03*
X367902Y303760D03*
X380771Y524903D03*
X375943D03*
X371724Y699450D03*
X370090Y697482D03*
X372000Y816862D03*
Y826362D03*
Y828862D03*
Y837862D03*
Y840362D03*
Y849362D03*
X378083Y1184949D03*
X367782Y1199648D03*
X380977Y1311378D03*
X375877Y1314485D03*
X378477Y1311378D03*
X375877D03*
X370677Y1314485D03*
X368077D03*
X373277D03*
X368077Y1311378D03*
X370677D03*
X373277D03*
X375877Y1317442D03*
X372351Y1326841D03*
X369921D03*
Y1321241D03*
X374781Y1326841D03*
X373277Y1317442D03*
X374781Y1321241D03*
X372351D03*
X374830Y1339256D03*
X379610Y1391781D03*
X375056Y1393741D03*
X375213Y1462595D03*
X377123Y1459995D03*
X368513Y1472295D03*
X377123Y1465195D03*
X375203Y1469695D03*
X370423D03*
X375203Y1474895D03*
X370423D03*
X368285Y1550897D03*
X373009Y1550697D03*
X377733Y1550897D03*
X368288Y1594876D03*
X373244D03*
X368288Y1589884D03*
X373244D03*
X367214Y1604876D03*
Y1599790D03*
X374318Y1604876D03*
X379274D03*
X374318Y1599884D03*
X379274D03*
Y1611796D03*
X374318D03*
X367214D03*
X379274Y1616788D03*
X374318D03*
X367214D03*
X373244Y1626788D03*
Y1621796D03*
X368288Y1626788D03*
Y1621796D03*
X372313Y1641759D03*
X379895Y1670046D03*
X372350Y1683284D03*
X385024Y-17575D03*
X381771Y-17589D03*
X388049Y-18895D03*
X381756Y-20104D03*
X385009Y-20090D03*
X381725Y-14717D03*
X385008Y-9673D03*
X385023Y-7158D03*
X381755Y-9687D03*
X388048Y-8478D03*
X381770Y-7172D03*
X381740Y-12202D03*
X395535Y49379D03*
X391600Y121178D03*
X387712Y147441D03*
X384600Y221800D03*
X386563Y280370D03*
X387184Y470495D03*
X387440Y525154D03*
X395657Y546894D03*
X391657Y546816D03*
X387657Y546876D03*
X384500Y810862D03*
X384499Y819862D03*
X388361Y1293713D03*
X385701Y1291828D03*
X392176Y1309859D03*
X394951Y1311259D03*
X389691Y1306240D03*
Y1308840D03*
X387091Y1306240D03*
Y1308840D03*
X389691Y1303640D03*
X387091D03*
X383421Y1311394D03*
X388441Y1311340D03*
X384367Y1314425D03*
Y1317382D03*
X392950Y1315280D03*
X392910Y1317880D03*
X395267Y1358621D03*
X393321Y1385630D03*
X388718Y1387386D03*
X384270Y1389875D03*
X395313Y1452895D03*
X381913D03*
X383823Y1450295D03*
X388603D03*
X383823Y1455495D03*
X388603D03*
X381903Y1459995D03*
Y1465195D03*
X382458Y1550897D03*
X387182Y1550797D03*
X393322Y1573347D03*
X394915Y1590018D03*
X387805Y1607802D03*
Y1604802D03*
Y1610802D03*
X387325Y1627212D03*
X385502Y1667154D03*
X394824Y1667120D03*
X389824D03*
X403734Y110326D03*
Y118976D03*
X397426Y112815D03*
Y116215D03*
X402606Y129465D03*
Y126065D03*
X403141Y144300D03*
X396237Y315507D03*
X399657Y546915D03*
X401880Y696220D03*
X404771Y698670D03*
X396129Y1334717D03*
X408459Y1330709D03*
X405859D03*
X400659D03*
X403259D03*
X408459Y1333816D03*
X405859D03*
X403259D03*
X400659D03*
X408459Y1336773D03*
X405859D03*
X402503Y1340572D03*
X407363D03*
X404933D03*
X407412Y1358587D03*
X407363Y1346172D03*
X404933D03*
X402503D03*
X410002Y1375093D03*
X405978Y1377794D03*
X401953Y1380494D03*
X397187Y1383354D03*
X397223Y1450295D03*
X402003D03*
X397223Y1455495D03*
X402003D03*
X401583Y1504872D03*
X404699Y1523953D03*
X398201Y1548563D03*
X410672Y1561170D03*
X400905Y1596091D03*
X403417Y1606224D03*
X403848Y1615354D03*
X400623Y1629772D03*
X406075Y1641000D03*
X399824Y1667120D03*
X409000Y1667025D03*
X405000Y1683500D03*
X401666Y1677925D03*
X417535Y49379D03*
X413949Y69270D03*
X414486Y127579D03*
Y124179D03*
X423521Y1311969D03*
X421091Y1311219D03*
X419673Y1325571D03*
Y1322971D03*
Y1328171D03*
X422273Y1322971D03*
Y1325571D03*
Y1328171D03*
X416949Y1336713D03*
Y1333756D03*
X424333Y1331447D03*
X411059Y1330709D03*
X416003Y1330725D03*
X413559Y1330709D03*
X421023Y1330671D03*
X414132Y1372234D03*
X415862Y1503715D03*
X422557Y1530595D03*
X420057D03*
X421059Y1569168D03*
X416163Y1594450D03*
X422007Y1592330D03*
X413100Y1607600D03*
X418293Y1607495D03*
X423379Y1607675D03*
X413200Y1612700D03*
X423439Y1612407D03*
X411515Y1599649D03*
X413100Y1617900D03*
X418500Y1618000D03*
X423349Y1617857D03*
X416962Y1634123D03*
X415437Y1636382D03*
X417365Y1630495D03*
X420765D03*
X421347Y1636668D03*
X411500Y1653500D03*
X417441Y1643946D03*
X420000Y1668075D03*
X417000Y1683500D03*
X439535Y49379D03*
X430564Y56348D03*
X430500Y72900D03*
X436090Y128007D03*
X440090Y132007D03*
X433124Y222253D03*
Y225205D03*
X439500Y484000D03*
X439284Y1038766D03*
Y1042766D03*
X431830Y1311240D03*
X438561Y1321622D03*
X432561D03*
X435561D03*
X437624Y1452895D03*
X430924Y1462595D03*
X439534Y1450295D03*
Y1455495D03*
X437614Y1459995D03*
X432834D03*
X437614Y1465195D03*
X432834D03*
X436140Y1499320D03*
X437661Y1518040D03*
Y1514420D03*
Y1510800D03*
X438153Y1528731D03*
X430239Y1581726D03*
X426688Y1598003D03*
X439283Y1608704D03*
X432559Y1627500D03*
X439404Y1615146D03*
X428000Y1640500D03*
X450102Y87011D03*
X450414Y92384D03*
X443014D03*
X452090Y116007D03*
Y124007D03*
Y132007D03*
Y128007D03*
X445997Y170701D03*
X453783Y217646D03*
X441320Y304170D03*
Y310170D03*
X449760Y497240D03*
X448688Y1305947D03*
X449440Y1308386D03*
X450220Y1310834D03*
X451083Y1313347D03*
X441561Y1321622D03*
X444561D03*
X452089Y1316074D03*
X452936Y1318775D03*
X453823Y1321436D03*
X454603Y1324033D03*
X454909Y1326721D03*
X444314Y1450295D03*
Y1455495D03*
X451024Y1472295D03*
X452934Y1469695D03*
Y1474895D03*
X452427Y1550797D03*
X440846Y1576526D03*
X451561Y1589884D03*
Y1594876D03*
X444128Y1604200D03*
Y1600200D03*
X451561Y1621796D03*
Y1626788D03*
X448776Y1622266D03*
Y1617166D03*
Y1619766D03*
X452500Y1637559D03*
X447387Y1641441D03*
X454099Y1649575D03*
X461535Y49379D03*
X457502Y87011D03*
X464456Y93101D03*
X457056D03*
X464051Y224799D03*
X460624Y244103D03*
X465925Y489925D03*
X457724Y1462595D03*
X459634Y1459995D03*
X464414D03*
X466334Y1450295D03*
X464424Y1452895D03*
X466334Y1455495D03*
X459634Y1465195D03*
X464414D03*
X457714Y1469695D03*
Y1474895D03*
X461876Y1550897D03*
X457151Y1550797D03*
X466600Y1550697D03*
X468577Y1589884D03*
Y1594876D03*
X456517Y1589884D03*
X463621D03*
Y1594876D03*
X456517D03*
X457591Y1599884D03*
X462547D03*
Y1604876D03*
X457591D03*
X462547Y1611796D03*
X457591D03*
X469651D03*
Y1599884D03*
Y1604876D03*
X462547Y1616788D03*
X457591D03*
X469651D03*
X468577Y1621796D03*
Y1626788D03*
X463621Y1621796D03*
Y1626788D03*
X456517Y1621796D03*
Y1626788D03*
X457240Y1629500D03*
X462500Y1655500D03*
X468350Y1645351D03*
X461000Y1650000D03*
X470309Y1689000D03*
X470500Y1674075D03*
X462500Y1701000D03*
X468500Y1708500D03*
X467416Y1724808D03*
X469975D03*
X464734Y1730518D03*
X483535Y49379D03*
X478949Y60029D03*
Y55135D03*
Y64975D03*
X470895Y128020D03*
X478295D03*
X482255Y127322D03*
Y135722D03*
X479630Y141942D03*
X471371Y231764D03*
X477203Y1015474D03*
X484784D03*
X477203Y1019017D03*
X484784D03*
X477203Y1022560D03*
X484784D03*
X484524Y1462595D03*
X471114Y1450295D03*
Y1455495D03*
X477824Y1472295D03*
X484514Y1469695D03*
X479734D03*
X484514Y1474895D03*
X479734D03*
X480774Y1550697D03*
X476049Y1550897D03*
X471325D03*
X480637Y1589884D03*
Y1594876D03*
X475681D03*
Y1589884D03*
X481711Y1611796D03*
Y1599884D03*
Y1604876D03*
X474607Y1611796D03*
Y1599884D03*
Y1604876D03*
X481711Y1616788D03*
X474607D03*
X475681Y1621796D03*
X480637D03*
X475681Y1626788D03*
X480637D03*
X478500Y1655500D03*
X476000Y1680000D03*
X478500Y1701000D03*
Y1714500D03*
X487590Y105969D03*
X494810D03*
X492300Y121389D03*
X487880Y131442D03*
X496280D03*
X492300Y124389D03*
X488580Y141942D03*
X494200Y158800D03*
X488260Y418980D03*
X488405Y578572D03*
X492284Y1015474D03*
Y1019017D03*
Y1022560D03*
X491224Y1452895D03*
X497914Y1450295D03*
X493134D03*
X497914Y1455495D03*
X493134D03*
X486434Y1459995D03*
X491214D03*
X486434Y1465195D03*
X491214D03*
X485498Y1550797D03*
X490223Y1550897D03*
X494947D03*
X499672D03*
X499801Y1594876D03*
X492697Y1589884D03*
X487741Y1594876D03*
X492697D03*
X499801Y1589884D03*
X487741D03*
X498727Y1611796D03*
Y1599884D03*
Y1604876D03*
X486667Y1611796D03*
X493771D03*
Y1599884D03*
Y1604876D03*
X486667Y1599884D03*
Y1604876D03*
X498727Y1616788D03*
X499801Y1621796D03*
Y1626788D03*
X486667Y1616788D03*
X493771D03*
X492697Y1621796D03*
X487741D03*
X492697Y1626788D03*
X487741D03*
X510815Y69562D03*
X502815Y106984D03*
X512654Y94967D03*
X500836Y119092D03*
X511140Y109829D03*
X511170Y224930D03*
Y227882D03*
X501500Y433000D03*
X511324Y1462595D03*
X513234Y1459995D03*
X504624Y1472295D03*
X513234Y1465195D03*
X511314Y1469695D03*
X506534D03*
X511314Y1474895D03*
X506534D03*
X513844Y1550897D03*
X509120Y1550697D03*
X504396Y1550897D03*
X511861Y1594876D03*
X504757Y1589884D03*
Y1594876D03*
X511861Y1589884D03*
X505831Y1611796D03*
X510787D03*
X505831Y1599884D03*
Y1604876D03*
X510787Y1599884D03*
Y1604876D03*
X511861Y1621796D03*
Y1626788D03*
X505831Y1616788D03*
X510787D03*
X504757Y1621796D03*
Y1626788D03*
X518843Y23788D03*
X517907Y69507D03*
X524993D03*
X516020Y102870D03*
X519240Y94967D03*
X521420Y109829D03*
X516020Y111770D03*
X518418Y137171D03*
X522831Y443712D03*
X518024Y1452895D03*
X519934Y1450295D03*
X524714D03*
X519934Y1455495D03*
X524714D03*
X518014Y1459995D03*
Y1465195D03*
X523293Y1550797D03*
X518569Y1550897D03*
X528940Y1548260D03*
X528877Y1589884D03*
Y1594876D03*
X516817Y1589884D03*
Y1594876D03*
X523921D03*
Y1589884D03*
X529951Y1611796D03*
Y1599790D03*
Y1604876D03*
X517891Y1611796D03*
X522847D03*
Y1599884D03*
X517891D03*
X522847Y1604876D03*
X517891D03*
X529951Y1616788D03*
X528877Y1621796D03*
Y1626788D03*
X517891Y1616788D03*
X522847D03*
X523921Y1621796D03*
X516817D03*
X523921Y1626788D03*
X516817D03*
X540843Y23788D03*
X542723Y39562D03*
X532080Y69507D03*
X539166D03*
X535170Y108730D03*
Y117630D03*
X533097Y246780D03*
X532000Y426500D03*
X544844Y439701D03*
X543500Y463500D03*
X540106Y657325D03*
X531424Y1452895D03*
X533334Y1450295D03*
X538114D03*
X533334Y1455495D03*
X538114D03*
X544814Y1459995D03*
X540810Y1523953D03*
X540937Y1589884D03*
Y1594876D03*
X535981D03*
Y1589884D03*
X542011Y1611796D03*
Y1599884D03*
Y1604876D03*
X534907Y1611796D03*
Y1599790D03*
Y1604876D03*
X542011Y1616788D03*
X540937Y1621796D03*
Y1626788D03*
X534907Y1616788D03*
X535981Y1621796D03*
Y1626788D03*
X548610Y57990D03*
X546253Y69507D03*
X553340D03*
X545935Y77516D03*
X553821D03*
X546400Y120700D03*
X553780Y118740D03*
Y127140D03*
X547196Y195256D03*
X546800Y262800D03*
X548856Y440452D03*
X556993Y616406D03*
X550993D03*
X553993D03*
X547993D03*
X558986Y1462595D03*
X545931Y1451344D03*
X559090Y1452185D03*
X548119Y1530595D03*
X550619D03*
X552997Y1589884D03*
X548041Y1594876D03*
X552997D03*
X548041Y1589884D03*
X559027Y1611796D03*
Y1599884D03*
Y1604876D03*
X546967Y1611796D03*
X554071D03*
Y1599884D03*
Y1604876D03*
X546967Y1599884D03*
Y1604876D03*
X559027Y1616788D03*
X546967D03*
X554071D03*
X552997Y1621796D03*
Y1626788D03*
X548041D03*
Y1621796D03*
X562843Y23788D03*
X560426Y69507D03*
X570860Y118310D03*
X565210Y125819D03*
X570860Y127510D03*
X564603Y197778D03*
Y200304D03*
X573911Y212196D03*
X569004Y228571D03*
X563230Y426508D03*
X563575Y448425D03*
X569464Y462140D03*
X559993Y616406D03*
X561580Y1242740D03*
X565686Y1452895D03*
X567596Y1450295D03*
X572376D03*
X567596Y1455495D03*
X572376D03*
X565676Y1459995D03*
X560896D03*
X565676Y1465195D03*
X560896D03*
X562860Y1499360D03*
X565723Y1510800D03*
Y1514420D03*
Y1518040D03*
X566215Y1528731D03*
X572161Y1594876D03*
X565057Y1589884D03*
X560101Y1594876D03*
X565057D03*
X572161Y1589884D03*
X560101D03*
X571087Y1611796D03*
Y1599884D03*
Y1604876D03*
X566131Y1611796D03*
Y1599884D03*
Y1604876D03*
X571087Y1616788D03*
X572161Y1621796D03*
Y1626788D03*
X566131Y1616788D03*
X565057Y1621796D03*
X560101D03*
X565057Y1626788D03*
X560101D03*
X584843Y23788D03*
X580098Y96439D03*
X576510Y125819D03*
X588554Y221277D03*
X577859Y212196D03*
X588554Y229277D03*
X575917Y421390D03*
X583505Y457925D03*
X587812Y474353D03*
X577801Y466000D03*
X578830Y1238075D03*
X578071Y1244425D03*
X588630Y1255075D03*
X583630D03*
X585786Y1462595D03*
X587696Y1459995D03*
X579086Y1472295D03*
X587696Y1465195D03*
X580996Y1469695D03*
X585776D03*
X580996Y1474895D03*
X585776D03*
X585213Y1550797D03*
X580489D03*
X589177Y1589884D03*
Y1594876D03*
X577117Y1589884D03*
Y1594876D03*
X584221D03*
Y1589884D03*
X578191Y1611796D03*
X583147D03*
Y1599884D03*
X578191D03*
X583147Y1604876D03*
X578191D03*
X589177Y1621796D03*
Y1626788D03*
X578191Y1616788D03*
X583147D03*
X584221Y1621796D03*
X577117D03*
X584221Y1626788D03*
X577117D03*
X603379Y70512D03*
X594430Y463600D03*
X592612Y805986D03*
X594330Y1238075D03*
X595671Y1245688D03*
X595598Y1251075D03*
X599659Y1241734D03*
X603947Y1258575D03*
X595947D03*
X592476Y1459995D03*
X594396Y1450295D03*
X599176D03*
X592486Y1452895D03*
X594396Y1455495D03*
X599176D03*
X592476Y1465195D03*
X599387Y1550897D03*
X604111D03*
X589938D03*
X594662Y1550697D03*
X601237Y1589884D03*
Y1594876D03*
X596281D03*
Y1589884D03*
X602311Y1611796D03*
Y1599884D03*
Y1604876D03*
X590251Y1611796D03*
X595207D03*
Y1599884D03*
X590251D03*
X595207Y1604876D03*
X590251D03*
X602311Y1616788D03*
X601237Y1621796D03*
Y1626788D03*
X590251Y1616788D03*
X595207D03*
X596281Y1621796D03*
Y1626788D03*
X606843Y23788D03*
X615190Y70533D03*
X607834Y222611D03*
X612414Y227041D03*
X605796Y425585D03*
X612969Y447260D03*
X616171Y780364D03*
X606559Y796116D03*
X612871Y1248488D03*
X612947Y1252075D03*
X609159Y1240234D03*
X612447Y1258575D03*
X616527Y1390732D03*
X619286Y1452895D03*
X612586Y1462595D03*
X614496Y1459995D03*
X619276D03*
X605886Y1472295D03*
X614496Y1465195D03*
X619276D03*
X612576Y1469695D03*
X607796D03*
X612576Y1474895D03*
X607796D03*
X613560Y1550797D03*
X618285Y1550897D03*
X608836Y1550697D03*
X613297Y1589884D03*
X608341Y1594876D03*
X613297D03*
X608341Y1589884D03*
X619327Y1611796D03*
Y1599884D03*
Y1604876D03*
X607267Y1611796D03*
X614371D03*
Y1599884D03*
Y1604876D03*
X607267Y1599884D03*
Y1604876D03*
X619327Y1616788D03*
X607267D03*
X614371D03*
X613297Y1621796D03*
X608341D03*
X613297Y1626788D03*
X608341D03*
X628843Y23788D03*
X625574Y150177D03*
X623605Y219277D03*
Y228777D03*
X624760Y424569D03*
X621916Y465088D03*
X632996Y478309D03*
X621309Y483346D03*
X634288Y766646D03*
X625976Y1450295D03*
X621196D03*
X625976Y1455495D03*
X621196D03*
X632686Y1472295D03*
X632458Y1550897D03*
X623009D03*
X627734D03*
X632461Y1594876D03*
X625357Y1589884D03*
X620401Y1594876D03*
X625357D03*
X632461Y1589884D03*
X620401D03*
X631387Y1611796D03*
Y1599790D03*
Y1604876D03*
X626431Y1611796D03*
Y1599790D03*
Y1604876D03*
X631387Y1616788D03*
X632461Y1626788D03*
Y1621796D03*
X626431Y1616788D03*
X620401Y1621796D03*
X625357D03*
X620401Y1626788D03*
X625357D03*
X627958Y1654114D03*
X645151Y69507D03*
X642394Y131172D03*
X642481Y184862D03*
X643012Y201913D03*
Y199313D03*
X635200Y415425D03*
X644673Y425816D03*
X637504Y454352D03*
X636614Y512597D03*
X647354Y776911D03*
Y783604D03*
Y807029D03*
Y813722D03*
Y820415D03*
Y843840D03*
Y850533D03*
Y857226D03*
Y880651D03*
Y887344D03*
Y894037D03*
Y917462D03*
Y924155D03*
Y930848D03*
Y954273D03*
Y960966D03*
Y967659D03*
Y974352D03*
Y981045D03*
Y987737D03*
Y994430D03*
Y1004470D03*
Y1034588D03*
Y1041281D03*
Y1047974D03*
Y1054667D03*
Y1061360D03*
Y1071399D03*
Y1078092D03*
Y1101517D03*
Y1108210D03*
Y1114903D03*
Y1138328D03*
Y1145021D03*
Y1151714D03*
Y1175139D03*
Y1181832D03*
Y1188525D03*
Y1211950D03*
Y1218643D03*
Y1225336D03*
Y1248761D03*
Y1255454D03*
X642436Y1350877D03*
X646236D03*
X638436D03*
X643563Y1392581D03*
X647445Y1392605D03*
X646086Y1452895D03*
X639386Y1462595D03*
X647996Y1450295D03*
Y1455495D03*
X641296Y1459995D03*
X646076D03*
X641296Y1465195D03*
X646076D03*
X639376Y1469695D03*
X634596D03*
X639376Y1474895D03*
X634596D03*
X646631Y1550897D03*
X637182Y1550697D03*
X641906Y1550897D03*
X637417Y1589884D03*
Y1594876D03*
X643447Y1599884D03*
X638491D03*
X643447Y1604876D03*
X638491D03*
X643447Y1611796D03*
X638491D03*
X643447Y1616788D03*
X637417Y1626788D03*
X638491Y1616788D03*
X637417Y1621796D03*
X640520Y1635483D03*
X649266Y1650126D03*
X642151Y1649961D03*
X639284Y1683049D03*
X647500Y1682850D03*
X635210Y1721545D03*
X650843Y23788D03*
X649585Y29298D03*
X663703Y32574D03*
X653570Y58363D03*
X660775Y78330D03*
X649441Y177003D03*
X662740Y375240D03*
X649500Y382500D03*
X660885Y412588D03*
X650268Y479141D03*
X649771Y505736D03*
X659398Y516260D03*
X658946Y756766D03*
X651904D03*
Y760266D03*
X663496Y773564D03*
X658946Y763766D03*
X651904Y767266D03*
X658046Y786950D03*
X663496Y780257D03*
X651754Y795316D03*
X658046Y796989D03*
X663496Y803682D03*
Y810375D03*
Y817068D03*
X651754Y832127D03*
X658046Y833800D03*
Y823761D03*
X663496Y840493D03*
Y847186D03*
X658046Y860572D03*
X663496Y853879D03*
X651754Y868938D03*
X658046Y870611D03*
X663496Y877304D03*
Y883997D03*
Y890690D03*
X651754Y905750D03*
X658046Y897383D03*
Y907423D03*
X663496Y914115D03*
Y920808D03*
X658046Y934194D03*
X663496Y927501D03*
X651754Y942561D03*
X658046Y944234D03*
X663496Y950926D03*
Y957619D03*
Y964312D03*
Y971005D03*
Y977698D03*
Y984391D03*
Y991084D03*
Y997777D03*
Y1004470D03*
Y1031241D03*
Y1037934D03*
Y1044627D03*
Y1051320D03*
Y1058013D03*
Y1068052D03*
Y1074745D03*
X651754Y1089805D03*
X658046Y1081438D03*
Y1091478D03*
X663496Y1098171D03*
Y1104863D03*
X658046Y1118249D03*
X663496Y1111556D03*
X651754Y1126616D03*
X658046Y1128289D03*
X663496Y1134982D03*
Y1141675D03*
Y1148367D03*
X651754Y1163427D03*
X658046Y1155060D03*
Y1165100D03*
X663496Y1171793D03*
Y1178486D03*
X658046Y1191871D03*
X663496Y1185178D03*
X651754Y1200238D03*
X658046Y1201911D03*
X663496Y1208604D03*
Y1215297D03*
Y1221989D03*
X651754Y1237049D03*
X658046Y1238722D03*
Y1228682D03*
X663496Y1245415D03*
Y1252108D03*
X657836Y1350877D03*
X653836D03*
X650036D03*
X661713Y1373981D03*
X655702Y1391107D03*
X659559Y1391027D03*
X655873Y1428844D03*
X652189Y1421276D03*
X659486Y1452895D03*
X661396Y1450295D03*
X652776D03*
X661396Y1455495D03*
X652776D03*
X662374Y1548563D03*
X651355Y1550797D03*
X651840Y1567752D03*
X660542Y1638169D03*
X657392Y1628137D03*
X652274Y1630366D03*
X650895Y1648115D03*
X655914Y1668744D03*
X659436Y1694697D03*
X649526Y1709274D03*
X663997Y1703111D03*
X659673Y1722174D03*
X661845Y1717340D03*
X654508Y1728000D03*
X654527Y1718229D03*
X659673Y1732836D03*
X672843Y23788D03*
X668739Y45262D03*
X677594Y36205D03*
X675887Y45262D03*
X666411Y69507D03*
X678664Y88080D03*
X673751Y78092D03*
X673691Y200672D03*
X673301Y211332D03*
X671753Y397936D03*
X670000Y457844D03*
X669955Y495468D03*
X671500Y529500D03*
X677055Y776911D03*
X667896Y791970D03*
X677055Y783604D03*
Y807029D03*
Y813722D03*
Y820415D03*
X667896Y828781D03*
X677055Y843840D03*
Y850533D03*
X667896Y865592D03*
X677055Y857226D03*
Y880651D03*
Y887344D03*
Y894037D03*
X667896Y902403D03*
X677055Y917462D03*
Y924155D03*
X667896Y939214D03*
X677055Y930848D03*
Y954273D03*
Y960966D03*
Y967659D03*
Y974352D03*
Y981045D03*
Y987737D03*
Y994430D03*
Y1004470D03*
Y1034588D03*
Y1041281D03*
Y1047974D03*
Y1054667D03*
Y1061360D03*
Y1071399D03*
X667896Y1086458D03*
X677055Y1078092D03*
Y1101517D03*
Y1108210D03*
Y1114903D03*
X667896Y1123269D03*
X677055Y1138328D03*
Y1145021D03*
X667896Y1160080D03*
X677055Y1151714D03*
Y1175139D03*
Y1181832D03*
Y1188525D03*
X667896Y1196891D03*
X677055Y1211950D03*
Y1218643D03*
X667896Y1233702D03*
X677055Y1225336D03*
Y1248761D03*
Y1255454D03*
X674552Y1351988D03*
Y1349488D03*
X666176Y1450295D03*
Y1455495D03*
X666050Y1501670D03*
X672684Y1522690D03*
X674687Y1519726D03*
X665800Y1530575D03*
X674620Y1535271D03*
Y1542125D03*
X672617Y1545089D03*
Y1538235D03*
X674894Y1629042D03*
X673982Y1639289D03*
X665802Y1652337D03*
X674486Y1647842D03*
X673480Y1662668D03*
X671631Y1690786D03*
X693672Y32684D03*
X686855Y43701D03*
X679719Y59066D03*
X682946Y69982D03*
X682891Y72642D03*
X688552Y79166D03*
X681895Y82212D03*
X685783Y78768D03*
X684954Y104968D03*
X691058Y131408D03*
X684521Y152482D03*
X688521D03*
X692521D03*
X682264Y224116D03*
X691547Y386834D03*
X688249Y405628D03*
X679862Y409320D03*
X679500Y526834D03*
X691496Y575081D03*
X688078Y675493D03*
X681605Y756766D03*
X681671Y760178D03*
X688647Y756766D03*
X693197Y773564D03*
X688647Y763766D03*
X681605Y767266D03*
X687747Y786950D03*
X693197Y780257D03*
X681455Y795316D03*
X687747Y796989D03*
X693197Y803682D03*
Y810375D03*
Y817068D03*
X681455Y832127D03*
X687747Y833800D03*
Y823761D03*
X693197Y840493D03*
Y847186D03*
X687747Y860572D03*
X693197Y853879D03*
X681455Y868938D03*
X687747Y870611D03*
X693197Y877304D03*
Y883997D03*
Y890690D03*
X681455Y905750D03*
X687747Y897383D03*
Y907423D03*
X693197Y914115D03*
Y920808D03*
X687747Y934194D03*
X693197Y927501D03*
X681455Y942561D03*
X687747Y944234D03*
X693197Y950926D03*
Y957619D03*
Y964312D03*
Y971005D03*
Y977698D03*
Y984391D03*
Y991084D03*
Y997777D03*
Y1004470D03*
Y1031241D03*
Y1037934D03*
Y1044627D03*
Y1051320D03*
Y1058013D03*
Y1068052D03*
Y1074745D03*
X681455Y1089805D03*
X687747Y1081438D03*
Y1091478D03*
X693197Y1098171D03*
Y1104863D03*
X687747Y1118249D03*
X693197Y1111556D03*
X681455Y1126616D03*
X687747Y1128289D03*
X693197Y1134982D03*
Y1141675D03*
Y1148367D03*
X681455Y1163427D03*
X687747Y1155060D03*
Y1165100D03*
X693197Y1171793D03*
Y1178486D03*
X687747Y1191871D03*
X693197Y1185178D03*
X681455Y1200238D03*
X687747Y1201911D03*
X693197Y1208604D03*
Y1215297D03*
Y1221989D03*
X681455Y1237049D03*
X687747Y1238722D03*
Y1228682D03*
X693197Y1245415D03*
Y1252108D03*
X688076Y1297506D03*
Y1305206D03*
Y1300006D03*
Y1302606D03*
X683052Y1352048D03*
Y1349548D03*
X685187Y1368700D03*
Y1363500D03*
Y1366100D03*
X687577Y1425054D03*
X688120Y1519601D03*
X683352Y1530526D03*
Y1526526D03*
X682016Y1539067D03*
X688308Y1631636D03*
X693150Y1640773D03*
X682925Y1657116D03*
X686825Y1647430D03*
X685485Y1682259D03*
X694843Y23788D03*
X701839Y45112D03*
X707608Y69718D03*
X705570Y133760D03*
X704144Y122602D03*
X707243Y123946D03*
X701927Y166535D03*
Y172441D03*
Y178346D03*
Y184252D03*
Y196063D03*
Y190157D03*
Y201968D03*
Y207874D03*
Y213779D03*
Y219685D03*
X696105Y364149D03*
X696500Y529862D03*
X700500Y545862D03*
X704500Y555862D03*
X701496Y580556D03*
X697392Y601686D03*
X697642Y733401D03*
X706756Y776911D03*
X697597Y791970D03*
X706756Y783604D03*
Y807029D03*
Y813722D03*
Y820415D03*
X697597Y828781D03*
X706756Y843840D03*
Y850533D03*
X697597Y865592D03*
X706756Y857226D03*
Y880651D03*
Y887344D03*
Y894037D03*
X697597Y902403D03*
X706756Y924155D03*
Y917462D03*
X697597Y939214D03*
X706756Y930848D03*
Y954273D03*
Y960966D03*
Y967659D03*
Y974352D03*
Y981045D03*
Y987737D03*
Y994430D03*
Y1004470D03*
Y1041281D03*
Y1034588D03*
Y1047974D03*
Y1054667D03*
Y1071399D03*
Y1061360D03*
Y1078092D03*
X697597Y1086458D03*
X706756Y1101517D03*
Y1114903D03*
Y1108210D03*
X697597Y1123269D03*
X706756Y1145021D03*
Y1138328D03*
Y1151714D03*
X697597Y1160080D03*
X706756Y1175139D03*
Y1181832D03*
Y1188525D03*
X697597Y1196891D03*
X706756Y1211950D03*
Y1218643D03*
Y1225336D03*
X697597Y1233702D03*
X706756Y1248761D03*
Y1255454D03*
X697483Y1297506D03*
Y1305206D03*
Y1300006D03*
Y1302606D03*
X701771Y1351988D03*
Y1349488D03*
X699467Y1368710D03*
Y1363510D03*
Y1366110D03*
X703568Y1379476D03*
X699610Y1580523D03*
X706681Y1627361D03*
X705833Y1633568D03*
X706089Y1643411D03*
X705815Y1654918D03*
X703473Y1663001D03*
X695400Y1685887D03*
X705366Y1684064D03*
X723479Y-28508D03*
X716843Y23788D03*
X717342Y57098D03*
X720328Y344824D03*
X711500Y360862D03*
X719500D03*
X711556Y575081D03*
X714583Y587642D03*
X715037Y603278D03*
X713280Y636897D03*
X712319Y654954D03*
X711306Y756766D03*
Y760178D03*
X718348Y756766D03*
X722898Y773564D03*
X718348Y763766D03*
X711306Y767266D03*
X722898Y780257D03*
X717448Y786950D03*
X722898Y803682D03*
X711156Y795316D03*
X717448Y796989D03*
X722898Y810375D03*
Y817068D03*
X717448Y823761D03*
Y833800D03*
X711156Y832127D03*
X722898Y847186D03*
Y840493D03*
Y853879D03*
X717448Y860572D03*
X722898Y877304D03*
X717448Y870611D03*
X711156Y868938D03*
X722898Y883997D03*
Y890690D03*
X717448Y897383D03*
Y907423D03*
X711156Y905750D03*
X722898Y920808D03*
Y914115D03*
Y927501D03*
X717448Y934194D03*
X722898Y950926D03*
X717448Y944234D03*
X711156Y942561D03*
X722898Y957619D03*
Y971005D03*
Y964312D03*
Y984391D03*
Y977698D03*
Y991084D03*
Y997777D03*
Y1004470D03*
Y1031241D03*
Y1037934D03*
Y1044627D03*
Y1051320D03*
Y1058013D03*
Y1068052D03*
Y1074745D03*
X717448Y1081438D03*
X711156Y1089805D03*
X717448Y1091478D03*
X722898Y1098171D03*
Y1104863D03*
Y1111556D03*
X717448Y1118249D03*
Y1128289D03*
X711156Y1126616D03*
X722898Y1134982D03*
Y1148367D03*
Y1141675D03*
X717448Y1165100D03*
X711156Y1163427D03*
X717448Y1155060D03*
X722898Y1178486D03*
Y1171793D03*
Y1185178D03*
X717448Y1191871D03*
X722898Y1208604D03*
X711156Y1200238D03*
X717448Y1201911D03*
X722898Y1215297D03*
Y1221989D03*
X717448Y1228682D03*
Y1238722D03*
X711156Y1237049D03*
X722898Y1252108D03*
Y1245415D03*
X721361Y1297546D03*
X711954D03*
X721361Y1305246D03*
Y1302646D03*
Y1300046D03*
X711954Y1305246D03*
Y1302646D03*
Y1300046D03*
X710221Y1351988D03*
Y1349488D03*
X716707Y1385281D03*
X719137D03*
X720233Y1378525D03*
Y1381482D03*
Y1375418D03*
X722833D03*
X714277Y1385281D03*
X715033Y1378525D03*
X717633D03*
X712433D03*
X717633Y1381482D03*
X715033Y1375418D03*
X717633D03*
X712433D03*
X719186Y1403296D03*
X719137Y1390881D03*
X714277D03*
X716707D03*
X709551Y1406578D03*
X716770Y1531459D03*
X715122Y1533378D03*
X716989Y1537249D03*
X713357Y1535212D03*
X715224Y1539083D03*
X713459Y1540917D03*
X722876Y1611343D03*
X717749Y1654921D03*
X709771Y1654927D03*
X712354Y1682279D03*
X738843Y23788D03*
X728981Y39872D03*
X736791Y39832D03*
X730131Y60757D03*
X736524Y58069D03*
X730958Y71014D03*
X738044Y71526D03*
X727944Y88972D03*
X727986Y101979D03*
X729900Y98090D03*
X727986Y105477D03*
X737624Y98858D03*
X734524Y98758D03*
X735734Y111988D03*
X726720Y574910D03*
X724001Y636790D03*
X726952Y648667D03*
X736457Y776911D03*
Y783604D03*
X727298Y791970D03*
X736457Y807029D03*
Y813722D03*
Y820415D03*
X727298Y828781D03*
X736457Y843840D03*
Y850533D03*
X727298Y865592D03*
X736457Y857226D03*
Y880651D03*
Y887344D03*
Y894037D03*
X727298Y902403D03*
X736457Y924155D03*
Y917462D03*
X727298Y939214D03*
X736457Y930848D03*
Y954273D03*
Y960966D03*
Y967659D03*
Y974352D03*
Y981045D03*
Y987737D03*
Y994430D03*
Y1004470D03*
Y1034588D03*
Y1041281D03*
Y1047974D03*
Y1054667D03*
Y1071399D03*
Y1061360D03*
X727298Y1086458D03*
X736457Y1078092D03*
Y1101517D03*
Y1114903D03*
Y1108210D03*
X727298Y1123269D03*
X736457Y1145021D03*
Y1138328D03*
X727298Y1160080D03*
X736457Y1151714D03*
Y1175139D03*
Y1181832D03*
Y1188525D03*
X727298Y1196891D03*
X736457Y1211950D03*
Y1218643D03*
X727298Y1233702D03*
X736457Y1225336D03*
Y1248761D03*
Y1255454D03*
X735954Y1297546D03*
Y1305246D03*
Y1302646D03*
Y1300046D03*
X727098Y1351977D03*
X730900Y1352131D03*
X727098Y1349077D03*
X730900Y1349231D03*
X734047Y1372880D03*
X731447D03*
X734047Y1370280D03*
Y1367680D03*
X731447D03*
Y1370280D03*
X728348Y1380832D03*
Y1377875D03*
X736280Y1379580D03*
X732797Y1375380D03*
X725333Y1375418D03*
X727777Y1375434D03*
X738230Y1402898D03*
X734925Y1657826D03*
X730302Y1658050D03*
X726302Y1658022D03*
X738370Y1677909D03*
X736001Y1695509D03*
X728454Y1690491D03*
X732434Y1690660D03*
X738550Y1693215D03*
X742841Y39832D03*
X744477Y58373D03*
X744988Y49062D03*
X747488D03*
X752261Y59782D03*
X745131Y69507D03*
X750090Y72820D03*
X745712Y212760D03*
X746705Y315647D03*
X742278Y566667D03*
X753500Y675800D03*
X748049Y756766D03*
X741007D03*
Y760266D03*
X752599Y773564D03*
X741007Y767266D03*
X748049Y763766D03*
X752599Y780257D03*
X747149Y786950D03*
X752599Y803682D03*
X747149Y796989D03*
X740857Y795316D03*
X752599Y810375D03*
Y817068D03*
X747149Y823761D03*
Y833800D03*
X740857Y832127D03*
X752599Y840493D03*
Y847186D03*
Y853879D03*
X747149Y860572D03*
X752599Y877304D03*
X747149Y870611D03*
X740857Y868938D03*
X752599Y890690D03*
Y883997D03*
X747149Y897383D03*
Y907423D03*
X740857Y905750D03*
X752599Y920808D03*
Y914115D03*
X747149Y934194D03*
X752599Y927501D03*
Y950926D03*
X747149Y944234D03*
X740857Y942561D03*
X752599Y957619D03*
Y971005D03*
Y964312D03*
Y984391D03*
Y977698D03*
Y991084D03*
Y997777D03*
Y1004470D03*
Y1031241D03*
Y1037934D03*
Y1044627D03*
Y1051320D03*
Y1058013D03*
Y1068052D03*
Y1074745D03*
X747149Y1081438D03*
X740857Y1089805D03*
X752599Y1098171D03*
Y1104863D03*
X747149Y1091478D03*
X752599Y1111556D03*
X747149Y1118249D03*
Y1128289D03*
X740857Y1126616D03*
X752599Y1134982D03*
Y1148367D03*
Y1141675D03*
X740857Y1163427D03*
X747149Y1165100D03*
Y1155060D03*
X752599Y1178486D03*
Y1171793D03*
Y1185178D03*
X747149Y1191871D03*
X752599Y1208604D03*
X740857Y1200238D03*
X747149Y1201911D03*
X752599Y1215297D03*
Y1221989D03*
X747149Y1228682D03*
Y1238722D03*
X740857Y1237049D03*
X752599Y1252108D03*
Y1245415D03*
X745475Y1297246D03*
Y1304946D03*
Y1302346D03*
Y1299746D03*
X739500Y1352031D03*
Y1349131D03*
X753015Y1381582D03*
Y1378625D03*
Y1375518D03*
X747059Y1385381D03*
X745215Y1378625D03*
X747815D03*
Y1375518D03*
X745215D03*
X750415Y1381582D03*
Y1378625D03*
Y1375518D03*
X749489Y1385381D03*
X751919D03*
X751968Y1403396D03*
X751919Y1390981D03*
X747059D03*
X749489D03*
X739888Y1404849D03*
X743740Y1657327D03*
X743039Y1643326D03*
X760843Y23788D03*
X754621Y74562D03*
X754634Y105288D03*
Y108288D03*
X762173Y123898D03*
X770073Y143438D03*
X756083Y220240D03*
X757464Y284087D03*
X754556Y283976D03*
X755335Y295589D03*
X758959Y319596D03*
X753959Y343790D03*
X766158Y776911D03*
Y783604D03*
X756999Y791970D03*
X766158Y807029D03*
Y813722D03*
Y820415D03*
X756999Y828781D03*
X766158Y843840D03*
Y850533D03*
Y857226D03*
X756999Y865592D03*
X766158Y880651D03*
Y887344D03*
Y894037D03*
X756999Y902403D03*
X766158Y924155D03*
Y917462D03*
X756999Y939214D03*
X766158Y930848D03*
Y954273D03*
Y960966D03*
Y967659D03*
Y974352D03*
Y981045D03*
Y987737D03*
Y994430D03*
Y1004470D03*
Y1041281D03*
Y1034588D03*
Y1047974D03*
Y1054667D03*
Y1071399D03*
Y1061360D03*
X756999Y1086458D03*
X766158Y1078092D03*
Y1101517D03*
Y1114903D03*
Y1108210D03*
X756999Y1123269D03*
X766158Y1145021D03*
Y1138328D03*
X756999Y1160080D03*
X766158Y1151714D03*
Y1175139D03*
Y1181832D03*
Y1188525D03*
X756999Y1196891D03*
X766158Y1211950D03*
Y1218643D03*
Y1225336D03*
X756999Y1233702D03*
X766158Y1248761D03*
Y1255454D03*
X759854Y1297246D03*
Y1304946D03*
Y1302346D03*
Y1299746D03*
X761800Y1352031D03*
Y1349131D03*
X764229Y1372880D03*
X766829D03*
Y1370380D03*
Y1367780D03*
X764229D03*
Y1370380D03*
X761130Y1380932D03*
Y1377975D03*
X755615Y1375518D03*
X758115D03*
X760559Y1375534D03*
X765579Y1375480D03*
X767381Y1676594D03*
X769475Y75360D03*
X771356Y167518D03*
X773221Y296262D03*
X780618Y296345D03*
X779121Y306155D03*
X773944Y312588D03*
X780808Y419865D03*
X777900Y756766D03*
X770708D03*
Y760266D03*
X782300Y773564D03*
X770708Y767266D03*
X777900Y763766D03*
X776850Y786950D03*
X782300Y780257D03*
X776850Y796989D03*
X770558Y795316D03*
X782300Y803682D03*
Y810375D03*
Y817068D03*
X770558Y832127D03*
X776850Y823761D03*
Y833800D03*
X782300Y847186D03*
Y840493D03*
X776850Y860572D03*
X782300Y853879D03*
Y877304D03*
X776850Y870611D03*
X770558Y868938D03*
X782300Y890690D03*
Y883997D03*
X776850Y897383D03*
Y907423D03*
X770558Y905750D03*
X782300Y920808D03*
Y914115D03*
X776850Y934194D03*
X782300Y927501D03*
X776850Y944234D03*
X770558Y942561D03*
X782300Y950926D03*
Y957619D03*
Y971005D03*
Y964312D03*
Y984391D03*
Y977698D03*
Y991084D03*
Y997777D03*
Y1004470D03*
Y1031241D03*
Y1037934D03*
Y1044627D03*
Y1051320D03*
Y1058013D03*
Y1068052D03*
Y1074745D03*
X776850Y1081438D03*
X770558Y1089805D03*
X782300Y1098171D03*
Y1104863D03*
X776850Y1091478D03*
Y1118249D03*
X782300Y1111556D03*
X776850Y1128289D03*
X770558Y1126616D03*
X782300Y1134982D03*
Y1148367D03*
Y1141675D03*
X776850Y1165100D03*
X770558Y1163427D03*
X776850Y1155060D03*
X782300Y1178486D03*
Y1171793D03*
Y1185178D03*
X776850Y1191871D03*
X782300Y1208604D03*
X770558Y1200238D03*
X776850Y1201911D03*
X782300Y1215297D03*
Y1221989D03*
X776850Y1228682D03*
Y1238722D03*
X770558Y1237049D03*
X782300Y1252108D03*
Y1245415D03*
X769521Y1297199D03*
Y1304899D03*
Y1299699D03*
Y1302299D03*
X770990Y1349091D03*
Y1351991D03*
X773069Y1375500D03*
X770469D03*
X776010Y1380750D03*
X787456Y49379D03*
X797594Y282233D03*
X797444Y271469D03*
X795668Y298801D03*
X792488Y377452D03*
X797252Y459344D03*
Y471344D03*
X794425Y541425D03*
X794059Y553559D03*
X791500Y560000D03*
X785000Y563500D03*
X795858Y776911D03*
Y783604D03*
X786700Y791970D03*
X795858Y807029D03*
Y820415D03*
Y813722D03*
X786700Y828781D03*
X795858Y843840D03*
Y850533D03*
X786700Y865592D03*
X795858Y857226D03*
Y880651D03*
Y894037D03*
Y887344D03*
X786700Y902403D03*
X795858Y924155D03*
Y917462D03*
X786700Y939214D03*
X795858Y930848D03*
Y954273D03*
Y960966D03*
Y967659D03*
Y981045D03*
Y974352D03*
Y994430D03*
Y987737D03*
Y1004470D03*
Y1041281D03*
Y1034588D03*
Y1054667D03*
Y1047974D03*
Y1071399D03*
Y1061360D03*
X786700Y1086458D03*
X795858Y1078092D03*
Y1101517D03*
Y1114903D03*
Y1108210D03*
X786700Y1123269D03*
X795858Y1145021D03*
Y1138328D03*
X786700Y1160080D03*
X795858Y1151714D03*
Y1175139D03*
Y1181832D03*
Y1188525D03*
X786700Y1196891D03*
X795858Y1218643D03*
Y1211950D03*
X786700Y1233702D03*
X795858Y1225336D03*
Y1248761D03*
Y1255454D03*
X809456Y49379D03*
X806984Y265653D03*
X798621Y312773D03*
X803264Y330102D03*
X808401Y341670D03*
X811569Y387674D03*
X813175Y422687D03*
X810360Y442079D03*
X802752Y455344D03*
X812500Y504000D03*
X807450Y756766D03*
X800408D03*
Y760266D03*
X812000Y773564D03*
X800408Y767266D03*
X812000Y780257D03*
X806550Y786950D03*
X812000Y803682D03*
X806550Y796989D03*
X800258Y795316D03*
X812000Y817068D03*
Y810375D03*
X800258Y832127D03*
X806550Y833800D03*
Y823761D03*
X812000Y847186D03*
Y840493D03*
X806550Y860572D03*
X812000Y853879D03*
Y877304D03*
X806550Y870611D03*
X800258Y868938D03*
X812000Y890690D03*
Y883997D03*
X806550Y897383D03*
Y907423D03*
X800258Y905750D03*
X812000Y920808D03*
Y914115D03*
Y927501D03*
X806550Y934194D03*
X812000Y950926D03*
X800258Y942561D03*
X806550Y944234D03*
X812000Y957619D03*
Y971005D03*
Y964312D03*
Y984391D03*
Y977698D03*
Y997777D03*
Y991084D03*
Y1004470D03*
Y1044627D03*
Y1037934D03*
Y1031241D03*
Y1058013D03*
Y1051320D03*
Y1068052D03*
Y1074745D03*
X806550Y1081438D03*
X800258Y1089805D03*
X812000Y1098171D03*
Y1104863D03*
X806550Y1091478D03*
X812000Y1111556D03*
X806550Y1118249D03*
Y1128289D03*
X800258Y1126616D03*
X812000Y1134982D03*
Y1148367D03*
Y1141675D03*
X806550Y1165100D03*
X800258Y1163427D03*
X806550Y1155060D03*
X812000Y1178486D03*
Y1171793D03*
Y1185178D03*
X806550Y1191871D03*
X812000Y1208604D03*
X806550Y1201911D03*
X800258Y1200238D03*
X812000Y1221989D03*
Y1215297D03*
X806550Y1228682D03*
Y1238722D03*
X800258Y1237049D03*
X812000Y1245415D03*
Y1252108D03*
X822699Y56712D03*
X821119Y134632D03*
X825699Y139062D03*
X816322Y284369D03*
X826665Y423425D03*
X817426Y487232D03*
X824500Y514500D03*
X817441Y517941D03*
X822559Y530876D03*
X826552Y543612D03*
X823777Y560988D03*
X816400Y828781D03*
Y865592D03*
Y902403D03*
Y939214D03*
Y1086458D03*
Y1123269D03*
Y1160080D03*
Y1196891D03*
Y1233702D03*
X826112Y1269546D03*
X833407Y-26181D03*
X836660Y-26167D03*
Y-16167D03*
X833407Y-16181D03*
X839700Y-14972D03*
X833422Y-13666D03*
X836675Y-13652D03*
X833412Y-19948D03*
X836674D03*
X836675Y-23652D03*
X833422Y-23666D03*
X839700Y-24972D03*
X833412Y52D03*
X836674D03*
X833412Y-9948D03*
X836674D03*
X836675Y-3652D03*
X833422Y-3666D03*
X839700Y-4972D03*
X833407Y-6181D03*
X836660Y-6167D03*
X836675Y16348D03*
X833422Y16334D03*
X839700Y15028D03*
X833407Y13819D03*
X836660Y13833D03*
X836674Y10052D03*
X833412D03*
X836675Y6348D03*
X833422Y6334D03*
X839700Y5028D03*
X833407Y3819D03*
X836660Y3833D03*
X836659Y24250D03*
X836674Y26765D03*
X833406Y24236D03*
X839699Y25445D03*
X833421Y26751D03*
X833376Y19206D03*
X833391Y21721D03*
X831456Y49379D03*
X836127Y62681D03*
X837792Y85186D03*
X831298Y104206D03*
X834616Y94324D03*
X842865Y110296D03*
X830340Y228143D03*
X832525Y268579D03*
X829572Y296511D03*
X840288Y287593D03*
X829167Y288063D03*
X832686Y331028D03*
X836840Y382003D03*
X841862Y390441D03*
X834430Y434634D03*
X834251Y459578D03*
X835425Y477890D03*
X830743Y500740D03*
X831756Y901318D03*
X835554Y1281324D03*
X835682Y1285472D03*
X836670Y1291355D03*
X836587Y1295333D03*
X842500Y1310000D03*
Y1306000D03*
Y1302000D03*
X834017Y1333584D03*
X834071Y1342457D03*
X839188Y1348937D03*
X841203Y1361376D03*
X853456Y49379D03*
X854108Y91232D03*
X851895Y160141D03*
X853800Y265057D03*
X847939Y265092D03*
X854334Y276117D03*
X854225Y280027D03*
Y283527D03*
X857334Y276117D03*
X852780Y291559D03*
X852801Y288562D03*
X853201Y297462D03*
X856701Y304862D03*
X846275Y335575D03*
X849750Y401280D03*
X852240Y470946D03*
X849126Y530138D03*
X845126D03*
X848660Y651127D03*
X846725Y1269785D03*
X861351Y61672D03*
X858528Y262382D03*
X860834Y276817D03*
X863934Y276917D03*
X862044Y290047D03*
X862075Y398537D03*
X872020Y413300D03*
X867590Y642420D03*
X864700Y836100D03*
X859446Y1284288D03*
X875345Y51595D03*
X877462Y139540D03*
X878221Y192055D03*
X880944Y283347D03*
Y286347D03*
X875447Y301500D03*
X884740Y316000D03*
X874500Y328000D03*
X873884Y453383D03*
X886707Y1254742D03*
Y1251742D03*
X881807Y1248920D03*
Y1245920D03*
X881937Y1251857D03*
X877480Y1248844D03*
X886707Y1257742D03*
X885000Y1307500D03*
X877000Y1340241D03*
X884462Y1446974D03*
X876044Y1444317D03*
X898720Y145206D03*
X888560Y469527D03*
X902376Y594657D03*
X903556Y614062D03*
X899678Y601043D03*
X897824Y909093D03*
X891648Y1137843D03*
X900723Y1146553D03*
X896107Y1254742D03*
Y1251742D03*
X896907Y1245920D03*
Y1248920D03*
X896107Y1257742D03*
X917386Y179500D03*
Y177000D03*
Y169500D03*
Y172000D03*
Y174500D03*
Y167000D03*
X909298Y195925D03*
X909161Y203012D03*
X909320Y210098D03*
Y217185D03*
Y224271D03*
Y231358D03*
X914575Y560027D03*
X906597Y579695D03*
X907035Y590172D03*
X906597Y628426D03*
X906734Y619373D03*
X906570Y663930D03*
X906387Y818471D03*
X903941Y874000D03*
X917622Y887545D03*
X909000Y909000D03*
X905000D03*
X904719Y921792D03*
X911500Y931000D03*
X908500Y927500D03*
X909890Y950217D03*
X910066Y960332D03*
X909203Y970709D03*
X916763Y972343D03*
X908799Y985291D03*
X910707Y1254742D03*
Y1251742D03*
X905007Y1248920D03*
Y1245920D03*
X905074Y1252177D03*
X910707Y1257742D03*
X920720Y145206D03*
X919886Y167000D03*
Y169500D03*
Y172000D03*
Y174500D03*
Y177000D03*
Y179500D03*
X927134Y189386D03*
X925321Y203399D03*
X926983Y604751D03*
X927127Y619251D03*
X930926Y664791D03*
X923916Y843990D03*
X918500Y856925D03*
X930925Y860925D03*
X929603Y889000D03*
X931948Y891397D03*
X919916Y908916D03*
X920276Y900554D03*
X931877Y918168D03*
X928535Y913454D03*
X920409Y918274D03*
X918000Y928000D03*
X926062Y938727D03*
X926004Y952716D03*
X925200Y1110443D03*
Y1107843D03*
Y1117443D03*
Y1114843D03*
Y1124443D03*
Y1121843D03*
Y1131443D03*
Y1128843D03*
X920107Y1251742D03*
Y1254742D03*
Y1248920D03*
Y1245920D03*
Y1257742D03*
X924000Y1310000D03*
X920738Y1321363D03*
X927869Y1317417D03*
X923680Y1339520D03*
X919758Y1348990D03*
X931798Y1660762D03*
X923798D03*
X945006Y593609D03*
X935649Y590751D03*
X939391Y600571D03*
X946366Y668811D03*
X940391Y859947D03*
X944057Y882886D03*
X940514Y918134D03*
X933021Y933979D03*
X939670Y945169D03*
X942924Y982547D03*
X943135Y977129D03*
X938507Y1137843D03*
X945691Y1254742D03*
Y1251742D03*
X940791Y1248920D03*
Y1245920D03*
X940921Y1251857D03*
X936464Y1248844D03*
X945691Y1257742D03*
X938000Y1309500D03*
Y1301500D03*
Y1304500D03*
X933586Y1325501D03*
X933041Y1315920D03*
X944406Y1532791D03*
X939798Y1660762D03*
X955529Y614017D03*
X951839Y812730D03*
X958051Y859384D03*
X952425Y876575D03*
X948060Y891468D03*
X951367Y913648D03*
X951500Y930925D03*
X955091Y1254742D03*
Y1251742D03*
X955891Y1245920D03*
Y1248920D03*
X955000Y1267000D03*
X955091Y1257742D03*
X955000Y1271000D03*
Y1275000D03*
Y1279000D03*
X960518Y1656185D03*
X957758D03*
X957848Y1659375D03*
X960608D03*
X960558Y1662015D03*
X957798D03*
X947798Y1660762D03*
X964720Y145206D03*
X975689Y156950D03*
Y153950D03*
X971192Y219589D03*
X968692D03*
X973616Y317648D03*
X963134Y882936D03*
X968919Y1116177D03*
Y1118777D03*
Y1109177D03*
Y1111777D03*
X968800Y1130046D03*
Y1132646D03*
X968919Y1123177D03*
Y1125777D03*
X969691Y1254742D03*
Y1251742D03*
X963991Y1248920D03*
Y1245920D03*
X964058Y1252177D03*
X969691Y1257742D03*
X975000Y1307500D03*
X967500Y1340241D03*
X963120Y1520080D03*
Y1523080D03*
Y1526080D03*
X976858Y1656185D03*
X976898Y1662015D03*
X976948Y1659375D03*
X986720Y145206D03*
X988593Y189347D03*
X981445Y185389D03*
X982455Y264781D03*
Y275443D03*
X989227Y389311D03*
X992037Y485369D03*
X979091Y1251742D03*
Y1254742D03*
Y1248920D03*
Y1245920D03*
Y1257742D03*
X986486Y1523080D03*
Y1520080D03*
Y1526080D03*
X985318Y1656105D03*
X988078D03*
X979618Y1656185D03*
X985358Y1661935D03*
X988118D03*
X985408Y1659295D03*
X988168D03*
X979658Y1662015D03*
X979708Y1659375D03*
X995189Y263340D03*
Y274002D03*
X992915Y280389D03*
X1007083Y363461D03*
X996232Y424440D03*
X999304Y1282574D03*
Y1289215D03*
X999303Y1285693D03*
X1004418Y1656105D03*
X1007178D03*
X1004508Y1659295D03*
X1004458Y1661935D03*
X1008720Y145206D03*
X1020661Y146580D03*
X1023221Y191574D03*
X1019803Y218099D03*
X1017870Y294386D03*
X1009618Y396125D03*
X1021425Y404925D03*
X1013365Y433426D03*
X1008789Y488642D03*
Y493655D03*
X1012211Y547574D03*
X1015061D03*
X1015961Y554432D03*
X1007703Y759012D03*
X1007587Y800384D03*
Y802884D03*
Y811352D03*
Y813852D03*
Y822252D03*
Y824752D03*
Y833356D03*
Y835856D03*
Y844256D03*
X1021908Y1289124D03*
X1019314Y1289159D03*
X1017069Y1290346D03*
X1013500Y1312500D03*
X1013000Y1306500D03*
X1013500Y1325500D03*
X1011500Y1335000D03*
X1013500Y1344500D03*
X1009852Y1523080D03*
Y1520080D03*
Y1526080D03*
X1007268Y1659295D03*
X1007218Y1661935D03*
X1023187Y146580D03*
X1027724Y397726D03*
X1030525Y391362D03*
X1027760Y451832D03*
X1022461Y558932D03*
X1027579D03*
X1032579Y559934D03*
X1025493Y768719D03*
X1035645Y773582D03*
X1033218Y1523080D03*
Y1520080D03*
Y1526080D03*
X1033798Y1656675D03*
X1033748Y1659315D03*
X1040199Y49379D03*
X1040891Y406586D03*
X1045100Y427059D03*
X1045015Y444404D03*
X1041254Y523874D03*
X1043180Y547027D03*
X1040890Y735717D03*
X1050015Y756765D03*
Y760265D03*
X1045465Y776910D03*
X1050015Y767265D03*
X1045465Y783603D03*
X1041065Y795315D03*
X1045465Y807028D03*
Y813721D03*
Y820414D03*
X1041065Y832126D03*
X1045465Y850532D03*
Y843839D03*
Y857225D03*
X1041065Y868937D03*
X1045465Y880650D03*
Y887343D03*
Y894036D03*
X1041065Y905749D03*
X1045465Y917461D03*
Y924154D03*
Y930847D03*
X1041065Y942560D03*
X1045465Y954272D03*
Y967658D03*
Y960965D03*
Y974351D03*
Y981044D03*
Y987736D03*
Y994429D03*
Y1004469D03*
Y1041280D03*
Y1034587D03*
Y1047973D03*
Y1054666D03*
Y1061359D03*
Y1071398D03*
Y1078091D03*
X1041065Y1089804D03*
X1045465Y1101516D03*
Y1108209D03*
Y1114902D03*
X1041065Y1126615D03*
X1045465Y1138327D03*
Y1145020D03*
Y1151713D03*
X1041065Y1163426D03*
X1045465Y1175138D03*
Y1188524D03*
Y1181831D03*
X1041065Y1200237D03*
X1045465Y1211949D03*
Y1218642D03*
X1041065Y1237048D03*
X1045465Y1225335D03*
Y1248760D03*
Y1255453D03*
X1048684Y1350724D03*
X1051684D03*
X1050866Y1659548D03*
X1062199Y49379D03*
X1061456Y406560D03*
X1063614Y733409D03*
X1057057Y756765D03*
X1061607Y773563D03*
X1057057Y763765D03*
X1057207Y791969D03*
X1056157Y786949D03*
X1061607Y780256D03*
Y803681D03*
X1056157Y796988D03*
X1061607Y810374D03*
Y817067D03*
X1056157Y823760D03*
Y833799D03*
X1057207Y828780D03*
X1061607Y847185D03*
Y840492D03*
Y853878D03*
X1056157Y860571D03*
X1057207Y865591D03*
X1056157Y870610D03*
X1061607Y877303D03*
Y883996D03*
Y890689D03*
X1056157Y907422D03*
Y897382D03*
X1057207Y902402D03*
X1061607Y914114D03*
Y920807D03*
Y927500D03*
X1056157Y934193D03*
X1057207Y939213D03*
X1061607Y950925D03*
X1056157Y944233D03*
X1061607Y964311D03*
Y971004D03*
Y957618D03*
Y977697D03*
Y984390D03*
Y991083D03*
Y997776D03*
Y1004469D03*
Y1037933D03*
Y1044626D03*
Y1031240D03*
Y1051319D03*
Y1058012D03*
Y1074744D03*
Y1068051D03*
X1057207Y1086457D03*
X1056157Y1081437D03*
Y1091477D03*
X1061607Y1098170D03*
Y1104862D03*
X1056157Y1118248D03*
X1061607Y1111555D03*
Y1134981D03*
X1057207Y1123268D03*
X1056157Y1128288D03*
X1061607Y1141674D03*
Y1148366D03*
X1056157Y1155059D03*
Y1165099D03*
X1057207Y1160079D03*
X1061607Y1171792D03*
Y1178485D03*
X1056157Y1191870D03*
X1061607Y1185177D03*
X1056157Y1201910D03*
X1057207Y1196890D03*
X1061607Y1208603D03*
Y1215296D03*
Y1221988D03*
X1056157Y1238721D03*
X1057207Y1233701D03*
X1056157Y1228681D03*
X1061607Y1245414D03*
Y1252107D03*
X1060684Y1350724D03*
X1057684D03*
X1054684D03*
X1056584Y1523080D03*
Y1520080D03*
Y1526080D03*
X1063751Y1653834D03*
X1064221Y1662726D03*
X1068221Y1662778D03*
X1068827Y389734D03*
X1074800Y391262D03*
X1077418Y411322D03*
Y416763D03*
Y421922D03*
X1081133Y461516D03*
X1071239Y479655D03*
X1081632Y648854D03*
X1079716Y756765D03*
Y760265D03*
Y767265D03*
X1075166Y776910D03*
Y783603D03*
X1070766Y795315D03*
X1075166Y807028D03*
Y813721D03*
Y820414D03*
X1070766Y832126D03*
X1075166Y850532D03*
Y843839D03*
Y857225D03*
X1070766Y868937D03*
X1075166Y880650D03*
Y887343D03*
Y894036D03*
X1070766Y905749D03*
X1075166Y917461D03*
Y924154D03*
Y930847D03*
X1070766Y942560D03*
X1075166Y954272D03*
Y967658D03*
Y960965D03*
Y974351D03*
Y981044D03*
Y987736D03*
Y994429D03*
Y1004469D03*
Y1034587D03*
Y1041280D03*
Y1047973D03*
Y1054666D03*
Y1061359D03*
Y1071398D03*
Y1078091D03*
X1070766Y1089804D03*
X1075166Y1101516D03*
Y1108209D03*
Y1114902D03*
X1070766Y1126615D03*
X1075166Y1138327D03*
Y1145020D03*
Y1151713D03*
X1070766Y1163426D03*
X1075166Y1175138D03*
Y1188524D03*
Y1181831D03*
X1070766Y1200237D03*
X1075166Y1211949D03*
Y1218642D03*
X1070766Y1237048D03*
X1075166Y1225335D03*
Y1248760D03*
Y1255453D03*
X1070949Y1337752D03*
X1067929Y1337702D03*
X1079215Y1357390D03*
X1076615D03*
X1071908Y1361660D03*
X1080889Y1367253D03*
X1076615Y1360497D03*
X1079215D03*
X1078459Y1367253D03*
Y1372853D03*
X1080889D03*
X1073733Y1388198D03*
X1068094Y1654099D03*
X1084199Y49379D03*
X1086936Y370532D03*
X1083583Y395195D03*
X1093722Y427960D03*
X1087000Y477500D03*
X1096473Y484391D03*
Y489391D03*
X1088730Y509362D03*
X1086758Y756765D03*
X1091308Y773563D03*
X1086758Y763765D03*
X1086908Y791969D03*
X1091308Y780256D03*
X1085858Y786949D03*
X1091308Y803681D03*
X1085858Y796988D03*
X1091308Y810374D03*
Y817067D03*
X1085858Y823760D03*
Y833799D03*
X1086908Y828780D03*
X1091308Y840492D03*
Y847185D03*
Y853878D03*
X1085858Y860571D03*
X1086908Y865591D03*
X1085858Y870610D03*
X1091308Y877303D03*
Y883996D03*
Y890689D03*
X1085858Y907422D03*
Y897382D03*
X1086908Y902402D03*
X1091308Y914114D03*
Y920807D03*
X1085858Y934193D03*
X1091308Y927500D03*
X1086908Y939213D03*
X1085858Y944233D03*
X1091308Y950925D03*
Y964311D03*
Y971004D03*
Y957618D03*
Y977697D03*
Y984390D03*
Y991083D03*
Y997776D03*
Y1004469D03*
Y1031240D03*
Y1037933D03*
Y1044626D03*
Y1051319D03*
Y1058012D03*
Y1074744D03*
Y1068051D03*
X1086908Y1086457D03*
X1085858Y1081437D03*
Y1091477D03*
X1091308Y1098170D03*
Y1104862D03*
X1085858Y1118248D03*
X1091308Y1111555D03*
Y1134981D03*
X1086908Y1123268D03*
X1085858Y1128288D03*
X1091308Y1141674D03*
Y1148366D03*
X1085858Y1155059D03*
Y1165099D03*
X1086908Y1160079D03*
X1091308Y1171792D03*
Y1178485D03*
X1085858Y1191870D03*
X1091308Y1185177D03*
X1085858Y1201910D03*
X1086908Y1196890D03*
X1091308Y1208603D03*
Y1215296D03*
Y1221988D03*
X1085858Y1238721D03*
Y1228681D03*
X1086908Y1233701D03*
X1091308Y1245414D03*
Y1252107D03*
X1095809Y1337824D03*
X1087015Y1357390D03*
X1095629Y1352252D03*
Y1349652D03*
Y1354852D03*
X1089515Y1357390D03*
X1091959Y1357406D03*
X1084415Y1357390D03*
X1081815D03*
X1092905Y1363394D03*
Y1360437D03*
X1083319Y1367253D03*
X1081815Y1360497D03*
X1084415D03*
X1081815Y1363454D03*
X1084415D03*
X1083319Y1372853D03*
X1083368Y1385268D03*
X1096469Y1643468D03*
X1090143Y1643625D03*
X1091026Y1653031D03*
X1092030Y1720841D03*
X1106199Y49379D03*
X1101942Y395361D03*
X1109416Y756765D03*
Y760265D03*
Y767265D03*
X1104866Y776910D03*
Y783603D03*
X1100466Y795315D03*
X1104866Y807028D03*
Y813721D03*
Y820414D03*
X1100466Y832126D03*
X1104866Y850532D03*
Y843839D03*
Y857225D03*
X1100466Y868937D03*
X1104866Y880650D03*
Y887343D03*
Y894036D03*
X1100466Y905749D03*
X1104866Y917461D03*
Y924154D03*
Y930847D03*
X1100466Y942560D03*
X1104866Y954272D03*
Y967658D03*
Y960965D03*
Y974351D03*
Y981044D03*
Y987736D03*
Y994429D03*
Y1004469D03*
Y1034587D03*
Y1041280D03*
Y1047973D03*
Y1054666D03*
Y1071398D03*
Y1061359D03*
Y1078091D03*
X1100466Y1089804D03*
X1104866Y1101516D03*
Y1108209D03*
Y1114902D03*
X1100466Y1126615D03*
X1104866Y1138327D03*
Y1145020D03*
Y1151713D03*
X1100466Y1163426D03*
X1104866Y1175138D03*
Y1188524D03*
Y1181831D03*
X1100466Y1200237D03*
X1104866Y1211949D03*
Y1218642D03*
X1100466Y1237048D03*
X1104866Y1225335D03*
Y1248760D03*
Y1255453D03*
X1103529Y1337792D03*
X1109289Y1337752D03*
X1098409Y1337824D03*
X1109215Y1357390D03*
X1098229Y1352252D03*
Y1349652D03*
X1096979Y1357352D03*
X1098229Y1354852D03*
X1104448Y1361680D03*
X1109215Y1360497D03*
X1111059Y1367253D03*
Y1372853D03*
X1103888Y1386721D03*
X1102230Y1384770D03*
X1105000Y1682132D03*
X1109521Y1724109D03*
X1113943Y452055D03*
X1116458Y756765D03*
X1121008Y773563D03*
X1116459Y763765D03*
X1116608Y791969D03*
X1121008Y780256D03*
X1115558Y786949D03*
X1121008Y803681D03*
X1115558Y796988D03*
X1121008Y810374D03*
Y817067D03*
X1115558Y823760D03*
Y833799D03*
X1116608Y828780D03*
X1121008Y847185D03*
Y840492D03*
Y853878D03*
X1115558Y860571D03*
X1116608Y865591D03*
X1115558Y870610D03*
X1121008Y877303D03*
Y883996D03*
Y890689D03*
X1115558Y907422D03*
Y897382D03*
X1116608Y902402D03*
X1121008Y914114D03*
Y920807D03*
X1115558Y934193D03*
X1121008Y927500D03*
X1116608Y939213D03*
X1115558Y944233D03*
X1121008Y950925D03*
Y964311D03*
Y971004D03*
Y957618D03*
Y977697D03*
Y984390D03*
Y991083D03*
Y997776D03*
Y1004469D03*
Y1031240D03*
Y1037933D03*
Y1044626D03*
Y1051319D03*
Y1058012D03*
Y1074744D03*
Y1068051D03*
X1116608Y1086457D03*
X1115558Y1081437D03*
Y1091477D03*
X1121008Y1098170D03*
Y1104862D03*
X1115558Y1118248D03*
X1121008Y1111555D03*
Y1134981D03*
X1116608Y1123268D03*
X1115558Y1128288D03*
X1121008Y1141674D03*
Y1148366D03*
X1115558Y1155059D03*
Y1165099D03*
X1116608Y1160079D03*
X1121008Y1171792D03*
Y1178485D03*
X1115558Y1191870D03*
X1121008Y1185177D03*
X1115558Y1201910D03*
X1116608Y1196890D03*
X1121008Y1208603D03*
Y1215296D03*
Y1221988D03*
X1115558Y1238721D03*
Y1228681D03*
X1116608Y1233701D03*
X1121008Y1245414D03*
Y1252107D03*
X1119615Y1357390D03*
X1122115D03*
X1124559Y1357406D03*
X1117015Y1357390D03*
X1111815D03*
X1114415D03*
X1117015Y1363454D03*
Y1360497D03*
X1115919Y1372853D03*
X1125505Y1363394D03*
Y1360437D03*
X1115919Y1367253D03*
X1113489D03*
X1114415Y1363454D03*
X1111815Y1360497D03*
X1114415D03*
X1113489Y1372853D03*
X1115968Y1385268D03*
X1117946Y1467955D03*
X1117828Y1473091D03*
X1118326Y1594118D03*
X1118004Y1584908D03*
X1113785Y1601462D03*
X1117263Y1601526D03*
X1115394Y1620306D03*
X1120376Y1641684D03*
X1125487Y1641754D03*
X1125771Y1652189D03*
X1120595Y1652037D03*
X1120200Y1646597D03*
X1116000Y1671029D03*
X1125732Y1666072D03*
X1120303Y1682055D03*
X1113948Y1714244D03*
X1128199Y49379D03*
X1142830Y53186D03*
X1139200Y380533D03*
Y385698D03*
X1127471Y404788D03*
X1132387Y615658D03*
X1139117Y756765D03*
Y760265D03*
Y767265D03*
X1134567Y776910D03*
Y783603D03*
X1130167Y795315D03*
X1134567Y807028D03*
Y813721D03*
Y820414D03*
X1130167Y832126D03*
X1134567Y850532D03*
Y843839D03*
Y857225D03*
X1130167Y868937D03*
X1134567Y880650D03*
Y887343D03*
Y894036D03*
X1130167Y905749D03*
X1134567Y917461D03*
Y924154D03*
Y930847D03*
X1130167Y942560D03*
X1134567Y954272D03*
Y967658D03*
Y960965D03*
Y974351D03*
Y981044D03*
Y987736D03*
Y994429D03*
Y1004469D03*
Y1034587D03*
Y1041280D03*
Y1047973D03*
Y1054666D03*
Y1061359D03*
Y1071398D03*
X1130167Y1089804D03*
X1134567Y1078091D03*
Y1101516D03*
Y1108209D03*
Y1114902D03*
X1130167Y1126615D03*
X1134567Y1138327D03*
Y1145020D03*
X1130167Y1163426D03*
X1134567Y1151713D03*
Y1175138D03*
Y1188524D03*
Y1181831D03*
X1130167Y1200237D03*
X1134567Y1211949D03*
Y1218642D03*
X1130167Y1237048D03*
X1134567Y1225335D03*
Y1248760D03*
Y1255453D03*
X1136219Y1337794D03*
X1133619D03*
X1130829Y1352252D03*
Y1349652D03*
Y1354852D03*
X1128229Y1352252D03*
Y1349652D03*
X1129579Y1357352D03*
X1128229Y1354852D03*
X1137218Y1361660D03*
X1136588Y1386721D03*
X1134930Y1384770D03*
X1137846Y1453487D03*
X1135043Y1553371D03*
X1137523Y1579453D03*
X1136173Y1573638D03*
X1131790Y1597984D03*
X1131832Y1607245D03*
X1132168Y1620860D03*
X1138752Y1624627D03*
X1130772Y1641753D03*
X1130684Y1646949D03*
X1130245Y1652189D03*
X1140117Y1671421D03*
X1132209Y1672033D03*
X1129230Y1666174D03*
X1137492Y1685240D03*
X1128934Y1688600D03*
X1150199Y49379D03*
X1155577Y73939D03*
X1147813Y492319D03*
X1146159Y756765D03*
X1150709Y773563D03*
X1146160Y763765D03*
X1146309Y791969D03*
X1145259Y786949D03*
X1150709Y780256D03*
X1145259Y796988D03*
X1150709Y803681D03*
Y810374D03*
Y817067D03*
X1146309Y828780D03*
X1145259Y823760D03*
Y833799D03*
X1150709Y840492D03*
Y847185D03*
X1146309Y865591D03*
X1145259Y860571D03*
X1150709Y853878D03*
X1145259Y870610D03*
X1150709Y877303D03*
Y883996D03*
Y890689D03*
X1145259Y907422D03*
X1146309Y902402D03*
X1145259Y897382D03*
X1150709Y914114D03*
Y920807D03*
X1145259Y934193D03*
X1146309Y939213D03*
X1150709Y927500D03*
X1145259Y944233D03*
X1150709Y950925D03*
Y964311D03*
Y971004D03*
Y957618D03*
Y977697D03*
Y984390D03*
Y991083D03*
Y997776D03*
Y1004469D03*
Y1031240D03*
Y1037933D03*
Y1044626D03*
Y1051319D03*
Y1058012D03*
Y1074744D03*
Y1068051D03*
X1146309Y1086457D03*
X1145259Y1081437D03*
Y1091477D03*
X1150709Y1098170D03*
Y1104862D03*
X1145259Y1118248D03*
X1150709Y1111555D03*
Y1134981D03*
X1146309Y1123268D03*
X1145259Y1128288D03*
X1150709Y1141674D03*
Y1148366D03*
X1145259Y1155059D03*
X1146309Y1160079D03*
X1145259Y1165099D03*
X1150709Y1171792D03*
Y1178485D03*
X1145259Y1191870D03*
X1150709Y1185177D03*
X1145259Y1201910D03*
X1146309Y1196890D03*
X1150709Y1208603D03*
Y1215296D03*
Y1221988D03*
X1145259Y1238721D03*
X1146309Y1233701D03*
X1145259Y1228681D03*
X1150709Y1245414D03*
Y1252107D03*
X1154839Y1337834D03*
X1145819D03*
X1143219D03*
X1152315Y1357390D03*
X1154815D03*
X1147115D03*
X1149715D03*
X1141915D03*
X1144515D03*
X1147115Y1360497D03*
X1149715Y1363454D03*
Y1360497D03*
X1147115Y1363454D03*
X1146189Y1372853D03*
X1148619D03*
Y1367253D03*
X1146189D03*
X1141915Y1360497D03*
X1144515D03*
X1143759Y1367253D03*
Y1372853D03*
X1148668Y1385268D03*
X1150458Y1433146D03*
X1144118Y1449628D03*
X1151384Y1556029D03*
X1143063Y1580334D03*
X1152186Y1570567D03*
X1149278Y1589453D03*
X1145060Y1588837D03*
X1141645Y1640017D03*
X1146316Y1649422D03*
X1143127Y1649068D03*
X1144107Y1671118D03*
X1146477Y1658441D03*
X1168687Y74202D03*
X1163113Y481691D03*
X1165589Y569118D03*
X1168818Y756765D03*
Y760265D03*
X1164268Y776910D03*
X1168818Y767265D03*
X1164268Y783603D03*
X1159868Y795315D03*
X1164268Y807028D03*
Y820414D03*
Y813721D03*
X1159868Y832126D03*
X1164268Y850532D03*
Y843839D03*
Y857225D03*
X1159868Y868937D03*
X1164268Y880650D03*
Y887343D03*
Y894036D03*
X1159868Y905749D03*
X1164268Y917461D03*
Y924154D03*
Y930847D03*
X1159868Y942560D03*
X1164268Y954272D03*
Y960965D03*
Y967658D03*
Y974351D03*
Y981044D03*
Y987736D03*
Y994429D03*
Y1004469D03*
Y1034587D03*
Y1041280D03*
Y1047973D03*
Y1054666D03*
Y1061359D03*
Y1071398D03*
X1159868Y1089804D03*
X1164268Y1078091D03*
Y1101516D03*
Y1108209D03*
Y1114902D03*
X1159868Y1126615D03*
X1164268Y1138327D03*
Y1145020D03*
X1159868Y1163426D03*
X1164268Y1151713D03*
Y1175138D03*
Y1181831D03*
Y1188524D03*
X1159868Y1200237D03*
X1164268Y1211949D03*
Y1218642D03*
X1159868Y1237048D03*
X1164268Y1225335D03*
Y1248760D03*
Y1255453D03*
X1167509Y1337884D03*
X1164909D03*
X1157439Y1337834D03*
X1160929Y1352252D03*
X1163529D03*
X1160929Y1349652D03*
X1163529D03*
X1162279Y1357352D03*
X1163529Y1354852D03*
X1157259Y1357406D03*
X1170138Y1361800D03*
X1158205Y1363394D03*
Y1360437D03*
X1169488Y1386721D03*
X1167830Y1384770D03*
X1161311Y1548204D03*
X1172523Y1573250D03*
X1160031Y1591163D03*
X1162144Y1658042D03*
X1159741Y1669759D03*
X1169187Y1687117D03*
X1174958Y-24648D03*
Y5352D03*
Y15352D03*
X1177429Y89556D03*
Y93556D03*
X1185952Y432202D03*
Y440202D03*
Y448202D03*
X1185707Y465272D03*
Y460202D03*
Y470392D03*
X1185117Y571807D03*
X1181445Y592868D03*
X1175860Y756765D03*
X1180410Y773563D03*
X1175860Y763765D03*
X1176010Y791969D03*
X1180410Y780256D03*
X1174960Y786949D03*
X1180410Y803681D03*
X1174960Y796988D03*
X1180410Y817067D03*
Y810374D03*
X1176010Y828780D03*
X1174960Y833799D03*
Y823760D03*
X1180410Y847185D03*
Y840492D03*
X1176010Y865591D03*
X1180410Y853878D03*
X1174960Y860571D03*
X1180410Y877303D03*
X1174960Y870610D03*
X1180410Y890689D03*
Y883996D03*
X1176010Y902402D03*
X1174960Y897382D03*
Y907422D03*
X1180410Y914114D03*
Y920807D03*
X1176010Y939213D03*
X1174960Y934193D03*
X1180410Y927500D03*
X1174960Y944233D03*
X1180410Y950925D03*
Y957618D03*
Y964311D03*
Y971004D03*
Y977697D03*
Y984390D03*
Y991083D03*
Y997776D03*
Y1004469D03*
Y1031240D03*
Y1037933D03*
Y1044626D03*
Y1051319D03*
Y1058012D03*
Y1068051D03*
Y1074744D03*
X1176010Y1086457D03*
X1174960Y1081437D03*
Y1091477D03*
X1180410Y1098170D03*
Y1104862D03*
X1174960Y1118248D03*
X1180410Y1111555D03*
X1176010Y1123268D03*
X1174960Y1128288D03*
X1180410Y1134981D03*
Y1141674D03*
Y1148366D03*
X1176010Y1160079D03*
X1174960Y1155059D03*
Y1165099D03*
X1180410Y1171792D03*
Y1178485D03*
X1174960Y1191870D03*
X1180410Y1185177D03*
X1176010Y1196890D03*
X1174960Y1201910D03*
X1180410Y1208603D03*
Y1215296D03*
Y1221988D03*
X1176010Y1233701D03*
X1174960Y1238721D03*
Y1228681D03*
X1180410Y1245414D03*
Y1252107D03*
X1182615Y1357390D03*
X1185215D03*
X1177415D03*
X1174815D03*
X1180015D03*
X1182615Y1363454D03*
Y1360497D03*
X1180015Y1363454D03*
X1174815Y1360497D03*
X1177415D03*
X1180015D03*
X1176659Y1367253D03*
Y1372853D03*
X1179089D03*
X1181519D03*
Y1367253D03*
X1179089D03*
X1181568Y1385268D03*
X1185000Y1396500D03*
Y1401000D03*
X1184100Y1410000D03*
X1185000Y1405500D03*
X1178400Y1433000D03*
X1181324Y1485895D03*
X1183234Y1483295D03*
Y1488495D03*
X1181314Y1492995D03*
X1176534D03*
X1174624Y1495595D03*
X1181314Y1498195D03*
X1176534D03*
X1180047Y1533247D03*
X1181853Y1561731D03*
X1172523Y1562350D03*
X1179187Y1666429D03*
X1175454Y1668046D03*
X1178932Y1686698D03*
X1185676Y1697249D03*
X1194199Y49379D03*
X1198694Y57015D03*
X1191488Y87125D03*
Y91125D03*
X1200518Y100875D03*
X1189701Y173187D03*
X1201157Y431875D03*
X1189540Y481691D03*
X1188192Y589263D03*
X1191646Y589567D03*
X1195729Y591022D03*
X1198519Y756765D03*
Y760265D03*
X1193969Y776910D03*
X1198519Y767265D03*
X1193969Y783603D03*
X1189569Y795315D03*
X1193969Y807028D03*
Y820414D03*
Y813721D03*
X1189569Y832126D03*
X1193969Y850532D03*
Y843839D03*
Y857225D03*
X1189569Y868937D03*
X1193969Y880650D03*
Y887343D03*
Y894036D03*
X1189569Y905749D03*
X1193969Y917461D03*
Y924154D03*
Y930847D03*
Y954272D03*
X1189569Y942560D03*
X1193969Y960965D03*
Y967658D03*
Y974351D03*
Y981044D03*
Y987736D03*
Y994429D03*
Y1004469D03*
Y1034587D03*
Y1041280D03*
Y1047973D03*
Y1054666D03*
Y1061359D03*
Y1071398D03*
X1189569Y1089804D03*
X1193969Y1078091D03*
Y1101516D03*
Y1108209D03*
Y1114902D03*
X1189569Y1126615D03*
X1193969Y1138327D03*
Y1145020D03*
X1189569Y1163426D03*
X1193969Y1151713D03*
Y1175138D03*
Y1181831D03*
Y1188524D03*
X1189569Y1200237D03*
X1193969Y1211949D03*
Y1218642D03*
X1189569Y1237048D03*
X1193969Y1225335D03*
Y1248760D03*
Y1255453D03*
X1196159Y1326549D03*
X1193659Y1326589D03*
Y1324049D03*
X1196259D03*
X1193659Y1321549D03*
X1196259D03*
X1199899Y1338065D03*
X1193829Y1352252D03*
X1196429D03*
X1193829Y1349652D03*
X1196429D03*
X1193829Y1354852D03*
X1190159Y1357406D03*
X1195179Y1357352D03*
X1196429Y1354852D03*
X1187715Y1357390D03*
X1191105Y1363394D03*
Y1360437D03*
X1200690Y1384572D03*
X1194000Y1418000D03*
X1187925Y1417000D03*
X1194000Y1428500D03*
Y1433000D03*
X1187925Y1440400D03*
X1188014Y1483295D03*
Y1488495D03*
X1194724Y1505295D03*
X1196634Y1502695D03*
Y1507895D03*
X1196127Y1583797D03*
X1195261Y1622884D03*
X1200217D03*
X1195050Y1620040D03*
X1195261Y1627876D03*
X1200217D03*
Y1654796D03*
X1195261D03*
X1200217Y1659788D03*
X1195261D03*
X1192903Y1666276D03*
X1189462Y1691366D03*
X1196767Y1712261D03*
X1196814Y1726261D03*
X1215528Y172395D03*
X1214156Y292066D03*
X1214856Y421018D03*
X1213866Y455376D03*
X1208400Y591631D03*
X1201440Y668138D03*
X1207177Y668115D03*
X1205561Y756765D03*
X1210111Y773563D03*
X1205561Y763765D03*
X1205711Y791969D03*
X1210111Y780256D03*
X1204661Y786949D03*
X1210111Y803681D03*
X1204661Y796988D03*
X1210111Y817067D03*
Y810374D03*
X1205711Y828780D03*
X1204661Y833799D03*
Y823760D03*
X1210111Y847185D03*
Y840492D03*
X1205711Y865591D03*
X1210111Y853878D03*
X1204661Y860571D03*
X1210111Y877303D03*
X1204661Y870610D03*
X1210111Y890689D03*
Y883996D03*
X1205711Y902402D03*
X1204661Y897382D03*
Y907422D03*
X1210111Y914114D03*
Y920807D03*
X1205711Y939213D03*
X1204661Y934193D03*
X1210111Y927500D03*
X1204661Y944233D03*
X1210111Y950925D03*
Y957618D03*
Y964311D03*
Y971004D03*
Y977697D03*
Y984390D03*
Y991083D03*
Y997776D03*
Y1004469D03*
Y1031240D03*
Y1037933D03*
Y1044626D03*
Y1051319D03*
Y1058012D03*
Y1068051D03*
Y1074744D03*
X1205711Y1086457D03*
X1204661Y1081437D03*
Y1091477D03*
X1210111Y1098170D03*
Y1104862D03*
X1204661Y1118248D03*
X1210111Y1111555D03*
X1205711Y1123268D03*
X1204661Y1128288D03*
X1210111Y1134981D03*
Y1141674D03*
Y1148366D03*
X1205711Y1160079D03*
X1204661Y1155059D03*
Y1165099D03*
X1210111Y1171792D03*
Y1178485D03*
X1204661Y1191870D03*
X1210111Y1185177D03*
X1205711Y1196890D03*
X1204661Y1201910D03*
X1210111Y1208603D03*
Y1215296D03*
Y1221988D03*
X1205711Y1233701D03*
X1204661Y1228681D03*
Y1238721D03*
X1210111Y1245414D03*
Y1252107D03*
X1205189Y1321492D03*
Y1323992D03*
X1202689Y1321492D03*
Y1324032D03*
X1211299Y1338105D03*
X1202399D03*
X1215415Y1357390D03*
X1212815D03*
X1210215D03*
X1207615D03*
X1202988Y1361490D03*
X1215415Y1363454D03*
Y1360497D03*
X1212815Y1363454D03*
Y1360497D03*
X1210215D03*
X1207615D03*
X1214319Y1372853D03*
X1211889D03*
X1209459D03*
Y1367253D03*
X1214319D03*
X1211889D03*
X1214368Y1385268D03*
X1202288Y1386721D03*
X1202484Y1402467D03*
X1203334Y1492995D03*
X1208114D03*
X1210034Y1483295D03*
X1214814D03*
X1208124Y1485895D03*
X1210034Y1488495D03*
X1214814D03*
X1201424Y1495595D03*
X1203334Y1498195D03*
X1208114D03*
X1201414Y1502695D03*
Y1507895D03*
X1200851Y1583797D03*
X1205576Y1583897D03*
X1210300Y1583697D03*
X1215025Y1583897D03*
X1207321Y1622884D03*
X1212277D03*
X1201291Y1637876D03*
Y1632884D03*
X1206247D03*
Y1637876D03*
X1213351D03*
Y1632884D03*
X1207321Y1627876D03*
X1212277D03*
X1207321Y1654796D03*
X1206247Y1649788D03*
X1201291D03*
X1212277Y1654796D03*
X1213351Y1649788D03*
X1206247Y1644796D03*
X1201291D03*
X1213351D03*
X1207321Y1659788D03*
X1212277D03*
X1204804Y1691375D03*
X1216199Y49379D03*
X1230156Y292066D03*
X1222094Y286948D03*
X1219463Y1338122D03*
X1229809Y1338105D03*
X1226629Y1352252D03*
X1229229D03*
X1226629Y1349652D03*
X1229229D03*
X1222959Y1357406D03*
X1227979Y1357352D03*
X1226629Y1354852D03*
X1229229D03*
X1220515Y1357390D03*
X1218015D03*
X1223905Y1363394D03*
Y1360437D03*
X1230134Y1492995D03*
X1228224Y1495595D03*
X1221524Y1505295D03*
X1230134Y1498195D03*
X1228214Y1502695D03*
X1223434D03*
Y1507895D03*
X1228214D03*
X1219749Y1583897D03*
X1224474Y1583697D03*
X1229198Y1583797D03*
X1219381Y1622884D03*
X1224337D03*
X1218307Y1637876D03*
Y1632884D03*
X1230367Y1637876D03*
X1225411D03*
X1230367Y1632884D03*
X1225411D03*
X1219381Y1627876D03*
X1224337D03*
Y1654796D03*
X1219381D03*
X1218307Y1649788D03*
X1225411D03*
X1230367D03*
X1218307Y1644796D03*
X1225411D03*
X1230367D03*
X1224337Y1659788D03*
X1219381D03*
X1219738Y1717011D03*
Y1731011D03*
X1236844Y-34348D03*
X1236829Y-36863D03*
X1236798Y-31476D03*
X1236813Y-28961D03*
X1240097Y-34334D03*
X1243122Y-35654D03*
X1240082Y-36849D03*
X1236877Y-26227D03*
X1236932Y-19948D03*
X1236942Y-13666D03*
X1236927Y-16181D03*
X1236892Y-23712D03*
X1240130Y-26213D03*
X1240194Y-19948D03*
X1240195Y-13652D03*
X1243220Y-14972D03*
X1240180Y-16167D03*
X1240145Y-23698D03*
X1243170Y-25018D03*
X1236932Y-9948D03*
Y52D03*
X1236942Y-3666D03*
X1236927Y-6181D03*
X1240194Y-9948D03*
Y52D03*
X1240195Y-3652D03*
X1243220Y-4972D03*
X1240180Y-6167D03*
X1236927Y13819D03*
X1236942Y16334D03*
X1236932Y10052D03*
X1236942Y6334D03*
X1236927Y3819D03*
X1240180Y13833D03*
X1243220Y15028D03*
X1240195Y16348D03*
X1240194Y10052D03*
X1240195Y6348D03*
X1243220Y5028D03*
X1240180Y3833D03*
X1236911Y21721D03*
X1236896Y19206D03*
X1236941Y26751D03*
X1236926Y24236D03*
X1243219Y25445D03*
X1240194Y26765D03*
X1240179Y24250D03*
X1238199Y49379D03*
X1245606Y1314351D03*
Y1311244D03*
X1240899Y1315460D03*
X1240240Y1339578D03*
X1232409Y1338105D03*
X1242500Y1430075D03*
X1237100Y1442500D03*
X1242500Y1437075D03*
X1234924Y1485895D03*
X1241614Y1483295D03*
X1236834D03*
X1241614Y1488495D03*
X1236834D03*
X1234914Y1492995D03*
Y1498195D03*
X1233923Y1583897D03*
X1238647D03*
X1243372D03*
X1231441Y1622884D03*
X1236397D03*
X1243501D03*
X1237471Y1637876D03*
Y1632884D03*
X1242427Y1637876D03*
Y1632884D03*
X1236397Y1627876D03*
X1231441D03*
X1243501D03*
X1231441Y1654796D03*
X1236397D03*
X1237471Y1649788D03*
X1243501Y1654796D03*
X1242427Y1649788D03*
X1237471Y1644796D03*
X1242427D03*
X1231441Y1659788D03*
X1236397D03*
X1243501D03*
X1260199Y49379D03*
X1256064Y101100D03*
X1254094Y286948D03*
X1245825Y305275D03*
X1260227Y407128D03*
Y411128D03*
X1248902Y470733D03*
X1257016Y467253D03*
X1246490Y483302D03*
X1257450Y1291721D03*
X1260050D03*
X1249650D03*
X1247050D03*
X1258506Y1311244D03*
X1256006D03*
X1253406Y1314351D03*
X1250806D03*
X1253406Y1311244D03*
X1250806D03*
X1248206Y1314351D03*
Y1311244D03*
X1252310Y1321107D03*
X1249880D03*
X1252310Y1326707D03*
X1253406Y1317308D03*
X1250806D03*
X1247450Y1326707D03*
Y1321107D03*
X1249880Y1326707D03*
X1252359Y1339122D03*
X1252315Y1417085D03*
X1254905Y1417026D03*
X1256934Y1492995D03*
X1255024Y1495595D03*
X1248324Y1505295D03*
X1256934Y1498195D03*
X1255014Y1502695D03*
X1250234D03*
X1255014Y1507895D03*
X1250234D03*
X1248096Y1583897D03*
X1252820Y1583697D03*
X1257544Y1583897D03*
X1248457Y1622884D03*
X1255561D03*
X1254487Y1637876D03*
Y1632884D03*
X1249531Y1637876D03*
Y1632884D03*
X1248457Y1627876D03*
X1255561D03*
X1248457Y1654796D03*
X1254487Y1649788D03*
X1249531D03*
X1255561Y1654796D03*
X1254487Y1644796D03*
X1249531D03*
X1248657Y1659588D03*
X1255561Y1659788D03*
X1266146Y121022D03*
X1263582Y164051D03*
Y160051D03*
Y180551D03*
Y176051D03*
Y172051D03*
Y168051D03*
Y185051D03*
X1270094Y286948D03*
X1262156Y292066D03*
X1270670Y1291624D03*
X1268070D03*
X1261896Y1314291D03*
X1260950Y1311260D03*
X1267220Y1306106D03*
Y1308706D03*
Y1303506D03*
X1265970Y1311206D03*
X1264620Y1303506D03*
Y1306106D03*
Y1308706D03*
X1273869Y1315300D03*
X1261896Y1317248D03*
X1273175Y1340547D03*
X1271517Y1338596D03*
X1275124Y1485895D03*
X1261724D03*
X1263634Y1483295D03*
X1268414D03*
X1263634Y1488495D03*
X1268414D03*
X1261714Y1492995D03*
Y1498195D03*
X1262269Y1583897D03*
X1266993Y1583797D03*
X1267621Y1622884D03*
X1260517D03*
X1272577D03*
X1261591Y1637876D03*
X1266547D03*
X1261591Y1632884D03*
X1266547D03*
X1273651Y1637876D03*
Y1632790D03*
X1267621Y1627876D03*
X1260517D03*
X1272577D03*
X1260517Y1654796D03*
X1267621D03*
X1266547Y1649788D03*
X1261591D03*
X1272577Y1654796D03*
X1273651Y1649788D03*
X1266547Y1644796D03*
X1261591D03*
X1273651D03*
X1260517Y1659788D03*
X1267621D03*
X1272577D03*
X1282199Y49379D03*
X1278111Y150030D03*
X1285391Y142553D03*
X1286094Y286948D03*
X1278156Y292066D03*
X1277598Y404428D03*
X1282165Y408987D03*
X1288202Y405741D03*
X1288902Y1311216D03*
X1286302Y1314323D03*
X1283702D03*
X1286302Y1311216D03*
X1283702D03*
X1278502Y1314323D03*
X1281102D03*
Y1311216D03*
X1278502D03*
X1285206Y1326679D03*
X1286302Y1317280D03*
X1283702D03*
X1285206Y1321079D03*
X1282776D03*
Y1326679D03*
X1280346Y1321079D03*
Y1326679D03*
X1285255Y1339094D03*
X1277034Y1483295D03*
X1281814D03*
X1277034Y1488495D03*
X1281814D03*
X1284510Y1556953D03*
X1278012Y1581563D03*
X1279681Y1622884D03*
X1284637D03*
X1278607Y1637876D03*
Y1632790D03*
X1285711Y1637876D03*
Y1632884D03*
X1279681Y1627876D03*
X1284637D03*
X1279681Y1654796D03*
X1278607Y1649788D03*
X1284637Y1654796D03*
X1285711Y1649788D03*
X1278607Y1644796D03*
X1285711D03*
X1279681Y1659788D03*
X1284637D03*
X1304199Y49379D03*
X1300668Y125739D03*
Y133739D03*
Y129739D03*
X1306431Y149330D03*
X1300668Y145739D03*
X1292082Y166051D03*
Y162051D03*
Y171551D03*
Y184051D03*
X1302094Y298066D03*
Y286948D03*
X1294156Y292066D03*
X1293277Y401125D03*
X1296228Y408125D03*
X1299076Y530023D03*
X1297487Y590607D03*
X1302890Y1291759D03*
X1298350Y1291721D03*
X1295750D03*
X1300116Y1306078D03*
Y1303478D03*
Y1308678D03*
X1298866Y1311178D03*
X1294792Y1314263D03*
X1297516Y1306078D03*
Y1303478D03*
Y1308678D03*
X1291402Y1311216D03*
X1293846Y1311232D03*
X1294792Y1317220D03*
X1304421Y1338539D03*
X1304596Y1492995D03*
X1302686Y1495595D03*
X1304596Y1498195D03*
X1291819Y1563595D03*
X1294319D03*
X1300560Y1554261D03*
X1291741Y1622884D03*
X1296697D03*
X1303801D03*
X1290667Y1637876D03*
Y1632884D03*
X1297771Y1637876D03*
Y1632884D03*
X1302727Y1637876D03*
Y1632884D03*
X1296697Y1627876D03*
X1291741D03*
X1303801D03*
X1291741Y1654796D03*
X1296697D03*
X1297771Y1649788D03*
X1290667D03*
X1303801Y1654796D03*
X1302727Y1649788D03*
X1297771Y1644796D03*
X1290667D03*
X1302727D03*
X1291741Y1659788D03*
X1296697D03*
X1303801D03*
X1306449Y92185D03*
X1306431Y152830D03*
X1310156Y292066D03*
X1305600Y1291759D03*
X1316606Y1314266D03*
Y1311159D03*
X1314006Y1314266D03*
Y1311159D03*
X1319206Y1314266D03*
Y1311159D03*
X1311406Y1314266D03*
Y1311159D03*
X1306799Y1315440D03*
X1315680Y1326622D03*
X1318110D03*
X1316606Y1317223D03*
X1319206D03*
X1318110Y1321022D03*
X1315680D03*
X1313250D03*
Y1326622D03*
X1318159Y1339037D03*
X1306079Y1340490D03*
X1314580Y1425240D03*
X1310580D03*
X1318580D03*
X1309386Y1485895D03*
X1311296Y1483295D03*
X1316076D03*
X1311296Y1488495D03*
X1316076D03*
X1309376Y1492995D03*
Y1498195D03*
X1308290Y1533380D03*
X1309423Y1543800D03*
Y1547420D03*
Y1551040D03*
X1309915Y1561731D03*
X1308757Y1622884D03*
X1315861D03*
X1309831Y1637876D03*
Y1632884D03*
X1314787Y1637876D03*
Y1632884D03*
X1308757Y1627876D03*
X1315861D03*
X1308757Y1654796D03*
X1309831Y1649788D03*
X1315861Y1654796D03*
X1314787Y1649788D03*
X1309831Y1644796D03*
X1314787D03*
X1308757Y1659788D03*
X1315861D03*
X1326199Y49379D03*
X1334156Y292066D03*
X1326094Y286948D03*
X1330277Y857388D03*
X1329477Y1222158D03*
X1331202Y1211488D03*
X1332680Y1291861D03*
X1330080D03*
X1333020Y1308621D03*
X1331770Y1311121D03*
X1333020Y1306021D03*
Y1303421D03*
X1330420Y1306021D03*
Y1303421D03*
Y1308621D03*
X1327696Y1314206D03*
X1321806Y1311159D03*
X1324306D03*
X1326750Y1311175D03*
X1327696Y1317163D03*
X1334580Y1425240D03*
X1330580D03*
X1326580D03*
X1322580D03*
X1331396Y1492995D03*
X1322786Y1505295D03*
X1329486Y1495595D03*
X1331396Y1498195D03*
X1324696Y1502695D03*
X1329476D03*
X1324696Y1507895D03*
X1329476D03*
X1328913Y1583797D03*
X1333638Y1583897D03*
X1324189Y1583797D03*
X1327921Y1622884D03*
X1320817D03*
X1332877D03*
X1321891Y1637876D03*
X1326847D03*
X1321891Y1632884D03*
X1326847D03*
X1333951Y1637876D03*
Y1632884D03*
X1327921Y1627876D03*
X1320817D03*
X1332877D03*
X1320817Y1654796D03*
X1327921D03*
X1326847Y1649788D03*
X1321891D03*
X1332877Y1654796D03*
X1333951Y1649788D03*
X1326847Y1644796D03*
X1321891D03*
X1333951D03*
X1320817Y1659788D03*
X1327921D03*
X1332877D03*
X1348199Y49379D03*
X1351750Y72826D03*
X1339840Y72860D03*
X1342094Y286948D03*
X1339347Y857388D03*
X1337975Y1177999D03*
X1338142Y1181642D03*
X1338440Y1291949D03*
X1335670Y1291899D03*
X1346806Y1311359D03*
X1349406D03*
X1346806Y1314466D03*
X1349406D03*
X1344206Y1311359D03*
Y1314466D03*
X1339429Y1315570D03*
X1348480Y1326822D03*
X1349406Y1317423D03*
X1346050Y1321222D03*
Y1326822D03*
X1348480Y1321222D03*
X1338879Y1340690D03*
X1337221Y1338739D03*
X1346580Y1425240D03*
X1342580D03*
X1338580D03*
X1336176Y1492995D03*
X1338096Y1483295D03*
X1342876D03*
X1336186Y1485895D03*
X1338096Y1488495D03*
X1342876D03*
X1349586Y1505295D03*
X1336176Y1498195D03*
X1343087Y1583897D03*
X1347811D03*
X1338362Y1583697D03*
X1339981Y1622884D03*
X1344937D03*
X1338907Y1637876D03*
Y1632884D03*
X1346011Y1637876D03*
Y1632884D03*
X1339981Y1627876D03*
X1344937D03*
X1339981Y1654796D03*
X1338907Y1649788D03*
X1344937Y1654796D03*
X1346011Y1649788D03*
X1338907Y1644796D03*
X1346011D03*
X1339981Y1659788D03*
X1344937D03*
X1361550Y67264D03*
X1350156Y292066D03*
X1358094Y286948D03*
X1354257Y675765D03*
X1364490Y1293694D03*
X1361830Y1291809D03*
X1360496Y1314406D03*
X1363220Y1308821D03*
X1364570Y1311321D03*
X1363220Y1306221D03*
Y1303621D03*
X1359550Y1311375D03*
X1352006Y1311359D03*
X1357106D03*
X1354606D03*
X1352006Y1314466D03*
X1360496Y1317363D03*
X1350910Y1326822D03*
X1352006Y1317423D03*
X1350910Y1321222D03*
X1350959Y1339237D03*
X1362580Y1425240D03*
X1358580D03*
X1354580D03*
X1350580D03*
X1362986Y1485895D03*
X1364896Y1483295D03*
Y1488495D03*
X1358196Y1492995D03*
X1362976D03*
X1356286Y1495595D03*
X1358196Y1498195D03*
X1362976D03*
X1356276Y1502695D03*
X1351496D03*
X1356276Y1507895D03*
X1351496D03*
X1357260Y1583797D03*
X1361985Y1583897D03*
X1352536Y1583697D03*
X1352041Y1622884D03*
X1356997D03*
X1364101D03*
X1350967Y1637876D03*
Y1632884D03*
X1358071Y1637876D03*
Y1632884D03*
X1363027Y1637876D03*
Y1632884D03*
X1356997Y1627876D03*
X1352041D03*
X1364101D03*
X1352041Y1654796D03*
X1356997D03*
X1358071Y1649788D03*
X1350967D03*
X1364101Y1654796D03*
X1363027Y1649788D03*
X1358071Y1644796D03*
X1350967D03*
X1363027D03*
X1352041Y1659788D03*
X1356997D03*
X1364101D03*
X1370199Y49379D03*
X1371259Y98000D03*
X1366156Y292066D03*
X1377862Y485552D03*
Y511052D03*
X1368305Y1307340D03*
X1365820Y1308821D03*
X1368305Y1309840D03*
X1365820Y1306221D03*
Y1303621D03*
X1372149Y1334890D03*
X1379388Y1330690D03*
Y1333797D03*
X1378632Y1340553D03*
X1376788Y1330690D03*
Y1333797D03*
X1378632Y1346153D03*
X1371422Y1359024D03*
X1368922D03*
X1379101Y1418621D03*
X1368299Y1425240D03*
X1372164Y1423810D03*
X1375341Y1421268D03*
X1369676Y1483295D03*
Y1488495D03*
X1376386Y1505295D03*
X1378296Y1502695D03*
Y1507895D03*
X1376158Y1583897D03*
X1366709D03*
X1371434D03*
X1369057Y1622884D03*
X1376161D03*
X1370131Y1637876D03*
Y1632790D03*
X1375087Y1637876D03*
Y1632790D03*
X1369057Y1627876D03*
X1376161D03*
X1369057Y1654796D03*
X1370131Y1649788D03*
X1376161Y1654796D03*
X1375087Y1649788D03*
X1370131Y1644796D03*
X1375087D03*
X1369057Y1659788D03*
X1376161D03*
X1392199Y49379D03*
X1389688Y1330690D03*
X1392132Y1330706D03*
X1393078Y1333737D03*
Y1336694D03*
X1383492Y1340553D03*
X1381062D03*
X1381988Y1336754D03*
X1384588D03*
X1387188Y1330690D03*
X1381988D03*
Y1333797D03*
X1384588Y1330690D03*
Y1333797D03*
X1383541Y1358568D03*
X1381062Y1346153D03*
X1383492D03*
X1383284Y1415973D03*
X1387308Y1413643D03*
X1392021Y1410360D03*
X1389786Y1485895D03*
X1391696Y1483295D03*
Y1488495D03*
X1384996Y1492995D03*
X1389776D03*
X1383086Y1495595D03*
X1384996Y1498195D03*
X1389776D03*
X1383076Y1502695D03*
Y1507895D03*
X1390331Y1583897D03*
X1380882Y1583697D03*
X1385606Y1583897D03*
X1381117Y1622884D03*
X1382191Y1637876D03*
X1387147D03*
X1382191Y1632884D03*
X1387147D03*
X1381117Y1627876D03*
Y1654796D03*
X1382191Y1649788D03*
X1387147D03*
X1382191Y1644796D03*
X1387147D03*
X1392068Y1667907D03*
X1381918D03*
X1381117Y1659788D03*
X1387620Y1721418D03*
X1385061D03*
X1403500Y458377D03*
X1402452Y642825D03*
X1405716Y1310618D03*
X1401740Y1311980D03*
X1399240D03*
X1408690Y1324803D03*
X1396302Y1328152D03*
Y1325552D03*
X1398902Y1328152D03*
Y1325552D03*
X1396302Y1322952D03*
X1398902D03*
X1401406Y1334918D03*
X1397652Y1330652D03*
X1398375Y1403688D03*
X1401764Y1399928D03*
X1405207Y1395480D03*
X1408543Y1391826D03*
X1395463Y1406918D03*
X1403186Y1485895D03*
X1405096Y1483295D03*
X1396476D03*
X1405096Y1488495D03*
X1396476D03*
X1409456Y1537872D03*
X1406074Y1581563D03*
X1395055Y1583797D03*
X1398058Y1619683D03*
X1409660Y1619853D03*
X1397367Y1639951D03*
X1402425Y1649532D03*
X1414199Y49379D03*
X1414000Y460362D03*
X1415426Y1042765D03*
Y1038765D03*
X1424561Y1305566D03*
X1420690Y1324803D03*
X1417690D03*
X1414690D03*
X1411690D03*
X1424163Y1373240D03*
X1411508Y1388384D03*
X1414950Y1384942D03*
X1417491Y1381183D03*
X1420774Y1377106D03*
X1409876Y1483295D03*
Y1488495D03*
X1423735Y1536715D03*
X1412572Y1556953D03*
X1421232Y1606126D03*
X1422914Y1601663D03*
X1421392Y1621706D03*
X1416357Y1644027D03*
X1420042Y1649716D03*
X1433817Y-34648D03*
Y-4648D03*
Y5352D03*
X1436199Y49379D03*
X1434513Y106950D03*
X1439232Y596291D03*
X1425437Y1308184D03*
X1426202Y1310752D03*
X1427314Y1313482D03*
X1428458Y1316481D03*
X1429517Y1319447D03*
X1430312Y1322412D03*
X1431106Y1325219D03*
X1426441Y1369427D03*
X1428559Y1365296D03*
X1430465Y1361060D03*
X1438798Y1495595D03*
X1430431Y1563595D03*
X1427931D03*
X1424971Y1566764D03*
Y1564264D03*
X1435584Y1596545D03*
X1430075Y1613904D03*
X1430319Y1623504D03*
X1425390Y1635496D03*
X1433327Y1643287D03*
X1446869Y105129D03*
X1451353Y116158D03*
X1443551Y539318D03*
Y535318D03*
X1453345Y1015473D03*
Y1019016D03*
Y1022559D03*
X1445498Y1485895D03*
X1447408Y1483295D03*
X1452188D03*
X1447408Y1488495D03*
X1452188D03*
X1445488Y1492995D03*
X1440708D03*
X1445488Y1498195D03*
X1440708D03*
X1444200Y1533240D03*
X1445535Y1551040D03*
Y1547420D03*
Y1543800D03*
X1446027Y1561731D03*
X1445500Y1611500D03*
X1448500Y1601000D03*
X1442579Y1673303D03*
X1447579D03*
X1452579D03*
X1453950Y1681450D03*
X1458199Y49379D03*
X1459682Y450372D03*
X1468395Y487582D03*
X1464257Y552977D03*
Y564977D03*
X1468257Y696265D03*
X1460926Y1015473D03*
X1467926D03*
X1460926Y1019016D03*
Y1022559D03*
X1467926Y1019016D03*
Y1022559D03*
X1467508Y1492995D03*
X1458898Y1505295D03*
X1465598Y1495595D03*
X1467508Y1498195D03*
X1460808Y1502695D03*
X1465588D03*
X1460808Y1507895D03*
X1465588D03*
X1465025Y1583797D03*
X1460301D03*
X1464391Y1622884D03*
X1459435D03*
X1465465Y1637876D03*
Y1632884D03*
X1459435Y1627876D03*
X1464391D03*
Y1654796D03*
X1465465Y1649788D03*
Y1644796D03*
X1459435Y1654796D03*
X1464391Y1659788D03*
X1466500Y1666000D03*
X1469034Y1667794D03*
X1459435Y1659788D03*
X1456852Y1673320D03*
X1466599Y1679401D03*
X1466260Y1675155D03*
X1460457Y1685160D03*
X1480199Y49379D03*
X1483820Y122713D03*
X1482257Y552977D03*
Y560477D03*
Y567977D03*
X1481934Y699670D03*
X1480300Y697750D03*
X1472288Y1492995D03*
X1474208Y1483295D03*
X1478988D03*
X1472298Y1485895D03*
X1474208Y1488495D03*
X1478988D03*
X1472288Y1498195D03*
X1479199Y1583897D03*
X1483923D03*
X1469750D03*
X1474474Y1583697D03*
X1476451Y1622884D03*
X1471495D03*
X1483555D03*
X1470421Y1632884D03*
Y1637876D03*
X1482481D03*
X1477525D03*
X1482481Y1632884D03*
X1477525D03*
X1471495Y1627876D03*
X1483555D03*
X1476451D03*
X1471495Y1654796D03*
X1470421Y1649788D03*
X1476451Y1654796D03*
X1483555D03*
X1482481Y1649788D03*
X1477525D03*
X1470421Y1644796D03*
X1477525D03*
X1482481D03*
X1471495Y1659788D03*
X1476451D03*
X1483555D03*
X1471616Y1670098D03*
X1479375Y1685984D03*
X1495539Y131237D03*
X1492237Y123842D03*
X1489757Y552977D03*
X1497257D03*
Y560477D03*
X1489757Y567977D03*
X1497257D03*
X1494371Y594462D03*
X1492673Y828513D03*
X1494386Y1178743D03*
X1499098Y1485895D03*
X1494308Y1492995D03*
X1499088D03*
X1492398Y1495595D03*
X1485698Y1505295D03*
X1494308Y1498195D03*
X1499088D03*
X1492388Y1502695D03*
X1487608D03*
X1492388Y1507895D03*
X1487608D03*
X1493372Y1583797D03*
X1498097Y1583897D03*
X1488648Y1583697D03*
X1488511Y1622884D03*
X1495615D03*
X1494541Y1637876D03*
X1489585D03*
X1494541Y1632884D03*
X1489585D03*
X1488511Y1627876D03*
X1495615D03*
X1488511Y1654796D03*
X1495615D03*
X1489585Y1649788D03*
X1494541D03*
X1489585Y1644796D03*
X1494541D03*
X1488511Y1659788D03*
X1495615D03*
X1502199Y49379D03*
X1514576Y219730D03*
X1513348Y253954D03*
X1500757Y537438D03*
X1504757Y537378D03*
X1508757Y537456D03*
X1512757Y537477D03*
X1513382Y697750D03*
X1499243Y803513D03*
X1501730Y811872D03*
X1501338Y825147D03*
X1513470Y1178265D03*
X1504470D03*
X1505788Y1483295D03*
X1501008D03*
X1505788Y1488495D03*
X1501008D03*
X1512498Y1505295D03*
X1512270Y1583897D03*
X1502821D03*
X1507546D03*
X1500571Y1622884D03*
X1512631D03*
X1507675D03*
X1501645Y1637876D03*
Y1632884D03*
X1506601Y1637876D03*
Y1632884D03*
X1513705Y1637876D03*
Y1632884D03*
X1500571Y1627876D03*
X1512631D03*
X1507675D03*
X1500571Y1654796D03*
X1501645Y1649788D03*
X1507675Y1654796D03*
X1512631D03*
X1513705Y1649788D03*
X1506601D03*
X1501645Y1644796D03*
X1513705D03*
X1506601D03*
X1500571Y1659788D03*
X1507675D03*
X1512831Y1659588D03*
X1524124Y47570D03*
X1522917Y119912D03*
X1529384Y201245D03*
X1516452Y249724D03*
X1514900Y251839D03*
X1515016Y699670D03*
X1515192Y814294D03*
X1525898Y1485895D03*
X1527808Y1483295D03*
Y1488495D03*
X1521108Y1492995D03*
X1525888D03*
X1525898Y1505295D03*
X1519198Y1495595D03*
X1521108Y1498195D03*
X1525888D03*
X1519188Y1502695D03*
X1527808D03*
X1514408D03*
X1519188Y1507895D03*
X1514408D03*
X1526443Y1583897D03*
X1516994Y1583697D03*
X1521718Y1583897D03*
X1524691Y1622884D03*
X1519735D03*
X1518661Y1637876D03*
Y1632884D03*
X1525765Y1637876D03*
Y1632884D03*
X1519735Y1627876D03*
X1524691D03*
X1518661Y1649788D03*
X1524691Y1654796D03*
X1519735D03*
X1525765Y1649788D03*
X1518661Y1644796D03*
X1525765D03*
X1524991Y1659788D03*
X1519735D03*
X1530064Y-27930D03*
X1530049Y-30445D03*
X1533317Y-27916D03*
X1536342Y-29236D03*
X1533302Y-30431D03*
X1530048Y-20028D03*
X1530063Y-17513D03*
X1530018Y-25058D03*
X1530033Y-22543D03*
X1533301Y-20014D03*
X1533316Y-17499D03*
X1536341Y-18819D03*
X1543862Y75343D03*
X1539756Y71839D03*
X1534776D03*
X1539756Y66847D03*
X1534776D03*
X1532866Y69340D03*
X1536542Y300819D03*
Y304819D03*
X1539693Y535212D03*
X1542902Y543641D03*
X1540850Y1240863D03*
X1539298Y1485895D03*
X1541208Y1483295D03*
X1532588D03*
X1541208Y1488495D03*
X1532588D03*
X1542186Y1581563D03*
X1531167Y1583797D03*
X1536751Y1622884D03*
X1531795D03*
X1530721Y1637876D03*
Y1632884D03*
X1537825Y1637876D03*
X1542781D03*
X1537825Y1632790D03*
X1542781D03*
X1531795Y1627876D03*
X1536751D03*
X1531795Y1654796D03*
X1530721Y1649788D03*
X1536751Y1654796D03*
X1542781Y1649788D03*
X1537825D03*
X1530721Y1644796D03*
X1542781D03*
X1537825D03*
X1531795Y1659788D03*
X1536751D03*
X1550965Y3001D03*
X1555568Y17045D03*
Y22037D03*
X1553601Y19541D03*
X1555452Y25977D03*
X1553452Y23981D03*
X1548496D03*
X1546496Y25977D03*
X1554520Y37106D03*
X1547434D03*
X1554520Y48720D03*
X1547434D03*
X1556776Y71839D03*
X1550756Y72850D03*
X1545776D03*
X1554866Y69340D03*
X1556776Y66847D03*
X1550756Y77842D03*
X1545776D03*
X1552981Y220826D03*
X1555481Y218326D03*
X1553913Y298119D03*
X1558480Y302678D03*
X1545960Y565162D03*
X1551887Y606938D03*
X1555570Y1235968D03*
X1555367Y1248078D03*
X1555303Y1242557D03*
X1547062Y1258468D03*
X1553811Y1264488D03*
X1545988Y1483295D03*
Y1488495D03*
X1548684Y1556953D03*
X1555993Y1563595D03*
X1558493D03*
X1548811Y1622884D03*
X1543855D03*
X1555915D03*
X1549885Y1637876D03*
X1554841D03*
X1549885Y1632884D03*
X1554841D03*
X1543855Y1627876D03*
X1548811D03*
X1555915D03*
X1543855Y1654796D03*
X1555915D03*
X1548811D03*
X1554841Y1649788D03*
X1549885D03*
X1554841Y1644796D03*
X1549885D03*
X1543855Y1659788D03*
X1555915D03*
X1548811D03*
X1572965Y3001D03*
X1569742Y17045D03*
X1560548D03*
X1567774Y19541D03*
X1569742Y22037D03*
X1560548D03*
X1562669Y23981D03*
X1567625D03*
X1560669Y25977D03*
X1569625D03*
X1562557Y19541D03*
X1561607Y37106D03*
X1568693D03*
Y48720D03*
X1561607D03*
X1572756Y72847D03*
X1561756Y71839D03*
X1565866Y75340D03*
X1567776Y72847D03*
X1561756Y66847D03*
X1572756Y77839D03*
X1567776D03*
X1564517Y299432D03*
X1569592Y294816D03*
X1572283Y301816D03*
X1562995Y789522D03*
X1569518Y806684D03*
X1564267Y1253158D03*
X1573560Y1485895D03*
X1573550Y1492995D03*
X1568770D03*
X1566860Y1495595D03*
X1573550Y1498195D03*
X1568770D03*
X1572230Y1533000D03*
X1573597Y1543800D03*
Y1547420D03*
Y1551040D03*
X1564839Y1554561D03*
X1560871Y1622884D03*
X1572931D03*
X1567975D03*
X1561945Y1637876D03*
Y1632884D03*
X1566901Y1637876D03*
Y1632884D03*
X1560871Y1627876D03*
X1572931D03*
X1567975D03*
X1560871Y1654796D03*
X1561945Y1649788D03*
X1567975Y1654796D03*
X1572931D03*
X1566901Y1649788D03*
X1561945Y1644796D03*
X1566901D03*
X1560871Y1659788D03*
X1567975D03*
X1572931D03*
X1583915Y17045D03*
X1574722D03*
X1581947Y19541D03*
X1583915Y22037D03*
X1576730Y19541D03*
X1574722Y22037D03*
X1576842Y23981D03*
X1581798D03*
X1574842Y25977D03*
X1583798D03*
X1575780Y37106D03*
X1582867D03*
Y48720D03*
X1575780D03*
X1587866Y75340D03*
X1578776Y71839D03*
X1583756D03*
X1576866Y69340D03*
X1578776Y66847D03*
X1583756D03*
X1574546Y251294D03*
X1575370Y1252770D03*
X1581327Y1252858D03*
X1586835Y1271918D03*
X1583007Y1288958D03*
X1577913Y1341623D03*
X1575504Y1356103D03*
X1578336D03*
X1575470Y1483295D03*
X1580250D03*
X1575470Y1488495D03*
X1580250D03*
X1586960Y1505295D03*
X1574089Y1561731D03*
X1588363Y1583797D03*
X1584991Y1622884D03*
X1580035D03*
X1574005Y1637876D03*
Y1632884D03*
X1578961Y1637876D03*
Y1632884D03*
X1586065Y1637876D03*
Y1632884D03*
X1580035Y1627876D03*
X1584991D03*
X1574005Y1649788D03*
X1580035Y1654796D03*
X1578961Y1649788D03*
X1584991Y1654796D03*
X1586065Y1649788D03*
X1574005Y1644796D03*
X1578961D03*
X1586065D03*
X1580035Y1659788D03*
X1584991D03*
X1594965Y3001D03*
X1603072Y17045D03*
X1598092D03*
X1588895D03*
X1603072Y22037D03*
X1598092D03*
X1596121Y19541D03*
X1590903D03*
X1588895Y22037D03*
X1595972Y23981D03*
X1591016D03*
X1589016Y25977D03*
X1597972D03*
X1589953Y37106D03*
X1597040D03*
Y48720D03*
X1589953D03*
X1589776Y72847D03*
X1594756D03*
X1600776Y71842D03*
X1598866Y69343D03*
X1600776Y66850D03*
X1589776Y77839D03*
X1594756D03*
X1597562Y555463D03*
X1595036D03*
X1591962D03*
X1589436D03*
X1589557Y1252778D03*
X1590097Y1246768D03*
X1603507Y1306262D03*
X1601772Y1337293D03*
X1601959Y1351773D03*
X1599139Y1400464D03*
X1595570Y1492995D03*
X1600350D03*
X1602270Y1483295D03*
X1600360Y1485895D03*
X1602270Y1488495D03*
X1593660Y1495595D03*
X1595570Y1498195D03*
X1600350D03*
X1588870Y1502695D03*
X1593650D03*
X1588870Y1507895D03*
X1593650D03*
X1593087Y1583797D03*
X1597812Y1583897D03*
X1602536Y1583697D03*
X1597051Y1622884D03*
X1592095D03*
X1591021Y1637876D03*
Y1632884D03*
X1598125Y1637876D03*
X1603081D03*
X1598125Y1632884D03*
X1603081D03*
X1592095Y1627876D03*
X1597051D03*
X1592095Y1654796D03*
X1591021Y1649788D03*
X1597051Y1654796D03*
X1603081Y1649788D03*
X1598125D03*
X1591021Y1644796D03*
X1603081D03*
X1598125D03*
X1592095Y1659788D03*
X1597051D03*
X1616965Y3001D03*
X1605077Y19541D03*
X1604127Y37106D03*
Y48720D03*
X1609866Y75340D03*
X1611776Y72847D03*
X1616756D03*
X1605756Y71842D03*
Y66850D03*
X1611776Y77839D03*
X1616756D03*
X1608640Y640660D03*
X1607050Y1483295D03*
Y1488495D03*
X1613760Y1505295D03*
X1615670Y1502695D03*
Y1507895D03*
X1607261Y1583897D03*
X1611985D03*
X1616710Y1583697D03*
X1609111Y1622884D03*
X1604155D03*
X1616215D03*
X1610185Y1637876D03*
X1615141D03*
X1610185Y1632884D03*
X1615141D03*
X1604155Y1627876D03*
X1609111D03*
X1616215D03*
X1604155Y1654796D03*
X1616215D03*
X1609111D03*
X1615141Y1649788D03*
X1610185D03*
X1615141Y1644796D03*
X1610185D03*
X1604155Y1659788D03*
X1616215D03*
X1609111D03*
X1631987Y19541D03*
X1626882Y23981D03*
X1631838D03*
X1624882Y25977D03*
X1632906Y37106D03*
X1625819D03*
X1632906Y48720D03*
X1625819D03*
X1629662Y69343D03*
X1633070Y75340D03*
X1627756Y71842D03*
X1622776D03*
X1627756Y66850D03*
X1622776D03*
X1620862Y69343D03*
X1627410Y172008D03*
X1632500Y381500D03*
X1630927Y398002D03*
X1628046Y756765D03*
Y760265D03*
Y767265D03*
X1623496Y776910D03*
Y783603D03*
X1627896Y795315D03*
X1623496Y807028D03*
Y813721D03*
Y820414D03*
X1627896Y832126D03*
X1623496Y843839D03*
Y850532D03*
Y857225D03*
X1627896Y868937D03*
X1623496Y880650D03*
Y887343D03*
Y894036D03*
X1627896Y905749D03*
X1623496Y917461D03*
Y924154D03*
Y930847D03*
X1627896Y942560D03*
X1623496Y954272D03*
Y960965D03*
Y967658D03*
Y974351D03*
Y981044D03*
Y987736D03*
Y994429D03*
Y1004469D03*
Y1034587D03*
Y1041280D03*
Y1047973D03*
Y1054666D03*
Y1061359D03*
Y1071398D03*
X1627896Y1089804D03*
X1623496Y1078091D03*
Y1101516D03*
Y1108209D03*
Y1114902D03*
X1627896Y1126615D03*
X1623496Y1138327D03*
Y1145020D03*
X1627896Y1163426D03*
X1623496Y1151713D03*
Y1175138D03*
Y1181831D03*
Y1188524D03*
X1627896Y1200237D03*
X1623496Y1211949D03*
Y1218642D03*
X1627896Y1237048D03*
X1623496Y1225335D03*
Y1248760D03*
Y1255453D03*
X1627052Y1424716D03*
X1627160Y1485895D03*
X1629070Y1483295D03*
Y1488495D03*
X1622370Y1492995D03*
X1627150D03*
X1620460Y1495595D03*
X1622370Y1498195D03*
X1627150D03*
X1620450Y1502695D03*
Y1507895D03*
X1621434Y1583797D03*
X1626159Y1583897D03*
X1630883D03*
X1621171Y1622884D03*
X1628275D03*
X1622245Y1637876D03*
Y1632884D03*
X1627201Y1637876D03*
Y1632884D03*
X1621171Y1627876D03*
X1628275D03*
X1621171Y1654796D03*
X1622245Y1649788D03*
X1628275Y1654796D03*
X1627201Y1649788D03*
X1622245Y1644796D03*
X1627201D03*
X1621171Y1659788D03*
X1628275D03*
X1638965Y3001D03*
X1648128Y17045D03*
X1633954D03*
X1638934D03*
X1648128Y22037D03*
X1648011Y25977D03*
X1633954Y22037D03*
X1638934D03*
X1646160Y19541D03*
X1640943D03*
X1641055Y23981D03*
X1646011D03*
X1639055Y25977D03*
X1633838D03*
X1647079Y37106D03*
X1639993D03*
X1647079Y48720D03*
X1639993D03*
X1634980Y72847D03*
X1639960D03*
X1645980Y71839D03*
X1644070Y69340D03*
X1645980Y66847D03*
X1634980Y77839D03*
X1639960D03*
X1642240Y399603D03*
X1642135Y414202D03*
X1639800Y426982D03*
X1636800D03*
X1639800Y429982D03*
X1636800D03*
X1639800Y432982D03*
X1636800D03*
X1647110Y434177D03*
X1639800Y435982D03*
X1636800D03*
X1639800Y438982D03*
X1636800D03*
X1635088Y756765D03*
Y763765D03*
X1639638Y773563D03*
X1644038Y791969D03*
X1634188Y786949D03*
X1639638Y780256D03*
X1634188Y796988D03*
X1639638Y803681D03*
Y810374D03*
Y817067D03*
X1644038Y828780D03*
X1634188Y823760D03*
Y833799D03*
X1639638Y840492D03*
Y847185D03*
X1644038Y865591D03*
X1634188Y860571D03*
X1639638Y853878D03*
X1634188Y870610D03*
X1639638Y877303D03*
Y883996D03*
Y890689D03*
X1644038Y902402D03*
X1634188Y897382D03*
Y907422D03*
X1639638Y914114D03*
Y920807D03*
X1644038Y939213D03*
X1634188Y934193D03*
X1639638Y927500D03*
X1634188Y944233D03*
X1639638Y950925D03*
Y957618D03*
Y964311D03*
Y971004D03*
Y977697D03*
Y984390D03*
Y991083D03*
Y997776D03*
Y1004469D03*
Y1031240D03*
Y1037933D03*
Y1044626D03*
Y1051319D03*
Y1058012D03*
Y1068051D03*
Y1074744D03*
X1644038Y1086457D03*
X1634188Y1081437D03*
Y1091477D03*
X1639638Y1098170D03*
Y1104862D03*
X1634188Y1118248D03*
X1639638Y1111555D03*
X1644038Y1123268D03*
X1634188Y1128288D03*
X1639638Y1134981D03*
Y1141674D03*
Y1148366D03*
X1644038Y1160079D03*
X1634188Y1155059D03*
Y1165099D03*
X1639638Y1171792D03*
Y1178485D03*
X1634188Y1191870D03*
X1639638Y1185177D03*
X1644038Y1196890D03*
X1634188Y1201910D03*
X1639638Y1208603D03*
Y1215296D03*
Y1221988D03*
X1644038Y1233701D03*
X1634188Y1228681D03*
Y1238721D03*
X1639638Y1245414D03*
Y1252107D03*
X1641904Y1351467D03*
Y1348567D03*
X1633850Y1483295D03*
Y1488495D03*
X1647260Y1495595D03*
X1640560Y1505295D03*
X1647250Y1502695D03*
X1642470D03*
X1647250Y1507895D03*
X1642470D03*
X1640332Y1583897D03*
X1645056Y1583697D03*
X1635608Y1583897D03*
X1633231Y1622884D03*
X1645291D03*
X1640335D03*
X1634305Y1637876D03*
Y1632790D03*
X1639261Y1637876D03*
Y1632790D03*
X1646365Y1637876D03*
Y1632884D03*
X1633231Y1627876D03*
X1640335D03*
X1645291D03*
X1633231Y1654796D03*
X1634305Y1649788D03*
X1640335Y1654796D03*
X1639261Y1649788D03*
X1645291Y1654796D03*
X1646365Y1649788D03*
X1634305Y1644796D03*
X1639261D03*
X1646365D03*
X1633231Y1659788D03*
X1640335D03*
X1645291D03*
X1647700Y1674228D03*
X1648013Y1713684D03*
Y1728834D03*
X1660965Y3001D03*
X1653108Y17045D03*
X1655116Y19541D03*
X1653108Y22037D03*
X1654166Y37106D03*
Y48720D03*
X1650960Y66847D03*
X1655066Y75343D03*
X1662065Y72850D03*
X1656980D03*
X1650960Y71839D03*
X1662065Y77842D03*
X1656980D03*
X1652610Y394727D03*
X1659610D03*
X1652810Y407402D03*
X1661110Y434177D03*
X1657747Y756765D03*
Y760265D03*
Y767265D03*
X1653197Y776910D03*
Y783603D03*
X1657597Y795315D03*
X1653197Y807028D03*
Y813721D03*
Y820414D03*
X1657597Y832126D03*
X1653197Y843839D03*
Y850532D03*
Y857225D03*
X1657597Y868937D03*
X1653197Y880650D03*
Y887343D03*
Y894036D03*
X1657597Y905749D03*
X1653197Y917461D03*
Y924154D03*
Y930847D03*
X1657597Y942560D03*
X1653197Y954272D03*
Y960965D03*
Y967658D03*
Y974351D03*
Y981044D03*
Y987736D03*
Y994429D03*
Y1004469D03*
Y1034587D03*
Y1041280D03*
Y1047973D03*
Y1054666D03*
Y1061359D03*
Y1071398D03*
X1657597Y1089804D03*
X1653197Y1078091D03*
Y1101516D03*
Y1108209D03*
Y1114902D03*
X1657597Y1126615D03*
X1653197Y1138327D03*
Y1145020D03*
X1657597Y1163426D03*
X1653197Y1151713D03*
Y1175138D03*
Y1188524D03*
Y1181831D03*
X1657597Y1200237D03*
X1653197Y1211949D03*
Y1218642D03*
X1657597Y1237048D03*
X1653197Y1225335D03*
Y1248760D03*
Y1255453D03*
X1660594Y1298735D03*
X1651187D03*
X1660594Y1303935D03*
Y1306535D03*
Y1301335D03*
X1651187Y1303935D03*
Y1306535D03*
Y1301335D03*
X1650177Y1351467D03*
Y1348567D03*
X1658904Y1351467D03*
Y1348567D03*
X1662010Y1384570D03*
X1662766Y1377814D03*
X1660166D03*
X1662766Y1374707D03*
X1660166D03*
X1651301Y1378765D03*
X1662010Y1390170D03*
X1654774Y1402619D03*
X1648857Y1403424D03*
X1662465Y1444358D03*
X1653960Y1485895D03*
X1655870Y1483295D03*
X1660650D03*
X1655870Y1488495D03*
X1660650D03*
X1649170Y1492995D03*
X1653950D03*
X1649170Y1498195D03*
X1653950D03*
X1654505Y1583897D03*
X1659229Y1583797D03*
X1649780Y1583897D03*
X1651321Y1637876D03*
Y1632884D03*
Y1649788D03*
Y1644796D03*
X1653464Y1668416D03*
X1661101Y1671631D03*
X1651101Y1700478D03*
X1660541Y1704237D03*
X1677972Y25977D03*
X1676121Y19541D03*
X1675972Y23981D03*
X1671016D03*
X1669016Y25977D03*
X1677040Y37106D03*
X1669953D03*
X1677040Y48720D03*
X1669953D03*
X1677204Y75340D03*
X1672960Y71839D03*
X1667980Y66847D03*
X1672960D03*
X1667980Y71839D03*
X1666070Y69340D03*
X1663610Y394727D03*
X1664789Y756765D03*
Y763765D03*
X1669339Y773563D03*
X1673739Y791969D03*
X1663889Y786949D03*
X1669339Y780256D03*
X1663889Y796988D03*
X1669339Y803681D03*
Y810374D03*
Y817067D03*
X1673739Y828780D03*
X1663889Y823760D03*
Y833799D03*
X1669339Y840492D03*
Y847185D03*
X1673739Y865591D03*
X1663889Y860571D03*
X1669339Y853878D03*
X1663889Y870610D03*
X1669339Y877303D03*
Y883996D03*
Y890689D03*
X1673739Y902402D03*
X1663889Y897382D03*
Y907422D03*
X1669339Y914114D03*
Y920807D03*
X1673739Y939213D03*
X1663889Y934193D03*
X1669339Y927500D03*
X1663889Y944233D03*
X1669339Y950925D03*
Y957618D03*
Y964311D03*
Y971004D03*
Y977697D03*
Y984390D03*
Y991083D03*
Y997776D03*
Y1004469D03*
Y1031240D03*
Y1037933D03*
Y1044626D03*
Y1051319D03*
Y1058012D03*
Y1068051D03*
Y1074744D03*
X1673739Y1086457D03*
X1663889Y1081437D03*
Y1091477D03*
X1669339Y1098170D03*
Y1104862D03*
X1663889Y1118248D03*
X1669339Y1111555D03*
X1673739Y1123268D03*
X1663889Y1128288D03*
X1669339Y1134981D03*
Y1141674D03*
Y1148366D03*
X1673739Y1160079D03*
X1663889Y1155059D03*
Y1165099D03*
X1669339Y1171792D03*
Y1178485D03*
X1663889Y1191870D03*
X1669339Y1185177D03*
X1673739Y1196890D03*
X1663889Y1201910D03*
X1669339Y1208603D03*
Y1215296D03*
Y1221988D03*
X1673739Y1233701D03*
X1663889Y1228681D03*
Y1238721D03*
X1669339Y1245414D03*
Y1252107D03*
X1675187Y1298735D03*
Y1303935D03*
Y1306535D03*
Y1301335D03*
X1674831Y1351266D03*
Y1348366D03*
X1675901Y1377594D03*
Y1380551D03*
X1666870Y1384570D03*
X1664440D03*
X1675510Y1374723D03*
X1667966Y1374707D03*
X1670566D03*
X1665366Y1377814D03*
Y1380771D03*
Y1374707D03*
X1667966Y1377814D03*
Y1380771D03*
X1673066Y1374707D03*
X1666870Y1390170D03*
X1664440D03*
X1666919Y1402585D03*
X1671067Y1405418D03*
X1672277Y1407694D03*
X1674777D03*
X1672907Y1429928D03*
X1672273Y1420567D03*
X1666290Y1444391D03*
X1667360Y1485895D03*
X1669270Y1483295D03*
X1674050D03*
X1669270Y1488495D03*
X1674050D03*
X1673674Y1563575D03*
X1670248Y1581563D03*
X1670534Y1670149D03*
X1673245Y1673475D03*
X1664256Y1690794D03*
X1673132Y1690741D03*
X1665520Y1716877D03*
Y1732027D03*
X1682965Y3001D03*
X1692262Y17045D03*
X1678088D03*
X1683068D03*
X1692262Y22037D03*
X1692145Y25977D03*
X1678088Y22037D03*
X1683068D03*
X1690294Y19541D03*
X1685077D03*
X1690145Y23981D03*
X1685189D03*
X1683189Y25977D03*
X1684127Y37106D03*
X1691213D03*
Y48720D03*
X1684127D03*
X1679114Y72847D03*
X1688200Y69343D03*
X1690114Y66850D03*
Y71842D03*
X1684094Y72847D03*
X1679114Y77839D03*
X1684094D03*
X1687448Y756765D03*
Y760265D03*
X1682898Y776910D03*
X1687448Y767265D03*
X1682898Y783603D03*
X1687298Y795315D03*
X1682898Y807028D03*
Y820414D03*
Y813721D03*
X1687298Y832126D03*
X1682898Y850532D03*
Y843839D03*
Y857225D03*
X1687298Y868937D03*
X1682898Y880650D03*
Y894036D03*
Y887343D03*
X1687298Y905749D03*
X1682898Y917461D03*
Y924154D03*
Y930847D03*
X1687298Y942560D03*
X1682898Y954272D03*
Y967658D03*
Y960965D03*
Y981044D03*
Y974351D03*
Y994429D03*
Y987736D03*
Y1004469D03*
Y1041280D03*
Y1034587D03*
Y1054666D03*
Y1047973D03*
Y1061359D03*
Y1071398D03*
Y1078091D03*
X1687298Y1089804D03*
X1682898Y1101516D03*
Y1108209D03*
Y1114902D03*
X1687298Y1126615D03*
X1682898Y1138327D03*
Y1145020D03*
Y1151713D03*
X1687298Y1163426D03*
X1682898Y1175138D03*
Y1188524D03*
Y1181831D03*
X1687298Y1200237D03*
X1682898Y1211949D03*
Y1218642D03*
Y1225335D03*
X1687298Y1237048D03*
X1682898Y1248760D03*
Y1255453D03*
X1684708Y1298435D03*
Y1303635D03*
Y1306235D03*
Y1301035D03*
X1687233Y1351320D03*
X1679133Y1351420D03*
X1687233Y1348420D03*
X1679133Y1348520D03*
X1679180Y1372169D03*
X1681780D03*
X1679180Y1366969D03*
X1681780D03*
Y1369569D03*
X1679180D03*
X1683896Y1378765D03*
X1692948Y1377914D03*
Y1374807D03*
X1680530Y1374669D03*
X1685963Y1402187D03*
X1687621Y1404138D03*
X1684172Y1538135D03*
X1682561Y1552726D03*
X1691226Y1563526D03*
X1680558Y1555690D03*
X1691226Y1559526D03*
X1682494Y1568271D03*
Y1575125D03*
X1680491Y1578089D03*
Y1571235D03*
X1689880Y1572067D03*
X1679420Y1683597D03*
X1683013Y1713684D03*
X1680519Y1726825D03*
X1689383Y1729187D03*
X1704965Y3001D03*
X1697242Y17045D03*
X1699250Y19541D03*
X1697242Y22037D03*
X1698300Y37106D03*
X1705381Y37108D03*
X1698300Y48720D03*
X1705386D03*
X1701114Y72847D03*
X1706094D03*
X1699204Y75340D03*
X1695094Y66850D03*
Y71842D03*
X1706094Y77839D03*
X1701114D03*
X1694490Y756765D03*
Y763765D03*
X1699040Y773563D03*
X1703440Y791969D03*
X1699040Y780256D03*
X1693590Y786949D03*
X1699040Y803681D03*
X1693590Y796988D03*
X1699040Y817067D03*
Y810374D03*
X1693590Y823760D03*
X1703440Y828780D03*
X1693590Y833799D03*
X1699040Y847185D03*
Y840492D03*
Y853878D03*
X1693590Y860571D03*
X1703440Y865591D03*
X1693590Y870610D03*
X1699040Y877303D03*
Y883996D03*
Y890689D03*
X1693590Y907422D03*
X1703440Y902402D03*
X1693590Y897382D03*
X1699040Y914114D03*
Y920807D03*
X1693590Y934193D03*
X1699040Y927500D03*
X1703440Y939213D03*
X1693590Y944233D03*
X1699040Y950925D03*
Y964311D03*
Y971004D03*
Y957618D03*
Y977697D03*
Y984390D03*
Y997776D03*
Y991083D03*
Y1004469D03*
Y1044626D03*
Y1037933D03*
Y1031240D03*
Y1058012D03*
Y1051319D03*
Y1074744D03*
Y1068051D03*
X1703440Y1086457D03*
X1693590Y1081437D03*
Y1091477D03*
X1699040Y1104862D03*
Y1098170D03*
Y1111555D03*
X1693590Y1118248D03*
X1699040Y1134981D03*
X1703440Y1123268D03*
X1693590Y1128288D03*
X1699040Y1141674D03*
Y1148366D03*
X1693590Y1155059D03*
Y1165099D03*
X1703440Y1160079D03*
X1699040Y1171792D03*
Y1178485D03*
X1693590Y1191870D03*
X1699040Y1185177D03*
X1693590Y1201910D03*
X1703440Y1196890D03*
X1699040Y1208603D03*
Y1221988D03*
Y1215296D03*
X1693590Y1228681D03*
Y1238721D03*
X1703440Y1233701D03*
X1699040Y1245414D03*
Y1252107D03*
X1699087Y1298435D03*
Y1303635D03*
Y1306235D03*
Y1301035D03*
X1695533Y1351320D03*
Y1348420D03*
X1694792Y1384670D03*
X1700748Y1377914D03*
Y1380871D03*
Y1374807D03*
X1703348D03*
X1705848D03*
X1698148Y1377914D03*
X1695548D03*
X1698148Y1380871D03*
X1695548Y1374807D03*
X1698148D03*
X1699652Y1384670D03*
X1697222D03*
X1699652Y1390270D03*
X1694792D03*
X1697222D03*
X1699701Y1402685D03*
X1700520Y1716877D03*
X1702777Y1723593D03*
X1695166Y1717606D03*
X1720148Y22910D03*
X1710886Y82208D03*
X1715550Y102923D03*
X1721400Y374462D03*
X1718241Y652105D03*
X1717149Y756765D03*
Y760265D03*
X1712599Y776910D03*
X1717149Y767265D03*
X1712599Y783603D03*
Y807028D03*
X1716999Y795315D03*
X1712599Y820414D03*
Y813721D03*
X1716999Y832126D03*
X1712599Y850532D03*
Y843839D03*
Y857225D03*
X1716999Y868937D03*
X1712599Y880650D03*
Y894036D03*
Y887343D03*
X1716999Y905749D03*
X1712599Y917461D03*
Y924154D03*
Y930847D03*
X1716999Y942560D03*
X1712599Y954272D03*
Y967658D03*
Y960965D03*
Y981044D03*
Y974351D03*
Y994429D03*
Y987736D03*
Y1004469D03*
Y1041280D03*
Y1034587D03*
Y1054666D03*
Y1047973D03*
Y1061359D03*
Y1071398D03*
Y1078091D03*
X1716999Y1089804D03*
X1712599Y1101516D03*
Y1108209D03*
Y1114902D03*
X1716999Y1126615D03*
X1712599Y1138327D03*
Y1145020D03*
Y1151713D03*
X1716999Y1163426D03*
X1712599Y1175138D03*
Y1188524D03*
Y1181831D03*
X1716999Y1200237D03*
X1712599Y1218642D03*
Y1211949D03*
Y1225335D03*
X1716999Y1237048D03*
X1712599Y1248760D03*
Y1255453D03*
X1721754Y1299488D03*
X1708754Y1298388D03*
X1721847Y1307298D03*
X1721754Y1304688D03*
X1708754Y1300988D03*
X1721754Y1302088D03*
X1708754Y1303588D03*
Y1306188D03*
X1718813Y1348450D03*
Y1351350D03*
X1709533Y1351520D03*
Y1348620D03*
X1711962Y1367069D03*
X1714562D03*
X1711962Y1369669D03*
X1714562D03*
X1719902Y1368509D03*
Y1365909D03*
Y1363409D03*
X1708678Y1380621D03*
Y1377664D03*
X1716267Y1375178D03*
X1713312Y1374769D03*
X1708292Y1374823D03*
X1720210Y1435330D03*
X1719893Y1594940D03*
Y1612940D03*
Y1599740D03*
Y1603040D03*
Y1606340D03*
Y1609640D03*
X1722133Y1725340D03*
X1727111Y-38849D03*
Y-28849D03*
X1726965Y3001D03*
X1732286Y28208D03*
X1728786D03*
X1725286D03*
X1727336Y57024D03*
X1726596Y61784D03*
X1729836Y57024D03*
X1726596Y64284D03*
X1726814Y102968D03*
X1733344Y134953D03*
X1736474D03*
X1730364Y177588D03*
X1725400Y372062D03*
X1737260Y368132D03*
X1732660Y372692D03*
X1725500Y383662D03*
X1723259Y653641D03*
X1726334Y670345D03*
X1724191Y756765D03*
Y763765D03*
X1728741Y773563D03*
X1733141Y791969D03*
X1723291Y786949D03*
X1728741Y780256D03*
Y803681D03*
X1723291Y796988D03*
X1728741Y817067D03*
Y810374D03*
X1733141Y828780D03*
X1723291Y823760D03*
Y833799D03*
X1728741Y847185D03*
Y840492D03*
Y853878D03*
X1733141Y865591D03*
X1723291Y860571D03*
Y870610D03*
X1728741Y877303D03*
Y883996D03*
Y890689D03*
X1723291Y907422D03*
X1733141Y902402D03*
X1723291Y897382D03*
X1728741Y914114D03*
Y920807D03*
X1723291Y934193D03*
X1728741Y927500D03*
X1733141Y939213D03*
X1723291Y944233D03*
X1728741Y950925D03*
Y964311D03*
Y971004D03*
Y957618D03*
Y977697D03*
Y984390D03*
Y997776D03*
Y991083D03*
Y1004469D03*
Y1044626D03*
Y1037933D03*
Y1031240D03*
Y1058012D03*
Y1051319D03*
Y1074744D03*
Y1068051D03*
X1733141Y1086457D03*
X1723291Y1081437D03*
Y1091477D03*
X1728741Y1104862D03*
Y1098170D03*
Y1111555D03*
X1723291Y1118248D03*
X1728741Y1134981D03*
X1733141Y1123268D03*
X1723291Y1128288D03*
X1728741Y1141674D03*
Y1148366D03*
X1723291Y1155059D03*
X1733141Y1160079D03*
X1723291Y1165099D03*
X1728741Y1171792D03*
Y1178485D03*
X1723291Y1191870D03*
X1728741Y1185177D03*
X1723291Y1201910D03*
X1733141Y1196890D03*
X1728741Y1208603D03*
Y1221988D03*
Y1215296D03*
X1733141Y1233701D03*
X1723291Y1228681D03*
Y1238721D03*
X1728741Y1245414D03*
Y1252107D03*
X1732624Y1299718D03*
X1732717Y1307528D03*
X1732624Y1302318D03*
Y1304918D03*
X1735202Y1368279D03*
Y1365679D03*
Y1363179D03*
X1723917Y1380518D03*
Y1377178D03*
X1737126Y1403838D03*
Y1401238D03*
X1722810Y1435330D03*
X1737541Y1543707D03*
X1734575Y1562068D03*
X1724323Y1676965D03*
X1748965Y3001D03*
X1752008Y25146D03*
X1748116Y37058D03*
X1745451Y119585D03*
X1747448Y121413D03*
X1750325Y179827D03*
X1750851Y216427D03*
X1748325D03*
X1752461Y255337D03*
Y252337D03*
X1742652Y671494D03*
X1746850Y756765D03*
Y760265D03*
X1742300Y776910D03*
X1746850Y767265D03*
X1742300Y783603D03*
X1746700Y795315D03*
X1742300Y807028D03*
Y820414D03*
Y813721D03*
X1746700Y832126D03*
X1742300Y850532D03*
Y843839D03*
Y857225D03*
X1746700Y868937D03*
X1742300Y880650D03*
Y894036D03*
Y887343D03*
X1746700Y905749D03*
X1742300Y917461D03*
Y924154D03*
Y930847D03*
X1746700Y942560D03*
X1742300Y954272D03*
Y960965D03*
Y967658D03*
Y981044D03*
Y974351D03*
Y994429D03*
Y987736D03*
Y1004469D03*
Y1041280D03*
Y1034587D03*
Y1054666D03*
Y1047973D03*
Y1061359D03*
Y1071398D03*
Y1078091D03*
X1746700Y1089804D03*
X1742300Y1101516D03*
Y1108209D03*
Y1114902D03*
X1746700Y1126615D03*
X1742300Y1138327D03*
Y1145020D03*
Y1151713D03*
X1746700Y1163426D03*
X1742300Y1175138D03*
Y1188524D03*
Y1181831D03*
X1746700Y1200237D03*
X1742300Y1218642D03*
Y1211949D03*
Y1225335D03*
X1746700Y1237048D03*
X1742300Y1248760D03*
Y1255453D03*
X1743072Y1432211D03*
X1743188Y1543871D03*
Y1547871D03*
X1740587Y1547946D03*
X1737738Y1548021D03*
X1740400Y1543682D03*
X1752364Y1556323D03*
Y1559430D03*
X1744564Y1556323D03*
Y1559430D03*
X1749764Y1556323D03*
Y1559430D03*
X1747164Y1556323D03*
Y1559430D03*
X1752564Y1562537D03*
X1751518Y1566186D03*
X1740079Y1559505D03*
X1740188Y1556371D03*
X1746558Y1566186D03*
X1749038D03*
X1749964Y1562537D03*
X1751518Y1571786D03*
X1746558D03*
X1749038D03*
X1739640Y1713383D03*
Y1728533D03*
X1762420Y17031D03*
X1763840Y37790D03*
X1753398Y48720D03*
X1760485D03*
X1759666Y57708D03*
X1764366Y57508D03*
X1758047Y68637D03*
X1758539Y87153D03*
Y83653D03*
X1758534Y79743D03*
X1765034Y80443D03*
X1766244Y93673D03*
X1766911Y179890D03*
X1752851Y179827D03*
X1757385Y179890D03*
X1764385D03*
X1759911D03*
X1757951Y216427D03*
X1755425D03*
X1762485Y216490D03*
X1765011D03*
X1758859Y251544D03*
Y248544D03*
X1766399Y251361D03*
Y248361D03*
X1753892Y756765D03*
Y763765D03*
X1758442Y773563D03*
X1762842Y791969D03*
X1752992Y786949D03*
X1758442Y780256D03*
Y803681D03*
X1752992Y796988D03*
X1758442Y817067D03*
Y810374D03*
X1752992Y823760D03*
Y833799D03*
X1762842Y828780D03*
X1758442Y847185D03*
Y840492D03*
X1752992Y860571D03*
X1758442Y853878D03*
X1762842Y865591D03*
X1752992Y870610D03*
X1758442Y877303D03*
Y883996D03*
Y890689D03*
X1752992Y907422D03*
Y897382D03*
X1762842Y902402D03*
X1758442Y914114D03*
Y920807D03*
X1752992Y934193D03*
X1758442Y927500D03*
X1762842Y939213D03*
X1752992Y944233D03*
X1758442Y950925D03*
Y964311D03*
Y971004D03*
Y957618D03*
Y977697D03*
Y984390D03*
Y997776D03*
Y991083D03*
Y1004469D03*
Y1044626D03*
Y1037933D03*
Y1031240D03*
Y1058012D03*
Y1051319D03*
Y1074744D03*
Y1068051D03*
X1752992Y1081437D03*
X1762842Y1086457D03*
X1752992Y1091477D03*
X1758442Y1104862D03*
Y1098170D03*
X1752992Y1118248D03*
X1758442Y1111555D03*
Y1134981D03*
X1752992Y1128288D03*
X1762842Y1123268D03*
X1758442Y1141674D03*
Y1148366D03*
X1752992Y1155059D03*
Y1165099D03*
X1762842Y1160079D03*
X1758442Y1171792D03*
Y1178485D03*
X1752992Y1191870D03*
X1758442Y1185177D03*
X1752992Y1201910D03*
X1762842Y1196890D03*
X1758442Y1208603D03*
Y1221988D03*
Y1215296D03*
X1752992Y1228681D03*
Y1238721D03*
X1762842Y1233701D03*
X1758442Y1245414D03*
Y1252107D03*
X1758238Y1556238D03*
X1761108Y1556339D03*
Y1559446D03*
X1761079Y1562605D03*
X1755038Y1556238D03*
X1765709Y1556050D03*
X1754479Y1585905D03*
X1754763Y1641665D03*
X1752864Y1716383D03*
X1770965Y3001D03*
X1772886Y37430D03*
X1768134Y80543D03*
X1771385Y179890D03*
X1773911D03*
X1778500Y183790D03*
X1769585Y215090D03*
X1772111D03*
X1776585D03*
X1779111D03*
X1778874Y253799D03*
Y256799D03*
X1770520Y364148D03*
Y368148D03*
X1771236Y557224D03*
X1776550Y756765D03*
Y760265D03*
X1772000Y776910D03*
X1776550Y767265D03*
X1772000Y783603D03*
Y807028D03*
X1776400Y795315D03*
X1772000Y813721D03*
Y820414D03*
X1776400Y832126D03*
X1772000Y850532D03*
Y843839D03*
Y857225D03*
X1776400Y868937D03*
X1772000Y880650D03*
Y894036D03*
Y887343D03*
X1776400Y905749D03*
X1772000Y917461D03*
Y924154D03*
Y930847D03*
X1776400Y942560D03*
X1772000Y954272D03*
Y967658D03*
Y960965D03*
Y981044D03*
Y974351D03*
Y994429D03*
Y987736D03*
Y1004469D03*
Y1041280D03*
Y1034587D03*
Y1047973D03*
Y1054666D03*
Y1061359D03*
Y1071398D03*
Y1078091D03*
X1776400Y1089804D03*
X1772000Y1101516D03*
Y1108209D03*
Y1114902D03*
X1776400Y1126615D03*
X1772000Y1138327D03*
Y1145020D03*
Y1151713D03*
X1776400Y1163426D03*
X1772000Y1175138D03*
Y1188524D03*
Y1181831D03*
X1776400Y1200237D03*
X1772000Y1218642D03*
Y1211949D03*
Y1225335D03*
X1776400Y1237048D03*
X1772000Y1248760D03*
Y1255453D03*
X1776188Y1543871D03*
Y1546871D03*
X1769188D03*
Y1543871D03*
X1768688Y1552871D03*
Y1549871D03*
X1772688Y1543871D03*
Y1546871D03*
X1776113Y1541172D03*
X1769113D03*
X1772613D03*
X1780307Y1559430D03*
Y1556323D03*
X1775979Y1556805D03*
Y1559805D03*
X1782301Y1566186D03*
X1768209Y1556000D03*
X1769826Y1562559D03*
X1782301Y1571786D03*
X1792965Y3001D03*
X1796781Y46686D03*
X1785144Y86973D03*
Y89973D03*
X1783448Y212957D03*
X1795794Y253719D03*
X1787534Y253769D03*
X1795794Y256719D03*
X1787534Y256769D03*
X1795479Y408056D03*
X1795468Y421334D03*
X1783592Y756765D03*
X1788142Y773563D03*
X1792542Y791969D03*
X1782692Y786949D03*
X1788142Y780256D03*
X1782692Y796988D03*
X1788142Y803681D03*
Y817067D03*
Y810374D03*
X1782692Y823760D03*
Y833799D03*
X1792542Y828780D03*
X1788142Y847185D03*
Y840492D03*
Y853878D03*
X1792542Y865591D03*
X1782692Y860571D03*
Y870610D03*
X1788142Y877303D03*
Y883996D03*
Y890689D03*
X1782692Y907422D03*
Y897382D03*
X1792542Y902402D03*
X1788142Y914114D03*
Y920807D03*
X1782692Y934193D03*
X1788142Y927500D03*
X1792542Y939213D03*
X1782692Y944233D03*
X1788142Y950925D03*
Y964311D03*
Y971004D03*
Y957618D03*
Y977697D03*
Y984390D03*
Y997776D03*
Y991083D03*
Y1004469D03*
Y1044626D03*
Y1037933D03*
Y1031240D03*
Y1058012D03*
Y1051319D03*
Y1074744D03*
Y1068051D03*
X1782692Y1081437D03*
X1792542Y1086457D03*
X1782692Y1091477D03*
X1788142Y1098170D03*
Y1104862D03*
X1782692Y1118248D03*
X1788142Y1111555D03*
Y1134981D03*
X1782692Y1128288D03*
X1792542Y1123268D03*
X1788142Y1141674D03*
Y1148366D03*
X1782692Y1155059D03*
Y1165099D03*
X1792542Y1160079D03*
X1788142Y1171792D03*
Y1178485D03*
X1782692Y1191870D03*
X1788142Y1185177D03*
X1782692Y1201910D03*
X1792542Y1196890D03*
X1788142Y1208603D03*
Y1221988D03*
Y1215296D03*
X1782692Y1228681D03*
Y1238721D03*
X1792542Y1233701D03*
X1788142Y1245414D03*
Y1252107D03*
X1796838Y1556125D03*
X1788107Y1556323D03*
X1793833Y1556195D03*
X1790633D03*
X1788107Y1559430D03*
X1788307Y1562537D03*
X1787261Y1566186D03*
X1782907Y1559430D03*
Y1556323D03*
X1784781Y1566186D03*
X1785507Y1559430D03*
Y1556323D03*
X1785707Y1562537D03*
X1796257Y1561255D03*
Y1558755D03*
X1787261Y1571786D03*
X1784781D03*
X1788679Y1585805D03*
X1807515Y56461D03*
X1807546Y59443D03*
X1807296Y255033D03*
X1804174Y253739D03*
Y256739D03*
X1803129Y362293D03*
X1802929Y385293D03*
X1804688Y1545871D03*
Y1542371D03*
Y1552871D03*
Y1549371D03*
X1801688Y1545871D03*
Y1542371D03*
Y1552871D03*
Y1549371D03*
X1804688Y1555871D03*
X1801688D03*
X1804688Y1559371D03*
X1818615Y49379D03*
X1818155Y149325D03*
X1819529Y320321D03*
X1820307Y373829D03*
X1820656Y388051D03*
X1820144Y398052D03*
X1819374Y410432D03*
X1818874Y423932D03*
X1840615Y49379D03*
X1853692Y308447D03*
G54D39*
X311115Y1214093D03*
X310957Y1219126D03*
X388805Y1218420D03*
X388647Y1223453D03*
X386461Y1235718D03*
X386303Y1240751D03*
X1898799Y1810398D03*
X1908799D03*
X1931395Y572237D03*
X1921395D03*
X1942395Y1184617D03*
X1940886Y1810370D03*
X1963362Y572379D03*
X1952395Y1184617D03*
X1950886Y1810370D03*
X1973362Y572379D03*
X1984482Y1184589D03*
X1992856Y1810550D03*
X1982856D03*
X2005452Y572389D03*
X1994482Y1184589D03*
X2015452Y572389D03*
X2036452Y1184769D03*
X2026452D03*
X2047419Y572531D03*
X2057419D03*
X2078539Y1184741D03*
X2068539D03*
G54D55*
X828780Y1684890D03*
X818780D03*
X828780Y1694890D03*
X818780D03*
X828780Y1704890D03*
X818780D03*
X828780Y1714890D03*
X818780D03*
X853780Y1684890D03*
Y1694890D03*
Y1704890D03*
Y1714890D03*
X863780Y1684890D03*
Y1694890D03*
Y1704890D03*
Y1714890D03*
X888780Y1684890D03*
Y1694890D03*
Y1704890D03*
Y1714890D03*
X898780Y1684890D03*
Y1694890D03*
Y1704890D03*
Y1714890D03*
X918780Y1704890D03*
X958780Y1684890D03*
Y1694890D03*
Y1704890D03*
Y1714890D03*
X968780Y1684890D03*
Y1694890D03*
Y1704890D03*
Y1714890D03*
X993780Y1684890D03*
Y1694890D03*
Y1704890D03*
Y1714890D03*
X1003780Y1684890D03*
Y1694890D03*
Y1704890D03*
Y1714890D03*
X1028780Y1684890D03*
X1038780D03*
X1028780Y1694890D03*
X1038780D03*
X1028780Y1704890D03*
Y1714890D03*
X1038780Y1704890D03*
Y1714890D03*
G54D29*
X182947Y1507512D03*
X186530Y1521453D03*
X185688Y1519195D03*
X186860Y1514243D03*
X186579Y1536063D03*
X177579Y1528725D03*
Y1523810D03*
X183051Y1542425D03*
X185966Y1592380D03*
Y1624292D03*
X188254Y1507295D03*
X192979D03*
X197703D03*
X191254Y1521453D03*
X195979D03*
X200703D03*
X196309Y1514243D03*
X201033D03*
X191584D03*
X187081Y1528853D03*
X191805D03*
X196530D03*
X201254D03*
X196029Y1536063D03*
X200753D03*
X191304D03*
X197703Y1542641D03*
X188254D03*
X192979D03*
X198026Y1592380D03*
X193766D03*
X192006Y1602380D03*
X199786D03*
X193766Y1624292D03*
X198026D03*
X199786Y1614292D03*
X192006D03*
X202427Y1507295D03*
X207152D03*
X211876D03*
X216601D03*
X205427Y1521453D03*
X210152D03*
X214876D03*
X205758Y1514243D03*
X215206D03*
X210482D03*
X205978Y1528853D03*
X210703D03*
X215427D03*
X214926Y1536063D03*
X211876Y1542641D03*
X202427D03*
X207152D03*
X216601D03*
X210086Y1592380D03*
X205826D03*
X216126Y1602380D03*
X204066D03*
X211846D03*
X205826Y1624292D03*
X210086D03*
X216126Y1614292D03*
X211846D03*
X204066D03*
X221325Y1507295D03*
X226049D03*
X230774D03*
X219601Y1521453D03*
X224325D03*
X229049D03*
X219931Y1514243D03*
X224655D03*
X229380D03*
X220152Y1528853D03*
X224876D03*
X229600D03*
X224375Y1536063D03*
X226049Y1542641D03*
X230774D03*
X221325D03*
X229946Y1592380D03*
X217886D03*
X222146D03*
X223906Y1602380D03*
X228186D03*
X229946Y1624292D03*
X222146D03*
X217886D03*
X228186Y1614292D03*
X223906D03*
X235498Y1507295D03*
X240223D03*
X244947D03*
X243223Y1521453D03*
X238498D03*
X233774D03*
X234104Y1514243D03*
X238828D03*
X243553D03*
X243774Y1528853D03*
X239049D03*
X234325D03*
X238548Y1536063D03*
X240223Y1542641D03*
X235498D03*
X244947D03*
X242006Y1592380D03*
X234206D03*
X246266D03*
X235966Y1602380D03*
X240246D03*
X246266Y1624292D03*
X242006D03*
X234206D03*
X240246Y1614292D03*
X235966D03*
X241141Y1679320D03*
Y1683857D03*
X233267Y1675383D03*
Y1679920D03*
Y1684454D03*
X241141Y1688391D03*
Y1693493D03*
Y1698030D03*
X233267Y1689556D03*
Y1694093D03*
Y1698627D03*
X241141Y1702564D03*
Y1707666D03*
Y1712203D03*
Y1716737D03*
X233267Y1703729D03*
Y1708266D03*
Y1712800D03*
X241141Y1721840D03*
Y1726377D03*
Y1730911D03*
X233267Y1717903D03*
Y1722440D03*
Y1726974D03*
X259120Y1507295D03*
X249671D03*
X254396D03*
X257396Y1521453D03*
X252672D03*
X247947D03*
X248277Y1514243D03*
X257726D03*
X257947Y1528853D03*
X253223D03*
X248498D03*
X257446Y1536063D03*
X247997D03*
X254396Y1542641D03*
X259120D03*
X249671D03*
X258326Y1592380D03*
X254066D03*
X248026Y1602380D03*
X252306D03*
X260086D03*
X258326Y1624292D03*
X254066D03*
X248026Y1614292D03*
X252306D03*
X260086D03*
X256889Y1679320D03*
Y1683857D03*
X249015Y1684454D03*
Y1679920D03*
Y1675383D03*
X256889Y1688391D03*
Y1693493D03*
Y1698030D03*
X249015Y1698627D03*
Y1694093D03*
Y1689556D03*
X256889Y1702564D03*
Y1707666D03*
Y1712203D03*
Y1716737D03*
X249015Y1712800D03*
Y1708266D03*
Y1703729D03*
X256889Y1721840D03*
Y1726377D03*
Y1730911D03*
X249015Y1726974D03*
Y1722440D03*
Y1717903D03*
X262141Y1521453D03*
X262777Y1536063D03*
X270386Y1592380D03*
X266126D03*
X264366Y1602380D03*
X272146D03*
X270386Y1624292D03*
X266126D03*
X272146Y1614292D03*
X264366D03*
X272637Y1679320D03*
Y1683857D03*
X264763Y1684454D03*
Y1679920D03*
Y1675383D03*
X272637Y1688391D03*
Y1693493D03*
Y1698030D03*
X264763Y1698627D03*
Y1694093D03*
Y1689556D03*
X272637Y1702564D03*
Y1707666D03*
Y1712203D03*
Y1716737D03*
X264763Y1712800D03*
Y1708266D03*
Y1703729D03*
X272637Y1721840D03*
Y1726377D03*
Y1730911D03*
X264763Y1726974D03*
Y1722440D03*
Y1717903D03*
X290246Y1592380D03*
X278186D03*
X282446D03*
X276426Y1602380D03*
X284206D03*
X288486D03*
X290236Y1624292D03*
X282446D03*
X278186D03*
X288486Y1614292D03*
X284206D03*
X276426D03*
X288385Y1683857D03*
Y1679320D03*
X280511Y1684454D03*
Y1679920D03*
Y1675383D03*
X288385Y1688391D03*
Y1693494D03*
Y1698031D03*
X280511Y1698627D03*
Y1694093D03*
Y1689556D03*
X288385Y1712204D03*
Y1716738D03*
Y1702565D03*
Y1707667D03*
X280511Y1712800D03*
Y1708266D03*
Y1703729D03*
X288385Y1721840D03*
Y1726377D03*
Y1730911D03*
X280511Y1726974D03*
Y1722440D03*
Y1717903D03*
X305641Y1528725D03*
Y1523810D03*
X302306Y1592380D03*
X294506D03*
X296266Y1602380D03*
X300546D03*
X302306Y1624292D03*
X294516D03*
X300546Y1614292D03*
X296266D03*
X300196Y1675383D03*
Y1679920D03*
Y1684454D03*
Y1689556D03*
Y1694093D03*
Y1698627D03*
Y1703729D03*
Y1708266D03*
Y1712800D03*
Y1717903D03*
Y1722440D03*
Y1726974D03*
X309886Y1028056D03*
X315437Y1031245D03*
X317288Y1040812D03*
X309886D03*
X317288Y1034434D03*
X309886D03*
X315437Y1044001D03*
X309886Y1047190D03*
X311736Y1056757D03*
X309886Y1053568D03*
X315437Y1050379D03*
X317288Y1053568D03*
Y1059946D03*
X309886D03*
X313587D03*
X315437Y1063135D03*
X317288Y1072702D03*
X309886D03*
Y1066324D03*
X315437Y1069513D03*
X317288Y1079080D03*
X309886D03*
X315437Y1082269D03*
Y1088647D03*
X309886Y1085458D03*
Y1091836D03*
X317288D03*
X309886Y1104592D03*
X315437Y1101403D03*
X317288Y1098214D03*
X309886D03*
X315437Y1107781D03*
X309886Y1110970D03*
X317288D03*
X309886Y1117348D03*
X317288D03*
X309886Y1123726D03*
X315437Y1120537D03*
Y1126915D03*
X309886Y1130103D03*
X317288D03*
X309886Y1136481D03*
X315437Y1139670D03*
X317288Y1136481D03*
X309886Y1142859D03*
X317288Y1149237D03*
X309886D03*
X315437Y1146048D03*
X317288Y1155615D03*
X309886D03*
X313587D03*
X308036Y1158804D03*
X311736Y1165182D03*
X320988Y1155615D03*
Y1161993D03*
X311009Y1507514D03*
X316316Y1507295D03*
X321041D03*
X319316Y1521453D03*
X314592D03*
X313750Y1519195D03*
X314922Y1514243D03*
X319646D03*
X319867Y1528853D03*
X315143D03*
X319366Y1536063D03*
X314641D03*
X311113Y1542425D03*
X316316Y1542641D03*
X321041D03*
X318626Y1592380D03*
X306566D03*
X314366D03*
X308326Y1602380D03*
X312606D03*
X320386D03*
X314366Y1624292D03*
X318626D03*
X306566D03*
X320386Y1614292D03*
X312606D03*
X308326D03*
X315944Y1675383D03*
Y1679920D03*
Y1684454D03*
X308070Y1683857D03*
Y1679320D03*
X315944Y1689556D03*
Y1694093D03*
Y1698627D03*
X308070Y1698030D03*
Y1693493D03*
Y1688391D03*
X315944Y1703729D03*
Y1708266D03*
Y1712800D03*
X308070Y1716737D03*
Y1712203D03*
Y1707666D03*
Y1702564D03*
X315944Y1722440D03*
Y1726974D03*
X308070Y1730911D03*
Y1726377D03*
Y1721840D03*
X315944Y1717903D03*
X328390Y1028056D03*
X335791D03*
X322839Y1031245D03*
Y1037623D03*
Y1044001D03*
X328390Y1040812D03*
Y1034434D03*
X330240Y1031245D03*
Y1037623D03*
Y1044001D03*
X335791Y1040812D03*
Y1034434D03*
X328390Y1047190D03*
X322839Y1050379D03*
Y1056757D03*
X326539D03*
X328390Y1053568D03*
Y1059946D03*
X324689D03*
X330240Y1050379D03*
Y1056757D03*
X335791Y1047190D03*
Y1053568D03*
Y1059946D03*
X328390Y1072702D03*
X330240Y1069513D03*
X335791Y1072702D03*
Y1066324D03*
X322839Y1063135D03*
X330240D03*
X322839Y1069513D03*
X328390Y1066324D03*
X322839Y1075891D03*
X330240D03*
X328390Y1079080D03*
X322839Y1088647D03*
X328390Y1085458D03*
X330240Y1088647D03*
X322839Y1082269D03*
X330240D03*
X335791Y1079080D03*
Y1085458D03*
X328390Y1091836D03*
X322839Y1095025D03*
X330240D03*
X328390Y1104592D03*
Y1098214D03*
X322839Y1101403D03*
X330240D03*
X335791Y1091836D03*
Y1104592D03*
Y1098214D03*
X322839Y1107781D03*
X330240D03*
X328390Y1110970D03*
Y1117348D03*
X330240Y1114159D03*
X322839D03*
X335791Y1110970D03*
Y1117348D03*
X330240Y1126915D03*
X322839D03*
X328390Y1123726D03*
X330240Y1120537D03*
X322839D03*
Y1133293D03*
X330240D03*
X328390Y1130103D03*
X335791Y1123726D03*
X335792Y1130105D03*
X328390Y1142859D03*
X322839Y1139670D03*
X328390Y1136481D03*
X330240Y1139670D03*
X328390Y1149237D03*
X330240Y1146048D03*
X322839D03*
X335791Y1136481D03*
Y1142859D03*
Y1149237D03*
X328390Y1155615D03*
X330240Y1152426D03*
X322839D03*
X326539Y1158804D03*
X330240D03*
X333941D03*
X322839D03*
X328390Y1161993D03*
X330240Y1165182D03*
X335791Y1155615D03*
Y1161993D03*
X330489Y1507295D03*
X335214D03*
X325765D03*
X333489Y1521453D03*
X328765D03*
X324041D03*
X324371Y1514243D03*
X329095D03*
X333820D03*
X334040Y1528853D03*
X329316D03*
X324592D03*
X324091Y1536063D03*
X328815D03*
X325765Y1542641D03*
X330489D03*
X335214D03*
X330686Y1592380D03*
X326426D03*
X324666Y1602380D03*
X332446D03*
X326426Y1624292D03*
X330686D03*
X332446Y1614292D03*
X324666D03*
X331692Y1675383D03*
Y1679920D03*
Y1684454D03*
X323818Y1683857D03*
Y1679320D03*
X331692Y1689556D03*
Y1694093D03*
Y1698627D03*
X323818Y1698030D03*
Y1693493D03*
Y1688391D03*
X331692Y1703729D03*
Y1708266D03*
Y1712800D03*
X323818Y1716737D03*
Y1712203D03*
Y1707666D03*
Y1702564D03*
Y1721840D03*
X331692Y1717903D03*
Y1722440D03*
Y1726974D03*
X323818Y1730911D03*
Y1726377D03*
X348744Y1031245D03*
X341343D03*
X343193Y1040812D03*
X348744Y1037623D03*
X343193Y1034434D03*
X348744Y1044001D03*
X341343D03*
X350595Y1059946D03*
X337642Y1056757D03*
X348744D03*
X343193Y1053568D03*
X341343Y1050379D03*
X348744D03*
X343193Y1059946D03*
X339492D03*
X341343Y1063135D03*
X348744D03*
X341343Y1069513D03*
X343193Y1072702D03*
X348744Y1069513D03*
X343193Y1079080D03*
X348744Y1075891D03*
X341343Y1082269D03*
X348744D03*
X341343Y1088647D03*
X348744D03*
Y1095025D03*
X343193Y1091836D03*
X348744Y1101403D03*
X341343D03*
X343193Y1098214D03*
X341343Y1107781D03*
X348744D03*
X343193Y1110970D03*
Y1117348D03*
X348744Y1114159D03*
Y1120537D03*
X341343D03*
Y1126915D03*
X348744D03*
Y1133293D03*
X343193Y1130103D03*
X341343Y1139670D03*
X343193Y1136481D03*
X348744Y1139670D03*
X343193Y1149237D03*
X348744Y1146048D03*
X341343D03*
X348744Y1152426D03*
X337642Y1158804D03*
X341343D03*
X348744D03*
X339492Y1155615D03*
X343193D03*
X346894D03*
X337642Y1165182D03*
X343193Y1161993D03*
X346894D03*
X348744Y1165182D03*
X339938Y1507295D03*
X344663D03*
X349387D03*
X347663Y1521453D03*
X342938D03*
X338214D03*
X338544Y1514243D03*
X343268D03*
X347993D03*
X348214Y1528853D03*
X343489D03*
X338765D03*
X342988Y1536063D03*
X339938Y1542641D03*
X344663D03*
X349387D03*
X338486Y1592380D03*
X342746D03*
X350546D03*
X336726Y1602380D03*
X344506D03*
X348786D03*
X350546Y1624292D03*
X342746D03*
X338486D03*
X348786Y1614292D03*
X344506D03*
X336726D03*
X347440Y1675383D03*
Y1679920D03*
Y1684454D03*
X339566Y1683857D03*
Y1679320D03*
X347440Y1694093D03*
Y1698627D03*
X339566Y1698030D03*
Y1693493D03*
Y1688391D03*
X347440Y1689556D03*
Y1703729D03*
Y1708266D03*
Y1712800D03*
X339566Y1716737D03*
Y1712203D03*
Y1707666D03*
Y1702564D03*
X347440Y1717903D03*
Y1722440D03*
Y1726974D03*
X339566Y1730911D03*
Y1726377D03*
Y1721840D03*
X354295Y1028056D03*
X361697D03*
Y1040812D03*
X356146Y1044001D03*
X354295Y1040812D03*
Y1034434D03*
X356146Y1031245D03*
Y1037623D03*
X361697Y1034434D03*
X354295Y1047190D03*
X361697D03*
X354295Y1053568D03*
Y1059946D03*
X363547Y1056757D03*
X356146D03*
Y1050379D03*
X361697Y1053568D03*
X365398Y1059946D03*
X361697D03*
X352445Y1056757D03*
X356146Y1063135D03*
X354295Y1072702D03*
Y1066324D03*
X356146Y1069513D03*
X361697Y1066324D03*
Y1072702D03*
X356146Y1075891D03*
X354295Y1079080D03*
X361697D03*
X354295Y1085458D03*
X356146Y1088647D03*
X361697Y1085458D03*
X356146Y1082269D03*
X354295Y1091836D03*
X361697D03*
X356146Y1095025D03*
X354295Y1104592D03*
Y1098214D03*
X361697Y1104592D03*
X356146Y1101403D03*
X361697Y1098214D03*
X356146Y1107781D03*
X354295Y1110970D03*
X361697D03*
Y1117348D03*
X356146Y1114159D03*
X354295Y1117348D03*
Y1123726D03*
X356146Y1126915D03*
Y1120537D03*
X361697Y1123726D03*
X356146Y1133293D03*
X361697Y1130103D03*
X354296Y1130105D03*
X354295Y1136481D03*
X356146Y1139670D03*
X361697Y1136481D03*
X354295Y1142859D03*
X361697D03*
Y1149237D03*
X356146Y1146048D03*
X354295Y1149237D03*
X363547Y1165182D03*
X356146D03*
X361697Y1161993D03*
X363547Y1158804D03*
X356146D03*
X359847D03*
X352445D03*
X365398Y1155615D03*
X356146Y1152426D03*
X361697Y1155615D03*
X354295D03*
Y1161993D03*
X354111Y1507295D03*
X358836D03*
X363560D03*
X361836Y1521453D03*
X357111D03*
X352387D03*
X352717Y1514243D03*
X357442D03*
X362166D03*
X362387Y1528853D03*
X357662D03*
X352938D03*
X352437Y1536063D03*
X354111Y1542641D03*
X358836D03*
X363560D03*
X362606Y1592380D03*
X354806D03*
X356566Y1602380D03*
X360846D03*
X354806Y1624292D03*
X360846Y1614292D03*
X356566D03*
X362606Y1624292D03*
X355314Y1683857D03*
Y1679320D03*
Y1688391D03*
Y1698030D03*
Y1693493D03*
Y1716737D03*
Y1712203D03*
Y1707666D03*
Y1702564D03*
Y1730911D03*
Y1726377D03*
Y1721840D03*
X380201Y1028056D03*
X367248Y1031245D03*
Y1044001D03*
X369099Y1034434D03*
Y1040812D03*
X374650Y1031245D03*
X380201Y1040812D03*
Y1034434D03*
X374650Y1037623D03*
Y1044001D03*
X367248Y1050379D03*
X380201Y1047190D03*
X369099Y1053568D03*
Y1059946D03*
X380201Y1053568D03*
X378351Y1056757D03*
X374650Y1050379D03*
Y1056757D03*
X380201Y1059946D03*
X376500D03*
X367248Y1063135D03*
Y1069513D03*
X374650Y1063135D03*
X369099Y1072702D03*
X380201D03*
X374650Y1069513D03*
X367248Y1088647D03*
Y1082269D03*
X374650Y1075891D03*
X369099Y1079080D03*
X380201Y1085458D03*
X374650Y1088647D03*
Y1082269D03*
X367248Y1101403D03*
X369099Y1091836D03*
X374650Y1095025D03*
X369099Y1098214D03*
X380201Y1104592D03*
Y1098214D03*
X374650Y1101403D03*
X367248Y1107781D03*
X374650D03*
X369099Y1110970D03*
Y1117348D03*
X380201D03*
X374650Y1114159D03*
X367248Y1120537D03*
Y1126915D03*
X374650Y1120537D03*
Y1126915D03*
X380201Y1130103D03*
X374650Y1133293D03*
X369099Y1130103D03*
X367248Y1139670D03*
Y1146048D03*
X380201Y1142859D03*
X374650Y1139670D03*
X369099Y1136481D03*
Y1149237D03*
X374650Y1146048D03*
X380201Y1155615D03*
X369099D03*
X372799D03*
X374650Y1152426D03*
X378351Y1158804D03*
X374650D03*
X376500Y1161993D03*
X377523Y1222274D03*
X372730Y1216782D03*
X367697Y1216624D03*
X377733Y1507295D03*
X368285D03*
X373009D03*
X376009Y1521453D03*
X380734D03*
X366560D03*
X371285D03*
X376339Y1514243D03*
X366890D03*
X371615D03*
X376560Y1528853D03*
X367111D03*
X371836D03*
X376059Y1536063D03*
X366610D03*
X377733Y1542641D03*
X368285D03*
X373009D03*
X374666Y1592380D03*
X366866D03*
X380696Y1602380D03*
X368626Y1602286D03*
X372906Y1602380D03*
X374666Y1624292D03*
X380696Y1614292D03*
X372906D03*
X368626D03*
X366866Y1624292D03*
X387603Y1028056D03*
X395004D03*
X393154Y1044001D03*
X385752Y1031245D03*
Y1037623D03*
Y1044001D03*
X395004Y1040812D03*
X387603Y1034434D03*
Y1040812D03*
X395004Y1034434D03*
X393154Y1031245D03*
Y1037623D03*
X395004Y1047190D03*
X387603D03*
Y1053568D03*
X391303Y1059946D03*
X395004Y1053568D03*
X385752Y1050379D03*
X393154Y1056757D03*
Y1050379D03*
X382051Y1063135D03*
Y1069513D03*
X393154Y1063135D03*
X395004Y1066324D03*
X387603D03*
X383902D03*
X391303Y1072702D03*
Y1066324D03*
X393154Y1069513D03*
X385752D03*
Y1063135D03*
X389453Y1069513D03*
Y1063135D03*
X382051Y1075891D03*
Y1088647D03*
Y1082269D03*
X393154Y1075891D03*
X387603Y1079080D03*
X383902D03*
X391303D03*
X395004D03*
X393154Y1082269D03*
X391303Y1085458D03*
X393154Y1088647D03*
X385752Y1075891D03*
X389453D03*
X385752Y1088647D03*
Y1082269D03*
X389453Y1088647D03*
Y1082269D03*
X382051Y1095025D03*
X383902Y1091836D03*
X393154Y1095025D03*
X391303Y1091836D03*
X395004D03*
X387603D03*
X391303Y1098214D03*
Y1104592D03*
X395004D03*
X387603D03*
X383902D03*
X385752Y1095025D03*
X389453D03*
X382051Y1107781D03*
Y1114159D03*
X383902Y1110970D03*
X387603D03*
X393154Y1107781D03*
X391303Y1110970D03*
X395004D03*
X391303Y1117348D03*
X393154Y1114159D03*
X391304Y1130105D03*
X382051Y1126915D03*
Y1120537D03*
Y1133293D03*
X383902Y1123726D03*
X387603D03*
X393154Y1126915D03*
X391303Y1123726D03*
X395004D03*
X393154Y1120537D03*
Y1133293D03*
X382051Y1139670D03*
Y1146048D03*
X393154Y1139670D03*
X395004Y1136481D03*
X391303D03*
X383902D03*
X387603D03*
X391303Y1142859D03*
X393154Y1146048D03*
X395004Y1149237D03*
X383902D03*
X387603D03*
X389453Y1158804D03*
X391303Y1155615D03*
X395004D03*
X383902D03*
X387603D03*
Y1161993D03*
X382458Y1507295D03*
X387182D03*
X390203Y1521453D03*
X385458D03*
X385788Y1514243D03*
X381285Y1528853D03*
X386009D03*
X385508Y1536063D03*
X390839D03*
X382458Y1542641D03*
X387182D03*
X398705Y1028056D03*
X409795Y1028064D03*
X398705Y1034434D03*
X402406Y1040812D03*
X400555Y1031245D03*
Y1037623D03*
Y1044001D03*
X409795Y1034442D03*
Y1040820D03*
X402406Y1047190D03*
X409807D03*
X402406Y1053568D03*
X407957Y1056757D03*
X402406Y1059946D03*
X409807Y1053568D03*
X400555Y1056757D03*
Y1050379D03*
X407957D03*
X398705Y1066324D03*
X404256Y1063135D03*
X402406Y1072702D03*
X404256Y1069513D03*
X406107Y1066324D03*
X409807D03*
X402406D03*
X396855Y1069513D03*
Y1063135D03*
X407957Y1069513D03*
Y1063135D03*
X400555Y1069513D03*
Y1063135D03*
X398705Y1079080D03*
X404256Y1075891D03*
X406107Y1079080D03*
X409807D03*
X402406D03*
X404256Y1088647D03*
X402406Y1085458D03*
X404256Y1082269D03*
X396855Y1075891D03*
X407957D03*
X400555D03*
X396855Y1088647D03*
Y1082269D03*
X407957Y1088647D03*
Y1082269D03*
X400555Y1088647D03*
Y1082269D03*
X398705Y1091836D03*
Y1104592D03*
X404256Y1095025D03*
X406107Y1091836D03*
X409807D03*
X402406D03*
Y1098214D03*
Y1104592D03*
X396855Y1095025D03*
X407957D03*
X400555D03*
X398705Y1110970D03*
X404256Y1107781D03*
X406107Y1110970D03*
X409807D03*
X402406D03*
X404256Y1114159D03*
X402406Y1117348D03*
X398705Y1123726D03*
X406107D03*
X409807D03*
X404256Y1120537D03*
X402406Y1123726D03*
X404256Y1126915D03*
Y1133293D03*
X402406Y1130103D03*
X398705Y1136481D03*
Y1149237D03*
X402406Y1142859D03*
X404256Y1139670D03*
X406107Y1136481D03*
X409807D03*
X402406D03*
X404256Y1146048D03*
X406107Y1149237D03*
X409807D03*
X398705Y1155615D03*
Y1161993D03*
X406107Y1155615D03*
X409807D03*
X402406D03*
X400555Y1158804D03*
X409807Y1161993D03*
X400555Y1165182D03*
X424598Y1040820D03*
X417197D03*
X413508Y1059946D03*
X417209Y1047190D03*
X424610D03*
Y1053568D03*
X422760Y1056757D03*
X424610Y1059946D03*
X417209Y1053568D03*
X415358Y1056757D03*
Y1050379D03*
X422760D03*
X413508Y1072702D03*
Y1066324D03*
X415358Y1063135D03*
X424610Y1072702D03*
Y1066324D03*
X420910D03*
X417209D03*
X415358Y1069513D03*
X419059Y1063135D03*
Y1069513D03*
X422760Y1063135D03*
X411658Y1069513D03*
Y1063135D03*
X422760Y1069513D03*
X413508Y1079080D03*
Y1085458D03*
X415358Y1075891D03*
X420910Y1079080D03*
X424610D03*
X417209D03*
X424610Y1085458D03*
X415358Y1088647D03*
Y1082269D03*
X419059Y1075891D03*
X422760D03*
X411658D03*
X419059Y1082269D03*
Y1088647D03*
X422760Y1082269D03*
X411658Y1088647D03*
Y1082269D03*
X422760Y1088647D03*
X413508Y1091836D03*
Y1098214D03*
Y1104592D03*
X415358Y1095025D03*
X420910Y1091836D03*
X424610D03*
X417209D03*
X420910Y1104592D03*
X424610D03*
Y1098214D03*
X417209Y1104592D03*
X415358Y1101403D03*
X419059Y1095025D03*
Y1101403D03*
X422760Y1095025D03*
Y1101403D03*
X411658Y1095025D03*
X413508Y1110970D03*
Y1117348D03*
X415358Y1107781D03*
X424610Y1110970D03*
X420910D03*
X417209D03*
X424610Y1117348D03*
X415358Y1114159D03*
Y1120537D03*
Y1126915D03*
X424610Y1123726D03*
X420910D03*
X417209D03*
X415358Y1133293D03*
X413508Y1123726D03*
Y1130103D03*
X424611Y1130105D03*
X413508Y1142859D03*
Y1136481D03*
X424610Y1142859D03*
Y1136481D03*
X420910D03*
X415358Y1139670D03*
X417209Y1136481D03*
X420910Y1149237D03*
X417209D03*
X415358Y1146048D03*
X413508Y1155615D03*
X411658Y1158804D03*
X424610Y1155615D03*
X420910D03*
X417209D03*
X422760Y1158804D03*
Y1165182D03*
X420910Y1161993D03*
X430162Y1056757D03*
Y1050379D03*
X432012Y1047190D03*
Y1053568D03*
X435713Y1059946D03*
X428311D03*
X432012D03*
X426461Y1063135D03*
X430162D03*
X426461Y1069513D03*
X433862Y1063135D03*
X435713Y1072702D03*
Y1066324D03*
X428311Y1072702D03*
Y1066324D03*
X432012Y1072702D03*
Y1066324D03*
X430162Y1075891D03*
X426461D03*
X430162Y1088647D03*
X426461D03*
Y1082269D03*
X433862Y1075891D03*
X435713Y1079080D03*
Y1085458D03*
X433862Y1088647D03*
X428311Y1079080D03*
X432012D03*
X428311Y1085458D03*
X432012D03*
X426461Y1095025D03*
X430162Y1101403D03*
X426461D03*
X435713Y1091836D03*
Y1098214D03*
Y1104592D03*
X433862Y1101403D03*
X428311Y1098214D03*
Y1091836D03*
X432012Y1098214D03*
Y1091836D03*
X430162Y1107781D03*
X426461D03*
Y1114159D03*
X433862Y1107781D03*
X435713Y1110970D03*
Y1117348D03*
X426461Y1126915D03*
X430162Y1120537D03*
X426461D03*
X430162Y1133293D03*
X426461D03*
X435713Y1123726D03*
X433862Y1120537D03*
X435713Y1130103D03*
X433862Y1133293D03*
X426461Y1139670D03*
Y1146048D03*
X428311Y1149237D03*
X435713Y1136481D03*
Y1142859D03*
Y1149237D03*
X432012D03*
X430162Y1158804D03*
X435713Y1155615D03*
Y1161993D03*
X454204Y1040820D03*
X446790Y1047190D03*
Y1053568D03*
Y1059946D03*
X454192Y1047190D03*
X448641Y1056757D03*
X454192Y1053568D03*
X448641Y1050379D03*
X454192Y1059946D03*
X450491D03*
X446790Y1066324D03*
Y1072702D03*
X452341Y1063135D03*
X448641D03*
X454192Y1066324D03*
Y1072702D03*
X450491Y1066324D03*
Y1072702D03*
X446790Y1079080D03*
Y1085458D03*
X452341Y1075891D03*
X448641D03*
X452341Y1088647D03*
X448641D03*
X454192Y1079080D03*
X450491D03*
X454192Y1085458D03*
X450491D03*
X446790Y1091836D03*
Y1098214D03*
Y1104592D03*
X452341Y1101403D03*
X448641D03*
X454192Y1091836D03*
Y1098214D03*
X450491Y1091836D03*
Y1098214D03*
X446790Y1110970D03*
Y1117348D03*
X452341Y1107781D03*
X448641D03*
X446790Y1123726D03*
Y1130103D03*
X448641Y1120537D03*
X452341D03*
Y1133293D03*
X448641D03*
X446790Y1136481D03*
Y1142859D03*
Y1149237D03*
X454192D03*
X450491D03*
X446790Y1155615D03*
Y1161993D03*
X454192Y1155615D03*
X447120Y1507512D03*
X452427Y1507295D03*
X450703Y1521453D03*
X451033Y1514243D03*
X449861Y1519195D03*
X451254Y1528853D03*
X450752Y1536063D03*
X441752Y1523810D03*
Y1528725D03*
X452427Y1542641D03*
X447224Y1542425D03*
X450139Y1592380D03*
Y1624292D03*
X469007Y1040820D03*
X461606D03*
X461593Y1047190D03*
Y1053568D03*
X456042Y1056757D03*
X457893Y1059946D03*
X456042Y1050379D03*
X468995Y1047190D03*
Y1053568D03*
Y1059946D03*
X463444Y1056757D03*
Y1050379D03*
X456042Y1063135D03*
Y1069513D03*
X457893Y1072702D03*
Y1066324D03*
X461593D03*
X467145Y1063135D03*
X468995Y1072702D03*
Y1066324D03*
X467145Y1069513D03*
X465294Y1066324D03*
X463444Y1063135D03*
Y1069513D03*
X459743Y1063135D03*
Y1069513D03*
X456042Y1075891D03*
X461593Y1079080D03*
X457893D03*
X456042Y1088647D03*
X457893Y1085458D03*
X456042Y1082269D03*
X467145Y1075891D03*
X468995Y1079080D03*
X465294D03*
X468995Y1085458D03*
X467145Y1088647D03*
Y1082269D03*
X463444Y1075891D03*
X459743D03*
X463444Y1082269D03*
Y1088647D03*
X459743Y1082269D03*
Y1088647D03*
X457893Y1091836D03*
X461593D03*
X456042Y1095025D03*
X457893Y1098214D03*
X456042Y1101403D03*
X457893Y1104592D03*
X461593D03*
X467145Y1095025D03*
X468995Y1091836D03*
X465294D03*
X468995Y1104592D03*
X465294D03*
X468995Y1098214D03*
X467145Y1101403D03*
X463444D03*
Y1095025D03*
X459743Y1101403D03*
Y1095025D03*
X456042Y1107781D03*
X457893Y1110970D03*
X461593D03*
X457893Y1117348D03*
X456042Y1114159D03*
X468995Y1110970D03*
X465294D03*
X467145Y1107781D03*
Y1114159D03*
X468995Y1117348D03*
X456042Y1126915D03*
X461593Y1123726D03*
X457893D03*
X456042Y1120537D03*
Y1133293D03*
X468995Y1123726D03*
X467145Y1120537D03*
X465294Y1123726D03*
X467145Y1126915D03*
X468995Y1130103D03*
X467145Y1133293D03*
X457893Y1130104D03*
X456042Y1139670D03*
X461593Y1136481D03*
X457893D03*
Y1142859D03*
X456042Y1146048D03*
X461593Y1149237D03*
X468995Y1142859D03*
X467145Y1139670D03*
X468995Y1136481D03*
X465294D03*
X467145Y1146048D03*
X465294Y1149237D03*
X459743Y1158804D03*
Y1152426D03*
X465294Y1155615D03*
X457152Y1507295D03*
X461876D03*
X466600D03*
X469600Y1521453D03*
X464876D03*
X460152D03*
X455427D03*
X455757Y1514243D03*
X460482D03*
X465206D03*
X469931D03*
X470151Y1528853D03*
X465427D03*
X460703D03*
X455978D03*
X464926Y1536063D03*
X460202D03*
X455477D03*
X466600Y1542641D03*
X457152D03*
X461876D03*
X469999Y1592380D03*
X457939D03*
X462199D03*
X463959Y1602380D03*
X456179D03*
X468239D03*
X457939Y1624292D03*
X463959Y1614292D03*
X456179D03*
X468239D03*
X469999Y1624292D03*
X462199D03*
X480097Y1028056D03*
X478247Y1037623D03*
Y1044001D03*
X480097Y1034434D03*
X483798Y1040812D03*
X481948Y1031245D03*
X476400Y1040820D03*
X476397Y1047190D03*
Y1053568D03*
X470845Y1056757D03*
X478247D03*
X470845Y1050379D03*
X478247D03*
X483798Y1047190D03*
Y1053568D03*
X480097Y1059946D03*
X478247Y1063135D03*
X472696Y1066324D03*
X476397D03*
X478247Y1069513D03*
X483798Y1066324D03*
X480097Y1072702D03*
Y1066324D03*
X474546Y1063135D03*
Y1069513D03*
X481948Y1063135D03*
Y1069513D03*
X470845Y1063135D03*
Y1069513D03*
X478247Y1075891D03*
X476397Y1079080D03*
X472696D03*
X478247Y1088647D03*
Y1082269D03*
X483798Y1079080D03*
X480097D03*
Y1085458D03*
X474546Y1075891D03*
X481948D03*
X470845D03*
X474546Y1082269D03*
Y1088647D03*
X481948Y1082269D03*
Y1088647D03*
X470845Y1082269D03*
Y1088647D03*
X480097Y1104592D03*
X483798D03*
X480097Y1098214D03*
X478247Y1095025D03*
X472696Y1091836D03*
X476397D03*
X480097D03*
X483798D03*
X474546Y1095025D03*
X481948D03*
X470845D03*
X472696Y1110970D03*
X476397D03*
X478247Y1107781D03*
Y1114159D03*
X483798Y1110970D03*
X480097D03*
Y1117348D03*
X476397Y1123726D03*
X472696D03*
X478247Y1120537D03*
Y1126915D03*
Y1133293D03*
X483798Y1123726D03*
X480097D03*
Y1130103D03*
X478247Y1139670D03*
X476397Y1136481D03*
X472696D03*
X476397Y1149237D03*
X472696D03*
X478247Y1146048D03*
X483798Y1136481D03*
X480097D03*
Y1142859D03*
X483798Y1149237D03*
X476397Y1155615D03*
X474546Y1152426D03*
X470845Y1158804D03*
X481948D03*
X471325Y1507295D03*
X476049D03*
X480774D03*
X483774Y1521453D03*
X479049D03*
X474325D03*
X474655Y1514243D03*
X479379D03*
X484104D03*
X484325Y1528853D03*
X479600D03*
X474876D03*
X479099Y1536063D03*
X476049Y1542641D03*
X471325D03*
X480774D03*
X482059Y1592380D03*
X474259D03*
X476019Y1602380D03*
X480299D03*
X482059Y1624292D03*
X476019Y1614292D03*
X474259Y1624292D03*
X480299Y1614292D03*
X494901Y1028056D03*
X487499D03*
X485649Y1044001D03*
X494901Y1034434D03*
X491200Y1040812D03*
X487499Y1034434D03*
X489349Y1031245D03*
X493050Y1037623D03*
X485649D03*
X493050Y1044001D03*
X496751Y1031245D03*
X498601Y1040812D03*
X491200Y1047190D03*
X493050Y1056757D03*
X491200Y1059946D03*
Y1053568D03*
X485649Y1056757D03*
X493050Y1050379D03*
X485649D03*
X498601Y1047190D03*
Y1053568D03*
X489349Y1063135D03*
X494901Y1066324D03*
X491200D03*
X487499D03*
X491200Y1072702D03*
X489349Y1069513D03*
X498601Y1066324D03*
X485649Y1063135D03*
Y1069513D03*
X496751Y1063135D03*
Y1069513D03*
X493050Y1063135D03*
Y1069513D03*
X489349Y1082269D03*
X498601Y1079080D03*
X494901D03*
X489349Y1075891D03*
X487499Y1079080D03*
X491200D03*
Y1085458D03*
X489349Y1088647D03*
X485649Y1075891D03*
X496751D03*
X493050D03*
X485649Y1082269D03*
Y1088647D03*
X496751Y1082269D03*
Y1088647D03*
X493050Y1082269D03*
Y1088647D03*
X494901Y1091836D03*
X487499D03*
X491200D03*
X489349Y1095025D03*
X494901Y1104592D03*
X491200Y1098214D03*
Y1104592D03*
X487499D03*
X498601Y1091836D03*
Y1104592D03*
X496751Y1101403D03*
X485649Y1095025D03*
X496751D03*
X493050D03*
X491200Y1110970D03*
X489349Y1114159D03*
X491200Y1117348D03*
X498601Y1110970D03*
X494901D03*
X489349Y1107781D03*
X487499Y1110970D03*
X494901Y1123726D03*
X489349Y1126915D03*
X491200Y1123726D03*
X487499D03*
X489349Y1120537D03*
X491200Y1130103D03*
X489349Y1133293D03*
X498601Y1123726D03*
X494901Y1136481D03*
X489349Y1139670D03*
X491200Y1136481D03*
X487499D03*
X491200Y1142859D03*
X494901Y1149237D03*
X489349Y1146048D03*
X487499Y1149237D03*
X498601Y1136481D03*
Y1149237D03*
X487499Y1155615D03*
X485649Y1152426D03*
X493050Y1158804D03*
X498601Y1155615D03*
X496751Y1152426D03*
X485498Y1507295D03*
X490222D03*
X499671D03*
X494947D03*
X497947Y1521453D03*
X493222D03*
X488498D03*
X488828Y1514243D03*
X493553D03*
X498277D03*
X498498Y1528853D03*
X493773D03*
X489049D03*
X488548Y1536063D03*
X494947Y1542641D03*
X485498D03*
X490222D03*
X499671D03*
X498379Y1592380D03*
X486319D03*
X494119D03*
X488079Y1602380D03*
X492359D03*
X498379Y1624292D03*
X488079Y1614292D03*
X486319Y1624292D03*
X494119D03*
X492359Y1614292D03*
X497440Y1684454D03*
Y1679920D03*
Y1675383D03*
Y1698627D03*
Y1694093D03*
Y1689556D03*
Y1712800D03*
Y1708266D03*
Y1703729D03*
Y1726974D03*
Y1722440D03*
Y1717903D03*
X502302Y1028056D03*
X513405D03*
X507853Y1037623D03*
X500452D03*
X502302Y1034434D03*
X507853Y1044001D03*
X500452D03*
X507853Y1031245D03*
X513405Y1034434D03*
Y1040812D03*
X507853Y1056757D03*
Y1050379D03*
X500452Y1056757D03*
X504153D03*
X500452Y1050379D03*
X502302Y1059946D03*
X506003D03*
X513405Y1053568D03*
Y1059946D03*
X507853Y1063135D03*
X500452D03*
X507853Y1069513D03*
X500452D03*
X502302Y1072702D03*
X513405D03*
X507853Y1075891D03*
X500452D03*
X507853Y1088647D03*
X500452D03*
X502302Y1085458D03*
X507853Y1082269D03*
X500452D03*
X513405Y1079080D03*
X507853Y1095025D03*
X500452D03*
X502302Y1098214D03*
X507853Y1101403D03*
X502302Y1104592D03*
X513405Y1091836D03*
Y1098214D03*
X507853Y1107781D03*
X500452D03*
X507853Y1114159D03*
X502302Y1117348D03*
X500452Y1114159D03*
X513405Y1110970D03*
Y1117348D03*
X507853Y1120537D03*
X500452D03*
X507853Y1126915D03*
X500452D03*
X507853Y1133293D03*
X500452D03*
X502302Y1130103D03*
X513405Y1130104D03*
X507853Y1139670D03*
X500452D03*
X502302Y1142859D03*
X507853Y1146048D03*
X500452D03*
X513405Y1136481D03*
Y1149237D03*
X511554Y1165182D03*
X509704Y1155615D03*
X507853Y1152426D03*
X502302Y1155615D03*
X507853Y1158804D03*
X504153D03*
X513405Y1155615D03*
X504396Y1507295D03*
X509120D03*
X513844D03*
X512120Y1521453D03*
X507396D03*
X502671D03*
X503001Y1514243D03*
X507726D03*
X512450D03*
X512671Y1528853D03*
X507947D03*
X503222D03*
X512170Y1536063D03*
X502721D03*
X513844Y1542641D03*
X504396D03*
X509120D03*
X510439Y1592380D03*
X506179D03*
X512199Y1602380D03*
X500139D03*
X504419D03*
X512199Y1614292D03*
X500139D03*
X506179Y1624292D03*
X510439D03*
X504419Y1614292D03*
X505314Y1679320D03*
Y1683857D03*
X513188Y1684454D03*
Y1679920D03*
Y1675383D03*
X505314Y1688391D03*
Y1693493D03*
Y1698030D03*
X513188Y1698627D03*
Y1694093D03*
Y1689556D03*
X505314Y1707666D03*
Y1712203D03*
X513188Y1712800D03*
Y1708266D03*
Y1703729D03*
X505314Y1716737D03*
Y1702564D03*
Y1721840D03*
Y1726377D03*
Y1730911D03*
X513188Y1726974D03*
Y1722440D03*
Y1717903D03*
X520806Y1028056D03*
X528208D03*
X526357Y1037623D03*
Y1044001D03*
Y1031245D03*
X515255D03*
X520806Y1040812D03*
Y1034434D03*
X515255Y1044001D03*
X528208Y1040812D03*
Y1034434D03*
X520806Y1047190D03*
X526357Y1050379D03*
Y1056757D03*
X520806Y1053568D03*
X515255Y1050379D03*
X518956Y1056757D03*
X520806Y1059946D03*
X517105D03*
X528208Y1047190D03*
Y1053568D03*
Y1059946D03*
X526357Y1063135D03*
X515255D03*
X526357Y1069513D03*
X520806Y1066324D03*
Y1072702D03*
X515255Y1069513D03*
X528208Y1066324D03*
Y1072702D03*
X526357Y1075891D03*
X520806Y1079080D03*
X526357Y1088647D03*
Y1082269D03*
X520806Y1085458D03*
X515255Y1088647D03*
Y1082269D03*
X528208Y1079080D03*
Y1085458D03*
X526357Y1095025D03*
X520806Y1091836D03*
X526357Y1101403D03*
X520806Y1104592D03*
Y1098214D03*
X515255Y1101403D03*
X528208Y1091836D03*
Y1104592D03*
Y1098214D03*
X526357Y1107781D03*
X520806Y1110970D03*
X515255Y1107781D03*
X526357Y1114159D03*
X520806Y1117348D03*
X528208Y1110970D03*
Y1117348D03*
Y1130104D03*
X526357Y1120537D03*
Y1126915D03*
X520806Y1123726D03*
X515255Y1120537D03*
Y1126915D03*
X526357Y1133293D03*
X520806Y1130103D03*
X528208Y1123726D03*
X515255Y1139670D03*
X520806Y1142859D03*
X526357Y1139670D03*
X520806Y1136481D03*
X526357Y1146048D03*
X520806Y1149237D03*
X515255Y1146048D03*
X528208Y1136481D03*
Y1142859D03*
Y1149237D03*
X526357Y1152426D03*
Y1158804D03*
X520806Y1155615D03*
X517105D03*
X522657Y1158804D03*
X515255D03*
X517105Y1161993D03*
X528208Y1155615D03*
X518569Y1507295D03*
X523293D03*
X526314Y1521453D03*
X521569D03*
X516845D03*
X521899Y1514243D03*
X522120Y1528853D03*
X517396D03*
X521619Y1536063D03*
X526950D03*
X523293Y1542641D03*
X518569D03*
X518239Y1592380D03*
X522499D03*
X524259Y1602380D03*
X528539D03*
X516479D03*
X524259Y1614292D03*
X518239Y1624292D03*
X522499D03*
X528539Y1614292D03*
X516479D03*
X521062Y1679320D03*
Y1683857D03*
X528936Y1684454D03*
Y1679920D03*
Y1675383D03*
X521062Y1688391D03*
Y1693493D03*
Y1698030D03*
X528936Y1698627D03*
Y1694093D03*
Y1689556D03*
X521062Y1716737D03*
Y1702564D03*
Y1707666D03*
Y1712203D03*
X528936Y1712800D03*
Y1708266D03*
Y1703729D03*
X521062Y1721840D03*
Y1726377D03*
Y1730911D03*
X528936Y1726974D03*
Y1722440D03*
Y1717903D03*
X539310Y1028056D03*
X541160Y1031245D03*
X533759D03*
X539310Y1034434D03*
Y1040812D03*
X533759Y1037623D03*
X541160Y1044001D03*
X533759D03*
X543011Y1059946D03*
X530058Y1056757D03*
X541160Y1050379D03*
X539310Y1053568D03*
X533759Y1050379D03*
Y1056757D03*
X539310Y1059946D03*
X531908D03*
X541160Y1063135D03*
X533759D03*
X541160Y1069513D03*
X539310Y1072702D03*
X533759Y1069513D03*
Y1075891D03*
X539310Y1079080D03*
X541160Y1088647D03*
X533759D03*
X541160Y1082269D03*
X533759D03*
X539310Y1091836D03*
X533759Y1095025D03*
X539310Y1098214D03*
X541160Y1101403D03*
X533759D03*
X541160Y1107781D03*
X533759D03*
X539310Y1110970D03*
Y1117348D03*
X533759Y1114159D03*
X541160Y1120537D03*
X533759D03*
X541160Y1126915D03*
X533759D03*
X539310Y1130103D03*
X533759Y1133293D03*
X541160Y1139670D03*
X539310Y1136481D03*
X533759Y1139670D03*
Y1146048D03*
X541160D03*
X539310Y1149237D03*
X543011Y1155615D03*
X533759Y1158804D03*
X530058D03*
X539310Y1155615D03*
X535609D03*
X533759Y1152426D03*
X543011Y1161993D03*
X542359Y1592380D03*
X530299D03*
X534559D03*
X536319Y1602380D03*
X540599D03*
X542359Y1624292D03*
X536319Y1614292D03*
X530299Y1624292D03*
X534559D03*
X540599Y1614292D03*
X536810Y1679320D03*
Y1683857D03*
X544684Y1684454D03*
Y1679920D03*
Y1675383D03*
X536810Y1688391D03*
Y1693493D03*
Y1698030D03*
X544684Y1698627D03*
Y1694093D03*
Y1689556D03*
X536810Y1716737D03*
Y1702564D03*
Y1707666D03*
Y1712203D03*
X544684Y1712800D03*
Y1708266D03*
Y1703729D03*
X536810Y1721840D03*
Y1726377D03*
Y1730911D03*
X544684Y1726974D03*
Y1722440D03*
Y1717903D03*
X554113Y1028056D03*
X546712D03*
Y1040812D03*
Y1034434D03*
X552263Y1031245D03*
X554113Y1040812D03*
X552263Y1037623D03*
X554113Y1034434D03*
X552263Y1044001D03*
X559664Y1031245D03*
Y1037623D03*
Y1044001D03*
X546712Y1047190D03*
X554113D03*
X544861Y1056757D03*
X546712Y1053568D03*
Y1059946D03*
X552263Y1056757D03*
X555964D03*
X554113Y1053568D03*
X552263Y1050379D03*
X554113Y1059946D03*
X557814D03*
X559664Y1050379D03*
Y1056757D03*
X552263Y1063135D03*
X546712Y1072702D03*
Y1066324D03*
X552263Y1069513D03*
X554113Y1066324D03*
Y1072702D03*
X559664Y1063135D03*
Y1069513D03*
X552263Y1075891D03*
X546712Y1079080D03*
X554113D03*
X546712Y1085458D03*
X552263Y1088647D03*
X554113Y1085458D03*
X552263Y1082269D03*
X559664Y1075891D03*
Y1088647D03*
Y1082269D03*
X546712Y1091836D03*
X554113D03*
X552263Y1095025D03*
Y1101403D03*
X554113Y1098214D03*
X546712Y1104592D03*
Y1098214D03*
X554113Y1104592D03*
X559664Y1095025D03*
Y1101403D03*
X552263Y1107781D03*
X554113Y1110970D03*
X546712D03*
X554113Y1117348D03*
X552263Y1114159D03*
X546712Y1117348D03*
X559664Y1107781D03*
Y1114159D03*
X546712Y1123726D03*
X554113D03*
X552263Y1120537D03*
Y1126915D03*
Y1133293D03*
X554113Y1130103D03*
X559664Y1120537D03*
Y1126915D03*
Y1133293D03*
X546712Y1130104D03*
X552263Y1139670D03*
X554113Y1136481D03*
X546712D03*
X554113Y1142859D03*
X546712D03*
Y1149237D03*
X552263Y1146048D03*
X554113Y1149237D03*
X559664Y1139670D03*
Y1146048D03*
X555964Y1165182D03*
X554113Y1155615D03*
X552263Y1152426D03*
X555964Y1158804D03*
X552263D03*
X548562D03*
X546712Y1155615D03*
X554113Y1161993D03*
X559664Y1152426D03*
Y1158804D03*
X558679Y1592380D03*
X546619D03*
X554419D03*
X548379Y1602380D03*
X552659D03*
X558679Y1624292D03*
X548379Y1614292D03*
X546619Y1624292D03*
X554419D03*
X552659Y1614292D03*
X552558Y1679320D03*
Y1683857D03*
Y1688391D03*
Y1693493D03*
Y1698030D03*
Y1716737D03*
Y1702564D03*
Y1707666D03*
Y1712203D03*
Y1721840D03*
Y1726377D03*
Y1730911D03*
X565216Y1028056D03*
X572617D03*
X567066Y1031245D03*
X565215Y1034434D03*
Y1040812D03*
X572617Y1034434D03*
Y1040812D03*
X567066Y1044001D03*
X565215Y1059946D03*
X572617Y1047190D03*
X567066Y1050379D03*
X572617Y1053568D03*
X570767Y1056757D03*
X565215Y1053568D03*
X572617Y1059946D03*
X568916D03*
X567066Y1063135D03*
X572617Y1066324D03*
Y1072702D03*
X567066Y1069513D03*
X565215Y1072702D03*
Y1079080D03*
X572617D03*
X567066Y1088647D03*
X572617Y1085458D03*
X567066Y1082269D03*
X572617Y1091836D03*
X565215D03*
X572617Y1104592D03*
Y1098214D03*
X567066Y1101403D03*
X565215Y1098214D03*
X567066Y1107781D03*
X572617Y1110970D03*
X565215D03*
X572617Y1117348D03*
X565215D03*
X572617Y1123726D03*
X567066Y1120537D03*
Y1126915D03*
X572617Y1130103D03*
X565215D03*
X572617Y1136481D03*
X565215Y1149237D03*
X572617D03*
X567066Y1146048D03*
X572617Y1142859D03*
X567066Y1139670D03*
X565215Y1136481D03*
X574467Y1158804D03*
X565215Y1155615D03*
X568916D03*
X572617D03*
X561515D03*
X565215Y1161993D03*
X569814Y1523810D03*
Y1528725D03*
X570739Y1592380D03*
X566479D03*
X572499Y1602380D03*
X560439D03*
X564719D03*
X572499Y1614292D03*
X570739Y1624292D03*
X560439Y1614292D03*
X566479Y1624292D03*
X564719Y1614292D03*
X572243Y1683857D03*
X564369Y1684454D03*
Y1679920D03*
Y1675383D03*
X572243Y1679320D03*
X564369Y1694093D03*
Y1689556D03*
X572243Y1688391D03*
Y1693493D03*
Y1698030D03*
X564369Y1698627D03*
X572243Y1702564D03*
Y1707666D03*
Y1712203D03*
X564369Y1712800D03*
Y1708266D03*
Y1703729D03*
X572243Y1716737D03*
Y1726377D03*
Y1730911D03*
X564369Y1726974D03*
Y1722440D03*
Y1717903D03*
X572243Y1721840D03*
X577728Y906182D03*
Y912560D03*
Y918938D03*
Y925316D03*
Y931694D03*
Y938072D03*
Y944450D03*
Y950828D03*
Y957206D03*
Y963584D03*
Y969962D03*
Y976340D03*
Y982718D03*
Y989096D03*
Y995474D03*
Y1008230D03*
Y1001852D03*
X578909Y1030198D03*
Y1036576D03*
Y1042954D03*
Y1049332D03*
Y1055710D03*
Y1062088D03*
Y1074844D03*
Y1068466D03*
Y1087600D03*
Y1081222D03*
Y1093978D03*
Y1100356D03*
Y1106734D03*
Y1113112D03*
Y1119490D03*
Y1125868D03*
Y1132246D03*
Y1138623D03*
Y1145001D03*
Y1151379D03*
X578168Y1158804D03*
X575182Y1507514D03*
X580489Y1507295D03*
X585214D03*
X588214Y1521453D03*
X583489D03*
X578765D03*
X579095Y1514243D03*
X583819D03*
X588544D03*
X577923Y1519195D03*
X588765Y1528853D03*
X584040D03*
X579316D03*
X588264Y1536063D03*
X583539D03*
X578814D03*
X585214Y1542641D03*
X580489D03*
X575286Y1542425D03*
X578539Y1592380D03*
X582799D03*
X584559Y1602380D03*
X588839D03*
X576779D03*
X584559Y1614292D03*
X582799Y1624292D03*
X578539D03*
X588839Y1614292D03*
X576779D03*
X587991Y1679320D03*
Y1683857D03*
X580117Y1684454D03*
Y1679920D03*
Y1675383D03*
X587991Y1688391D03*
Y1693493D03*
Y1698030D03*
X580117Y1698627D03*
Y1694093D03*
Y1689556D03*
X587991Y1716737D03*
Y1702564D03*
Y1707666D03*
Y1712203D03*
X580117Y1712800D03*
Y1708266D03*
Y1703729D03*
X587991Y1721840D03*
Y1726377D03*
Y1730911D03*
X580117Y1726974D03*
Y1722440D03*
Y1717903D03*
X589938Y1507295D03*
X594662D03*
X599387D03*
X604111D03*
X602387Y1521453D03*
X597662D03*
X592938D03*
X593268Y1514243D03*
X597993D03*
X602717D03*
X602938Y1528853D03*
X598213D03*
X593489D03*
X592988Y1536063D03*
X589938Y1542641D03*
X604111D03*
X599387D03*
X594662D03*
X602659Y1592380D03*
X590599D03*
X594859D03*
X596619Y1602380D03*
X600899D03*
X602659Y1624292D03*
X596619Y1614292D03*
X594859Y1624292D03*
X590599D03*
X600899Y1614292D03*
X603739Y1679320D03*
Y1683857D03*
X595865Y1684454D03*
Y1679920D03*
Y1675383D03*
X603739Y1688391D03*
Y1693493D03*
Y1698030D03*
X595865Y1698627D03*
Y1694093D03*
Y1689556D03*
X603739Y1716737D03*
Y1702564D03*
Y1707666D03*
Y1712203D03*
X595865Y1712800D03*
Y1708266D03*
Y1703729D03*
X603739Y1721840D03*
Y1726377D03*
Y1730911D03*
X595865Y1726974D03*
Y1722440D03*
Y1717903D03*
X608836Y1507295D03*
X613560D03*
X618284D03*
X616560Y1521453D03*
X611836D03*
X607111D03*
X607441Y1514243D03*
X612166D03*
X616890D03*
X617111Y1528853D03*
X612387D03*
X607662D03*
X607161Y1536063D03*
X616610D03*
X613560Y1542641D03*
X618284D03*
X608836D03*
X618979Y1592380D03*
X614719D03*
X606919D03*
X608679Y1602380D03*
X612959D03*
X618979Y1624292D03*
X608679Y1614292D03*
X606919Y1624292D03*
X614719D03*
X612959Y1614292D03*
X611613Y1684454D03*
Y1679920D03*
Y1675383D03*
Y1698627D03*
Y1694093D03*
Y1689556D03*
Y1712800D03*
Y1708266D03*
Y1703729D03*
Y1726974D03*
Y1722440D03*
Y1717903D03*
X623009Y1507295D03*
X627733D03*
X632458D03*
X630733Y1521453D03*
X626009D03*
X621284D03*
X621615Y1514243D03*
X626339D03*
X631063D03*
X631284Y1528853D03*
X626560D03*
X621835D03*
X630783Y1536063D03*
X632458Y1542641D03*
X627733D03*
X623009D03*
X631039Y1592380D03*
X626779D03*
X632799Y1602286D03*
X620739Y1602380D03*
X625019D03*
X631039Y1624292D03*
X632799Y1614292D03*
X626779Y1624292D03*
X620739Y1614292D03*
X625019D03*
X619487Y1679320D03*
Y1683857D03*
Y1688391D03*
Y1693493D03*
Y1698030D03*
Y1716737D03*
Y1702564D03*
Y1707666D03*
Y1712203D03*
Y1721840D03*
Y1726377D03*
Y1730911D03*
X637182Y1507295D03*
X641906D03*
X646631D03*
X644907Y1521453D03*
X640182D03*
X635458D03*
X635788Y1514243D03*
X640512D03*
X645458Y1528853D03*
X640733D03*
X636009D03*
X640232Y1536063D03*
X646631Y1542641D03*
X641906D03*
X637182D03*
X638839Y1592380D03*
X644869Y1602380D03*
X637079D03*
X644869Y1614292D03*
X638839Y1624292D03*
X637079Y1614292D03*
X651355Y1507295D03*
X654376Y1521453D03*
X649631D03*
X649961Y1514243D03*
X650182Y1528853D03*
X649681Y1536063D03*
X655012D03*
X651355Y1542641D03*
X1185452Y1556810D03*
Y1561725D03*
X1190820Y1540512D03*
X1194733Y1547243D03*
X1196127Y1540295D03*
X1199457Y1547243D03*
X1193561Y1552195D03*
X1199127Y1554453D03*
X1194403D03*
X1199678Y1561853D03*
X1194954D03*
X1199177Y1569063D03*
X1196127Y1575641D03*
X1194452Y1569063D03*
X1190924Y1575425D03*
X1193839Y1625380D03*
X1199879Y1635380D03*
Y1647292D03*
X1193839Y1657292D03*
X1200852Y1540295D03*
X1204182Y1547243D03*
X1205576Y1540295D03*
X1208906Y1547243D03*
X1210300Y1540295D03*
X1213631Y1547243D03*
X1215025Y1540295D03*
X1213300Y1554453D03*
X1208576D03*
X1203852D03*
X1213851Y1561853D03*
X1209127D03*
X1204403D03*
X1210300Y1575641D03*
X1208626Y1569063D03*
X1203902D03*
X1200852Y1575641D03*
X1205576D03*
X1215025D03*
X1205899Y1625380D03*
X1201639D03*
X1213699D03*
X1207659Y1635380D03*
X1211939D03*
X1207659Y1647292D03*
X1211939D03*
X1201639Y1657292D03*
X1205899D03*
X1213699D03*
X1218355Y1547243D03*
X1219749Y1540295D03*
X1223079Y1547243D03*
X1227804D03*
X1229198Y1540295D03*
X1224474D03*
X1227474Y1554453D03*
X1222749D03*
X1218025D03*
X1228025Y1561853D03*
X1223300D03*
X1218576D03*
X1222799Y1569063D03*
X1219749Y1575641D03*
X1224474D03*
X1229198D03*
X1217959Y1625380D03*
X1225759D03*
X1230019D03*
X1223999Y1635380D03*
X1219719D03*
X1223999Y1647292D03*
X1219719D03*
X1217959Y1657292D03*
X1230019D03*
X1225759D03*
X1232528Y1547243D03*
X1233922Y1540295D03*
X1237253Y1547243D03*
X1241977D03*
X1243371Y1540295D03*
X1238647D03*
X1241647Y1554453D03*
X1236922D03*
X1232198D03*
X1242198Y1561853D03*
X1237473D03*
X1232749D03*
X1238647Y1575641D03*
X1232248Y1569063D03*
X1233922Y1575641D03*
X1243371D03*
X1237819Y1625380D03*
X1242079D03*
X1231779Y1635380D03*
X1236059D03*
X1243839D03*
X1236059Y1647292D03*
X1231779D03*
X1243839D03*
X1237819Y1657292D03*
X1242079D03*
X1241140Y1684454D03*
Y1679920D03*
Y1675383D03*
Y1698627D03*
Y1694093D03*
Y1689556D03*
Y1712800D03*
Y1708266D03*
Y1703729D03*
Y1726974D03*
Y1722440D03*
Y1717903D03*
X1246701Y1547243D03*
X1248096Y1540295D03*
X1251426Y1547243D03*
X1252820Y1540295D03*
X1256150Y1547243D03*
X1257544Y1540295D03*
X1255820Y1554453D03*
X1251096D03*
X1246371D03*
X1256371Y1561853D03*
X1251647D03*
X1246922D03*
X1257544Y1575641D03*
X1255870Y1569063D03*
X1246421D03*
X1248096Y1575641D03*
X1252820D03*
X1249879Y1625380D03*
X1254139D03*
X1248119Y1635380D03*
X1255899D03*
X1260179D03*
X1248119Y1647292D03*
X1255899D03*
X1260179D03*
X1254139Y1657292D03*
X1249879D03*
X1249014Y1679320D03*
Y1683857D03*
X1256888Y1684454D03*
Y1679920D03*
Y1675383D03*
X1249014Y1688391D03*
Y1693493D03*
Y1698030D03*
X1256888Y1698627D03*
Y1694093D03*
Y1689556D03*
Y1703729D03*
X1249014Y1716737D03*
Y1702564D03*
Y1707666D03*
Y1712203D03*
X1256888Y1712800D03*
Y1708266D03*
X1249014Y1721840D03*
Y1726377D03*
Y1730911D03*
X1256888Y1726974D03*
Y1722440D03*
Y1717903D03*
X1262269Y1540295D03*
X1265599Y1547243D03*
X1266993Y1540295D03*
X1270014Y1554453D03*
X1265269D03*
X1260545D03*
X1265820Y1561853D03*
X1261096D03*
X1270650Y1569063D03*
X1266993Y1575641D03*
X1265319Y1569063D03*
X1262269Y1575641D03*
X1266199Y1625380D03*
X1261939D03*
X1273999D03*
X1267959Y1635380D03*
X1272239D03*
X1267959Y1647292D03*
X1272239D03*
X1266199Y1657292D03*
X1261939D03*
X1273999D03*
X1264762Y1679320D03*
Y1683857D03*
X1272636Y1684454D03*
Y1679920D03*
Y1675383D03*
X1264762Y1688391D03*
Y1693493D03*
Y1698030D03*
X1272636Y1698627D03*
Y1694093D03*
Y1689556D03*
X1264762Y1716737D03*
Y1702564D03*
Y1707666D03*
Y1712203D03*
X1272636Y1712800D03*
Y1708266D03*
Y1703729D03*
X1264762Y1721840D03*
Y1726377D03*
Y1730911D03*
X1272636Y1726974D03*
Y1722440D03*
Y1717903D03*
X1286028Y1028055D03*
Y1034433D03*
Y1040811D03*
Y1047189D03*
Y1053567D03*
X1287878Y1056756D03*
X1289729Y1059945D03*
X1286028D03*
Y1066323D03*
Y1072701D03*
Y1079079D03*
Y1085457D03*
Y1091835D03*
Y1098213D03*
Y1104591D03*
Y1110969D03*
Y1117347D03*
Y1123725D03*
Y1130102D03*
Y1136480D03*
Y1142858D03*
Y1149236D03*
X1289729Y1155614D03*
X1286028D03*
X1284178Y1158803D03*
X1287878Y1165181D03*
X1278259Y1625380D03*
X1286059D03*
X1280019Y1635380D03*
X1284299D03*
X1280019Y1647292D03*
X1284299D03*
X1278259Y1657292D03*
X1286059D03*
X1280510Y1679320D03*
Y1683857D03*
X1288384Y1684454D03*
Y1679920D03*
Y1675383D03*
X1280510Y1688391D03*
Y1693493D03*
Y1698030D03*
X1288384Y1698627D03*
Y1694093D03*
Y1689556D03*
X1280510Y1716737D03*
Y1702564D03*
Y1707666D03*
Y1712203D03*
X1288384Y1712800D03*
Y1708266D03*
Y1703729D03*
X1280510Y1721840D03*
Y1726377D03*
Y1730911D03*
X1288384Y1726974D03*
Y1722440D03*
Y1717903D03*
X1304532Y1028055D03*
X1293430Y1034433D03*
Y1040811D03*
X1298981Y1044000D03*
Y1037622D03*
X1304532Y1034433D03*
Y1040811D03*
X1298981Y1031244D03*
X1291579D03*
Y1044000D03*
X1304532Y1047189D03*
X1291579Y1050378D03*
X1293430Y1053567D03*
Y1059945D03*
X1304532Y1053567D03*
X1298981Y1050378D03*
X1302681Y1056756D03*
X1298981D03*
X1300831Y1059945D03*
X1304532D03*
X1298981Y1063134D03*
X1291579D03*
Y1069512D03*
X1293430Y1072701D03*
X1304532D03*
Y1066323D03*
X1298981Y1069512D03*
Y1075890D03*
X1293430Y1079079D03*
X1304532D03*
Y1085457D03*
X1298981Y1088646D03*
X1291579Y1082268D03*
X1298981D03*
X1291579Y1088646D03*
X1293430Y1091835D03*
X1304532D03*
X1298981Y1095024D03*
X1293430Y1098213D03*
X1298981Y1101402D03*
X1304532Y1098213D03*
Y1104591D03*
X1291579Y1101402D03*
X1298981Y1107780D03*
X1291579D03*
X1293430Y1110969D03*
X1304532D03*
X1293430Y1117347D03*
X1298981Y1114158D03*
X1304532Y1117347D03*
X1291579Y1120536D03*
X1298981D03*
X1304532Y1123725D03*
X1291579Y1126914D03*
X1298981D03*
X1304532Y1130102D03*
X1298981Y1133292D03*
X1293430Y1130102D03*
X1304532Y1136480D03*
X1298981Y1139669D03*
X1291579D03*
X1293430Y1136480D03*
X1304532Y1142858D03*
X1291579Y1146047D03*
X1293430Y1149236D03*
X1298981Y1146047D03*
X1304532Y1149236D03*
X1293430Y1155614D03*
X1304532D03*
X1298981Y1152425D03*
X1297130Y1155614D03*
X1302681Y1158803D03*
X1298981D03*
X1304532Y1161992D03*
X1297130D03*
X1298119Y1625380D03*
X1290319D03*
X1302379D03*
X1292079Y1635380D03*
X1296359D03*
X1304139D03*
X1296359Y1647292D03*
X1292079D03*
X1304139D03*
X1298119Y1657292D03*
X1290319D03*
X1302379D03*
X1296258Y1679320D03*
Y1683857D03*
Y1688391D03*
Y1693493D03*
Y1698030D03*
Y1716737D03*
Y1702564D03*
Y1707666D03*
Y1712203D03*
Y1721840D03*
Y1726377D03*
Y1730911D03*
X1311933Y1028055D03*
X1306382Y1044000D03*
Y1037622D03*
Y1031244D03*
X1319335Y1034433D03*
X1311933Y1040811D03*
X1319335D03*
X1317485Y1031244D03*
Y1044000D03*
X1311933Y1034433D03*
X1306382Y1050378D03*
Y1056756D03*
X1311933Y1047189D03*
X1313784Y1056756D03*
X1311933Y1059945D03*
X1315634D03*
X1319335D03*
X1317485Y1050378D03*
X1319335Y1053567D03*
X1311933D03*
X1306382Y1063134D03*
Y1069512D03*
X1317485Y1063134D03*
X1319335Y1072701D03*
X1317485Y1069512D03*
X1311933Y1066323D03*
Y1072701D03*
X1306382Y1075890D03*
Y1088646D03*
Y1082268D03*
X1319335Y1079079D03*
X1311933D03*
Y1085457D03*
X1317485Y1088646D03*
Y1082268D03*
X1306382Y1095024D03*
Y1101402D03*
X1319335Y1091835D03*
X1311933D03*
Y1098213D03*
X1319335D03*
X1317485Y1101402D03*
X1311933Y1104591D03*
X1306382Y1107780D03*
Y1114158D03*
X1317485Y1107780D03*
X1319335Y1110969D03*
X1311933D03*
Y1117347D03*
X1319335D03*
X1306382Y1120536D03*
Y1126914D03*
Y1133292D03*
X1317485Y1120536D03*
X1311933Y1123725D03*
X1317485Y1126914D03*
X1319335Y1130102D03*
X1311933Y1130103D03*
X1306382Y1139669D03*
Y1146047D03*
X1319335Y1136480D03*
X1317485Y1139669D03*
X1311933Y1136480D03*
Y1142858D03*
X1317485Y1146047D03*
X1319335Y1149236D03*
X1311933D03*
X1317485Y1158803D03*
X1313784D03*
X1319335Y1161992D03*
X1311933D03*
X1306382Y1165181D03*
X1313784D03*
X1306382Y1152425D03*
Y1158803D03*
X1319335Y1155614D03*
X1315634D03*
X1311933D03*
X1310083Y1158803D03*
X1318882Y1540514D03*
X1313514Y1556810D03*
Y1561725D03*
X1318986Y1575425D03*
X1310179Y1625380D03*
X1314439D03*
X1308419Y1635380D03*
X1316199D03*
X1308419Y1647292D03*
X1316199D03*
X1310179Y1657292D03*
X1314439D03*
X1315943Y1679320D03*
Y1683857D03*
X1308069Y1684454D03*
Y1679920D03*
Y1675383D03*
X1315943Y1688391D03*
Y1693493D03*
Y1698030D03*
X1308069Y1698627D03*
Y1694093D03*
Y1689556D03*
X1315943Y1716737D03*
Y1702564D03*
Y1707666D03*
Y1712203D03*
X1308069Y1712800D03*
Y1708266D03*
Y1703729D03*
X1315943Y1721840D03*
Y1726377D03*
Y1730911D03*
X1308069Y1726974D03*
Y1722440D03*
Y1717903D03*
X1330437Y1028055D03*
X1324886Y1031244D03*
X1332288D03*
X1324886Y1044000D03*
Y1037622D03*
X1332288Y1044000D03*
X1330437Y1034433D03*
X1332288Y1037622D03*
X1330437Y1040811D03*
Y1047189D03*
X1324886Y1050378D03*
Y1056756D03*
X1332288Y1050378D03*
X1330437Y1053567D03*
X1328587Y1056756D03*
X1332288D03*
X1326737Y1059945D03*
X1330437D03*
X1332288Y1063134D03*
X1324886D03*
Y1069512D03*
X1330437Y1066323D03*
X1332288Y1069512D03*
X1330437Y1072701D03*
X1324886Y1075890D03*
X1332288D03*
X1330437Y1079079D03*
X1324886Y1088646D03*
X1330437Y1085457D03*
X1332288Y1088646D03*
X1324886Y1082268D03*
X1332288D03*
X1330437Y1091835D03*
X1324886Y1095024D03*
X1332288D03*
X1324886Y1101402D03*
X1330437Y1098213D03*
X1332288Y1101402D03*
X1330437Y1104591D03*
X1324886Y1107780D03*
X1332288D03*
X1330437Y1110969D03*
X1324886Y1114158D03*
X1332288D03*
X1330437Y1117347D03*
X1324886Y1120536D03*
X1332288D03*
X1330437Y1123725D03*
X1324886Y1126914D03*
X1332288D03*
X1324886Y1133292D03*
X1332288D03*
X1330439Y1130102D03*
X1324886Y1139669D03*
X1330437Y1136480D03*
X1332288Y1139669D03*
X1330437Y1142858D03*
X1332288Y1146047D03*
X1330437Y1149236D03*
X1324886Y1146047D03*
X1332288Y1165181D03*
X1323036Y1155614D03*
Y1161992D03*
X1332288Y1152425D03*
X1330437Y1155614D03*
X1324886Y1152425D03*
X1332288Y1158803D03*
X1328587D03*
X1324886D03*
X1330437Y1161992D03*
X1324886Y1165181D03*
X1322795Y1547243D03*
X1324189Y1540295D03*
X1327519Y1547243D03*
X1328914Y1540295D03*
X1332244Y1547243D03*
X1333638Y1540295D03*
X1321623Y1552195D03*
X1331914Y1554453D03*
X1327189D03*
X1322465D03*
X1332465Y1561853D03*
X1327740D03*
X1323016D03*
X1333638Y1575641D03*
X1331964Y1569063D03*
X1328914Y1575641D03*
X1327239Y1569063D03*
X1324189Y1575641D03*
X1322514Y1569063D03*
X1326499Y1625380D03*
X1322239D03*
X1334299D03*
X1320479Y1635380D03*
X1328259D03*
X1332539D03*
X1328259Y1647292D03*
X1320479D03*
X1332539D03*
X1322239Y1657292D03*
X1326499D03*
X1334299D03*
X1331691Y1679320D03*
Y1683857D03*
X1323817Y1684454D03*
Y1679920D03*
Y1675383D03*
X1331691Y1688391D03*
Y1693493D03*
Y1698030D03*
X1323817Y1698627D03*
Y1694093D03*
Y1689556D03*
X1331691Y1716737D03*
Y1702564D03*
Y1707666D03*
Y1712203D03*
X1323817Y1712800D03*
Y1708266D03*
Y1703729D03*
X1331691Y1721840D03*
Y1726377D03*
Y1730911D03*
X1323817Y1726974D03*
Y1722440D03*
Y1717903D03*
X1337839Y1028055D03*
Y1040811D03*
Y1034433D03*
X1343390Y1031244D03*
Y1044000D03*
X1345241Y1040811D03*
Y1034433D03*
X1337839Y1047189D03*
Y1053567D03*
Y1059945D03*
X1339689Y1056756D03*
X1343390Y1050378D03*
X1345241Y1053567D03*
X1341540Y1059945D03*
X1345241D03*
X1337839Y1072701D03*
Y1066323D03*
X1343390Y1063134D03*
Y1069512D03*
X1345241Y1072701D03*
X1337839Y1079079D03*
Y1085457D03*
X1345241Y1079079D03*
X1343390Y1088646D03*
Y1082268D03*
X1337839Y1091835D03*
Y1098213D03*
Y1104591D03*
X1345241Y1091835D03*
X1343390Y1101402D03*
X1345241Y1098213D03*
X1337839Y1110969D03*
Y1117347D03*
X1343390Y1107780D03*
X1345241Y1110969D03*
Y1117347D03*
X1337839Y1123725D03*
Y1130102D03*
X1343390Y1120536D03*
Y1126914D03*
X1345241Y1130102D03*
X1337839Y1136480D03*
Y1142858D03*
Y1149236D03*
X1343390Y1139669D03*
X1345241Y1136480D03*
Y1149236D03*
X1343390Y1146047D03*
X1337839Y1155614D03*
X1335989Y1158803D03*
X1337839Y1161992D03*
X1341540Y1155614D03*
X1339689Y1158803D03*
X1348941Y1155614D03*
X1345241D03*
X1339689Y1165181D03*
X1336968Y1547243D03*
X1338362Y1540295D03*
X1341693Y1547243D03*
X1343087Y1540295D03*
X1346417Y1547243D03*
X1347811Y1540295D03*
X1346087Y1554453D03*
X1341362D03*
X1336638D03*
X1346638Y1561853D03*
X1341913D03*
X1337189D03*
X1347811Y1575641D03*
X1343087D03*
X1338362D03*
X1336688Y1569063D03*
X1338559Y1625380D03*
X1346359D03*
X1340319Y1635380D03*
X1344599D03*
X1340319Y1647292D03*
X1344599D03*
X1338559Y1657292D03*
X1346359D03*
X1347439Y1679320D03*
Y1683857D03*
X1339565Y1684454D03*
Y1679920D03*
Y1675383D03*
X1347439Y1688391D03*
Y1693493D03*
Y1698030D03*
X1339565Y1698627D03*
Y1694093D03*
Y1689556D03*
X1347439Y1716737D03*
Y1702564D03*
Y1707666D03*
Y1712203D03*
X1339565Y1712800D03*
Y1708266D03*
Y1703729D03*
X1347439Y1721840D03*
Y1726377D03*
Y1730911D03*
X1339565Y1726974D03*
Y1722440D03*
Y1717903D03*
X1356343Y1028055D03*
X1363745D03*
X1350792Y1031244D03*
Y1044000D03*
Y1037622D03*
X1356343Y1034433D03*
Y1040811D03*
X1363745Y1034433D03*
Y1040811D03*
X1361894Y1044000D03*
Y1037622D03*
Y1031244D03*
X1354493Y1056756D03*
X1350792D03*
Y1050378D03*
X1352642Y1059945D03*
X1356343Y1047189D03*
X1363745D03*
X1356343Y1053567D03*
X1361894Y1050378D03*
X1356343Y1059945D03*
X1363745Y1053567D03*
X1350792Y1063134D03*
Y1069512D03*
X1358193Y1063134D03*
X1356343Y1072701D03*
X1363745Y1066323D03*
X1358193Y1069512D03*
X1360044Y1066323D03*
X1361894Y1069512D03*
Y1063134D03*
X1350792Y1075890D03*
Y1082268D03*
Y1088646D03*
X1358193Y1075890D03*
X1363745Y1079079D03*
X1360044D03*
X1356343Y1085457D03*
X1358193Y1088646D03*
Y1082268D03*
X1361894Y1075890D03*
Y1088646D03*
Y1082268D03*
X1350792Y1095024D03*
Y1101402D03*
X1356343Y1104591D03*
X1363745Y1091835D03*
X1360044D03*
X1358193Y1095024D03*
X1356343Y1098213D03*
X1363745Y1104591D03*
X1360044D03*
X1361894Y1095024D03*
X1350792Y1107780D03*
Y1114158D03*
X1358193Y1107780D03*
X1360044Y1110969D03*
X1363745D03*
X1356343Y1117347D03*
X1358193Y1114158D03*
X1350792Y1120536D03*
Y1126914D03*
Y1133292D03*
X1358193Y1126914D03*
X1363745Y1123725D03*
X1360044D03*
X1358193Y1120536D03*
X1356343Y1130102D03*
X1358193Y1133292D03*
X1350792Y1139669D03*
Y1146047D03*
X1358193Y1139669D03*
X1363745Y1136480D03*
X1360044D03*
X1356343Y1142858D03*
X1363745Y1149236D03*
X1360044D03*
X1358193Y1146047D03*
X1354493Y1158803D03*
X1350792Y1152425D03*
Y1158803D03*
X1352642Y1161992D03*
X1356343Y1155614D03*
X1363745D03*
X1360044D03*
X1363745Y1161992D03*
X1351141Y1547243D03*
X1352536Y1540295D03*
X1355866Y1547243D03*
X1357260Y1540295D03*
X1360590Y1547243D03*
X1361984Y1540295D03*
X1360260Y1554453D03*
X1355536D03*
X1350811D03*
X1360811Y1561853D03*
X1356087D03*
X1351362D03*
X1361984Y1575641D03*
X1360310Y1569063D03*
X1352536Y1575641D03*
X1350861Y1569063D03*
X1357260Y1575641D03*
X1350619Y1625380D03*
X1358419D03*
X1362679D03*
X1352379Y1635380D03*
X1356659D03*
X1364439D03*
X1356659Y1647292D03*
X1352379D03*
X1364439D03*
X1358419Y1657292D03*
X1350619D03*
X1362679D03*
X1363187Y1679320D03*
Y1683857D03*
X1355313Y1684454D03*
Y1679920D03*
Y1675383D03*
Y1694093D03*
Y1689556D03*
X1363187Y1688391D03*
Y1693493D03*
Y1698030D03*
X1355313Y1698627D03*
X1363187Y1716737D03*
Y1702564D03*
Y1707666D03*
Y1712203D03*
X1355313Y1712800D03*
Y1708266D03*
Y1703729D03*
X1363187Y1726377D03*
Y1730911D03*
X1355313Y1726974D03*
Y1722440D03*
Y1717903D03*
X1363187Y1721840D03*
X1371146Y1028055D03*
X1374847D03*
X1369296Y1044000D03*
Y1037622D03*
Y1031244D03*
X1371146Y1034433D03*
X1376697Y1037622D03*
X1378548Y1040811D03*
X1371146D03*
X1374847Y1034433D03*
X1376697Y1031244D03*
Y1044000D03*
X1378548Y1053567D03*
X1376697Y1050378D03*
X1367445Y1059945D03*
X1369296Y1056756D03*
Y1050378D03*
X1371146Y1047189D03*
X1378548D03*
X1376697Y1056756D03*
X1371146Y1053567D03*
X1378548Y1059945D03*
X1369296Y1063134D03*
Y1069512D03*
X1367445Y1066323D03*
Y1072701D03*
X1371146Y1066323D03*
X1378548D03*
X1374847D03*
X1378548Y1072701D03*
X1372997Y1069512D03*
Y1063134D03*
X1365595Y1069512D03*
Y1063134D03*
X1376697Y1069512D03*
Y1063134D03*
X1369296Y1075890D03*
X1367445Y1079079D03*
X1369296Y1088646D03*
X1367445Y1085457D03*
X1369296Y1082268D03*
X1371146Y1079079D03*
X1378548D03*
X1374847D03*
X1378548Y1085457D03*
X1372997Y1075890D03*
X1365595D03*
X1376697D03*
X1372997Y1088646D03*
Y1082268D03*
X1365595Y1088646D03*
Y1082268D03*
X1376697Y1088646D03*
Y1082268D03*
X1367445Y1091835D03*
X1369296Y1095024D03*
X1367445Y1104591D03*
Y1098213D03*
X1371146Y1091835D03*
X1378548D03*
X1374847D03*
X1371146Y1104591D03*
X1374847D03*
X1378548Y1098213D03*
Y1104591D03*
X1372997Y1095024D03*
X1365595D03*
X1376697D03*
X1369296Y1107780D03*
X1367445Y1110969D03*
X1369296Y1114158D03*
X1367445Y1117347D03*
X1371146Y1110969D03*
X1378548D03*
X1374847D03*
X1378548Y1117347D03*
X1367445Y1130103D03*
X1369296Y1126914D03*
Y1120536D03*
X1367445Y1123725D03*
X1369296Y1133292D03*
X1374847Y1123725D03*
X1371146D03*
X1378548D03*
Y1130102D03*
X1369296Y1139669D03*
X1367445Y1136480D03*
Y1142858D03*
X1369296Y1146047D03*
X1374847Y1136480D03*
X1371146D03*
X1378548D03*
Y1142858D03*
X1371146Y1149236D03*
X1374847D03*
X1367445Y1155614D03*
X1365595Y1158803D03*
X1371146Y1155614D03*
X1378548D03*
X1374847D03*
X1376697Y1158803D03*
Y1165181D03*
X1374847Y1161992D03*
X1365315Y1547243D03*
X1366709Y1540295D03*
X1370039Y1547243D03*
X1371433Y1540295D03*
X1374763Y1547243D03*
X1376158Y1540295D03*
X1379488Y1547243D03*
X1379158Y1554453D03*
X1374433D03*
X1369709D03*
X1364984D03*
X1374984Y1561853D03*
X1370260D03*
X1365535D03*
X1371433Y1575641D03*
X1366709D03*
X1376158D03*
X1374483Y1569063D03*
X1370479Y1625380D03*
X1374740D03*
X1368719Y1635380D03*
X1376499Y1635286D03*
X1368719Y1647292D03*
X1376499D03*
X1370479Y1657292D03*
X1374739D03*
X1385937Y1028063D03*
Y1034441D03*
X1393339Y1040819D03*
X1385937D03*
X1385949Y1047189D03*
Y1053567D03*
X1384099Y1056756D03*
Y1050378D03*
X1393351Y1047189D03*
Y1053567D03*
X1389650Y1059945D03*
X1391500Y1056756D03*
Y1050378D03*
X1389650Y1066323D03*
X1391500Y1069512D03*
X1389650Y1072701D03*
X1380398Y1063134D03*
X1385949Y1066323D03*
X1382249D03*
X1380398Y1069512D03*
X1391500Y1063134D03*
X1393351Y1066323D03*
X1384099Y1069512D03*
Y1063134D03*
X1387800Y1069512D03*
Y1063134D03*
X1380398Y1075890D03*
X1385949Y1079079D03*
X1382249D03*
X1380398Y1088646D03*
Y1082268D03*
X1391500Y1075890D03*
X1393351Y1079079D03*
X1389650D03*
X1391500Y1088646D03*
X1389650Y1085457D03*
X1391500Y1082268D03*
X1384099Y1075890D03*
X1387800D03*
X1384099Y1088646D03*
Y1082268D03*
X1387800Y1088646D03*
Y1082268D03*
X1385949Y1091835D03*
X1382249D03*
X1380398Y1095024D03*
X1393351Y1091835D03*
X1389650D03*
X1391500Y1095024D03*
Y1101402D03*
X1389650Y1098213D03*
X1393351Y1104591D03*
X1389650D03*
X1384099Y1095024D03*
X1387800D03*
X1385949Y1110969D03*
X1382249D03*
X1380398Y1107780D03*
Y1114158D03*
X1393351Y1110969D03*
X1389650D03*
X1391500Y1107780D03*
X1389650Y1117347D03*
X1391500Y1114158D03*
X1385949Y1123725D03*
X1382249D03*
X1380398Y1120536D03*
Y1126914D03*
Y1133292D03*
X1393351Y1123725D03*
X1389650D03*
X1391500Y1120536D03*
Y1126914D03*
Y1133292D03*
X1389650Y1130102D03*
X1380398Y1139669D03*
X1385949Y1136480D03*
X1382249D03*
X1385949Y1149236D03*
X1382249D03*
X1380398Y1146047D03*
X1391500Y1139669D03*
X1393351Y1136480D03*
X1389650D03*
Y1142858D03*
X1393351Y1149236D03*
X1391500Y1146047D03*
X1385949Y1155614D03*
X1382249D03*
X1385949Y1161992D03*
X1387800Y1158803D03*
X1393351Y1155614D03*
X1389650D03*
X1380882Y1540295D03*
X1384212Y1547243D03*
X1385606Y1540295D03*
X1390331D03*
X1393661Y1547243D03*
X1393331Y1554453D03*
X1388607D03*
X1383882D03*
X1393882Y1561853D03*
X1389158D03*
X1384433D03*
X1379709D03*
X1385606Y1575641D03*
X1383932Y1569063D03*
X1380882Y1575641D03*
X1390331D03*
X1393381Y1569063D03*
X1382539Y1625380D03*
X1388569Y1635380D03*
X1380779D03*
Y1647292D03*
X1388569D03*
X1382539Y1657292D03*
X1400740Y1040819D03*
X1400752Y1047189D03*
X1398902Y1056756D03*
X1400752Y1053567D03*
Y1059945D03*
X1398902Y1050378D03*
X1408154Y1047189D03*
Y1053567D03*
X1406304Y1056756D03*
Y1050378D03*
X1404453Y1059945D03*
X1408154D03*
X1402603Y1063134D03*
Y1069512D03*
X1397052Y1066323D03*
X1400752D03*
Y1072701D03*
X1406304Y1063134D03*
X1395201D03*
X1404453Y1072701D03*
Y1066323D03*
X1395201Y1069512D03*
X1398902Y1063134D03*
X1408154Y1072701D03*
Y1066323D03*
X1398902Y1069512D03*
X1402603Y1075890D03*
X1400752Y1079079D03*
X1397052D03*
X1402603Y1088646D03*
Y1082268D03*
X1400752Y1085457D03*
X1406304Y1075890D03*
Y1088646D03*
X1395201Y1075890D03*
X1404453Y1079079D03*
X1398902Y1075890D03*
X1408154Y1079079D03*
X1395201Y1082268D03*
X1404453Y1085457D03*
X1395201Y1088646D03*
X1398902Y1082268D03*
X1408154Y1085457D03*
X1398902Y1088646D03*
X1402603Y1095024D03*
X1400752Y1091835D03*
X1397052D03*
X1402603Y1101402D03*
X1400752Y1104591D03*
X1397052D03*
X1400752Y1098213D03*
X1406304Y1101402D03*
X1395201Y1095024D03*
Y1101402D03*
X1404453Y1098213D03*
Y1091835D03*
X1398902Y1095024D03*
Y1101402D03*
X1408154Y1098213D03*
Y1091835D03*
X1402603Y1107780D03*
X1397052Y1110969D03*
X1400752D03*
X1402603Y1114158D03*
X1400752Y1117347D03*
X1406304Y1107780D03*
X1402603Y1120536D03*
Y1126914D03*
X1397052Y1123725D03*
X1400752D03*
X1402603Y1133292D03*
X1406304Y1120536D03*
Y1133292D03*
X1400752Y1130103D03*
X1402603Y1139669D03*
X1397052Y1136480D03*
X1400752D03*
Y1142858D03*
X1402603Y1146047D03*
X1397052Y1149236D03*
X1408154D03*
X1404453D03*
X1398902Y1158803D03*
X1397052Y1155614D03*
X1400752D03*
X1397052Y1161992D03*
X1398902Y1165181D03*
X1406304Y1158803D03*
X1395055Y1540295D03*
X1398076Y1554453D03*
X1395055Y1575641D03*
X1398712Y1569063D03*
X1411855Y1059945D03*
X1422932Y1047189D03*
Y1059945D03*
Y1053567D03*
X1410004Y1063134D03*
X1411855Y1066323D03*
Y1072701D03*
X1422932D03*
Y1066323D03*
X1410004Y1075890D03*
X1411855Y1079079D03*
Y1085457D03*
X1410004Y1088646D03*
X1422932Y1079079D03*
Y1085457D03*
Y1091835D03*
Y1104591D03*
Y1098213D03*
X1411855Y1091835D03*
Y1104591D03*
Y1098213D03*
X1410004Y1101402D03*
Y1107780D03*
X1411855Y1110969D03*
Y1117347D03*
X1422932Y1110969D03*
Y1117347D03*
X1411855Y1123725D03*
X1410004Y1120536D03*
X1411855Y1130102D03*
X1410004Y1133292D03*
X1422932Y1123725D03*
Y1130102D03*
X1411855Y1136480D03*
Y1142858D03*
Y1149236D03*
X1422932Y1136480D03*
Y1142858D03*
Y1149236D03*
X1411855Y1155614D03*
Y1161992D03*
X1422932Y1155614D03*
Y1161992D03*
X1430346Y1040819D03*
X1437748D03*
X1430334Y1047189D03*
X1424783Y1056756D03*
X1434035Y1059945D03*
X1432184Y1056756D03*
X1430334Y1053567D03*
X1424783Y1050378D03*
X1432184D03*
X1437735Y1047189D03*
Y1053567D03*
X1430334Y1059945D03*
X1426633D03*
X1432184Y1063134D03*
X1428483D03*
X1424783D03*
X1432184Y1069512D03*
X1434035Y1072701D03*
Y1066323D03*
X1437735D03*
X1430334D03*
Y1072701D03*
X1426633Y1066323D03*
Y1072701D03*
X1435885Y1063134D03*
Y1069512D03*
X1437735Y1079079D03*
X1428483Y1075890D03*
X1432184D03*
X1424783D03*
X1434035Y1079079D03*
X1424783Y1088646D03*
X1432184Y1082268D03*
X1428483Y1088646D03*
X1432184D03*
X1434035Y1085457D03*
X1430334Y1079079D03*
X1426633D03*
X1435885Y1075890D03*
Y1088646D03*
X1430334Y1085457D03*
X1426633D03*
X1435885Y1082268D03*
X1432184Y1095024D03*
X1434035Y1091835D03*
Y1104591D03*
X1428483Y1101402D03*
X1432184D03*
X1434035Y1098213D03*
X1424783Y1101402D03*
X1437735Y1091835D03*
Y1104591D03*
X1435885Y1101402D03*
Y1095024D03*
X1430334Y1091835D03*
Y1098213D03*
X1426633Y1091835D03*
Y1098213D03*
X1428483Y1107780D03*
X1432184D03*
X1424783D03*
X1434035Y1110969D03*
Y1117347D03*
X1432184Y1114158D03*
X1437735Y1110969D03*
X1432184Y1126914D03*
Y1120536D03*
X1428483D03*
X1424783D03*
X1434035Y1123725D03*
X1424783Y1133292D03*
X1428483D03*
X1432184D03*
X1437735Y1123725D03*
X1434035Y1130103D03*
X1432184Y1139669D03*
X1434035Y1136480D03*
Y1142858D03*
X1430334Y1149236D03*
X1432184Y1146047D03*
X1426633Y1149236D03*
X1437735Y1136480D03*
Y1149236D03*
X1430333Y1155614D03*
X1435885Y1158803D03*
Y1152425D03*
X1452542Y1040819D03*
X1445149D03*
X1445137Y1047189D03*
X1446987Y1056756D03*
X1445137Y1059945D03*
X1439586Y1056756D03*
X1445137Y1053567D03*
X1439586Y1050378D03*
X1446987D03*
X1452539Y1047189D03*
Y1053567D03*
X1443287Y1063134D03*
X1445137Y1072701D03*
X1443287Y1069512D03*
X1448838Y1066323D03*
X1445137D03*
X1441436D03*
X1452539D03*
X1439586Y1063134D03*
Y1069512D03*
X1450688Y1063134D03*
Y1069512D03*
X1446987Y1063134D03*
Y1069512D03*
X1445137Y1079079D03*
X1448838D03*
X1441436D03*
X1443287Y1075890D03*
Y1088646D03*
X1445137Y1085457D03*
X1443287Y1082268D03*
X1452539Y1079079D03*
X1439586Y1075890D03*
X1450688D03*
X1446987D03*
X1439586Y1088646D03*
X1450688Y1082268D03*
X1446987D03*
X1439586D03*
X1450688Y1088646D03*
X1446987D03*
X1441436Y1091835D03*
X1448838D03*
X1445137D03*
X1443287Y1095024D03*
X1445137Y1104591D03*
X1443287Y1101402D03*
X1445137Y1098213D03*
X1441436Y1104591D03*
X1452539Y1091835D03*
X1439586Y1101402D03*
Y1095024D03*
X1450688D03*
X1446987D03*
X1441436Y1110969D03*
X1448838D03*
X1445137D03*
X1443287Y1107780D03*
X1445137Y1117347D03*
X1443287Y1114158D03*
X1452539Y1110969D03*
X1445137Y1123725D03*
X1448838D03*
X1443287Y1120536D03*
X1441436Y1123725D03*
X1443287Y1126914D03*
Y1133292D03*
X1445137Y1130102D03*
X1452539Y1123725D03*
X1448838Y1149236D03*
X1443287Y1146047D03*
X1441436Y1149236D03*
X1452539Y1136480D03*
Y1149236D03*
X1445137Y1142858D03*
X1443287Y1139669D03*
X1445137Y1136480D03*
X1448838D03*
X1441436D03*
X1446987Y1158803D03*
X1450688Y1152425D03*
X1441436Y1155614D03*
X1449626Y1556810D03*
Y1561725D03*
X1463641Y1028055D03*
X1456239D03*
X1459940Y1040811D03*
X1458090Y1031244D03*
X1463641Y1034433D03*
X1456239D03*
X1465491Y1031244D03*
X1454389Y1037622D03*
X1467342Y1040811D03*
X1454389Y1044000D03*
X1461791Y1037622D03*
Y1044000D03*
X1459940Y1047189D03*
X1456239Y1059945D03*
X1459940Y1053567D03*
X1454389Y1056756D03*
X1461791D03*
X1454389Y1050378D03*
X1461791D03*
X1467342Y1047189D03*
Y1059945D03*
Y1053567D03*
X1465491Y1063134D03*
X1454389D03*
X1456239Y1072701D03*
X1459940Y1066323D03*
X1463641D03*
X1465491Y1069512D03*
X1454389D03*
X1456239Y1066323D03*
X1467342Y1072701D03*
Y1066323D03*
X1461791Y1063134D03*
Y1069512D03*
X1458090Y1063134D03*
Y1069512D03*
X1459940Y1079079D03*
X1463641D03*
X1456239D03*
X1465491Y1075890D03*
X1454389D03*
X1465491Y1088646D03*
X1454389D03*
X1456239Y1085457D03*
X1465491Y1082268D03*
X1454389D03*
X1467342Y1079079D03*
Y1085457D03*
X1461791Y1075890D03*
X1458090D03*
X1461791Y1082268D03*
Y1088646D03*
X1458090Y1082268D03*
Y1088646D03*
X1456239Y1098213D03*
X1467342Y1091835D03*
Y1104591D03*
Y1098213D03*
X1463641Y1091835D03*
X1459940D03*
X1456239D03*
X1465491Y1095024D03*
X1454389D03*
X1459940Y1104591D03*
X1463641D03*
X1456239D03*
X1461791Y1095024D03*
X1458090D03*
X1465491Y1107780D03*
X1454389D03*
X1463641Y1110969D03*
X1459940D03*
X1456239D03*
Y1117347D03*
X1454389Y1114158D03*
X1465491D03*
X1467342Y1110969D03*
Y1117347D03*
X1454389Y1120536D03*
X1465491Y1126914D03*
X1454389D03*
X1459940Y1123725D03*
X1463641D03*
X1465491Y1120536D03*
X1456239Y1123725D03*
X1454389Y1133292D03*
X1456239Y1130102D03*
X1465491Y1133292D03*
X1467342Y1123725D03*
Y1130102D03*
X1456239Y1142858D03*
X1465491Y1139669D03*
X1459940Y1136480D03*
X1463641D03*
X1454389Y1139669D03*
X1456239Y1136480D03*
X1465491Y1146047D03*
X1459940Y1149236D03*
X1463641D03*
X1454389Y1146047D03*
X1467342Y1136480D03*
Y1142858D03*
X1463641Y1155614D03*
X1461791Y1152425D03*
X1458090Y1158803D03*
X1454994Y1540512D03*
X1458907Y1547243D03*
X1460301Y1540295D03*
X1463631Y1547243D03*
X1465026Y1540295D03*
X1468356Y1547243D03*
X1457735Y1552195D03*
X1468026Y1554453D03*
X1463301D03*
X1458577D03*
X1468577Y1561853D03*
X1463852D03*
X1459128D03*
X1455098Y1575425D03*
X1468076Y1569063D03*
X1463351D03*
X1460301Y1575641D03*
X1458626Y1569063D03*
X1465026Y1575641D03*
X1458013Y1625380D03*
X1465813D03*
X1464053Y1635380D03*
Y1647292D03*
X1465813Y1657292D03*
X1458013D03*
X1478444Y1028055D03*
X1471043D03*
X1472893Y1031244D03*
X1469192Y1037622D03*
Y1044000D03*
X1478444Y1034433D03*
X1476594Y1037622D03*
X1474743Y1040811D03*
X1476594Y1044000D03*
X1471043Y1034433D03*
X1474743Y1047189D03*
X1480295Y1056756D03*
X1482145Y1059945D03*
X1469192Y1050378D03*
X1476594D03*
Y1056756D03*
X1474743Y1053567D03*
X1478444Y1059945D03*
X1469192Y1056756D03*
X1476594Y1063134D03*
X1478444Y1072701D03*
X1476594Y1069512D03*
X1474743Y1066323D03*
X1471043D03*
X1472893Y1063134D03*
Y1069512D03*
X1469192Y1063134D03*
Y1069512D03*
X1476594Y1075890D03*
X1474743Y1079079D03*
X1471043D03*
X1478444Y1085457D03*
X1476594Y1088646D03*
Y1082268D03*
X1472893Y1075890D03*
X1469192D03*
X1472893Y1082268D03*
Y1088646D03*
X1469192Y1082268D03*
Y1088646D03*
X1474743Y1091835D03*
X1471043D03*
X1476594Y1095024D03*
X1478444Y1098213D03*
Y1104591D03*
X1474743D03*
X1471043D03*
X1472893Y1101402D03*
Y1095024D03*
X1469192D03*
X1476594Y1107780D03*
X1474743Y1110969D03*
X1471043D03*
X1476594Y1114158D03*
X1478444Y1117347D03*
X1476594Y1126914D03*
Y1120536D03*
X1474743Y1123725D03*
X1471043D03*
X1478444Y1130102D03*
X1476594Y1133292D03*
Y1139669D03*
X1474743Y1136480D03*
X1471043D03*
X1478444Y1142858D03*
X1476594Y1146047D03*
X1474743Y1149236D03*
X1471043D03*
X1474743Y1155614D03*
X1478444D03*
X1472893Y1152425D03*
X1480295Y1158803D03*
X1469192D03*
X1469750Y1540295D03*
X1473080Y1547243D03*
X1474474Y1540295D03*
X1477805Y1547243D03*
X1479199Y1540295D03*
X1482529Y1547243D03*
X1483923Y1540295D03*
X1482199Y1554453D03*
X1477474D03*
X1472750D03*
X1482750Y1561853D03*
X1478025D03*
X1473301D03*
X1469750Y1575641D03*
X1483923D03*
X1474474D03*
X1472800Y1569063D03*
X1479199Y1575641D03*
X1470073Y1625380D03*
X1482133D03*
X1477873D03*
X1471833Y1635380D03*
X1483893D03*
X1476113D03*
X1471833Y1647292D03*
X1483893D03*
X1476113D03*
X1470073Y1657292D03*
X1477873D03*
X1482133D03*
X1489547Y1028055D03*
X1496948D03*
X1483995Y1031244D03*
Y1037622D03*
Y1044000D03*
X1491397Y1031244D03*
X1489547Y1040811D03*
Y1034433D03*
X1491397Y1044000D03*
X1496948Y1034433D03*
Y1040811D03*
Y1047189D03*
X1483995Y1050378D03*
Y1056756D03*
X1489547Y1053567D03*
X1495098Y1056756D03*
X1491397Y1050378D03*
X1489547Y1059945D03*
X1493247D03*
X1496948Y1053567D03*
Y1059945D03*
X1483995Y1063134D03*
X1491397D03*
X1483995Y1069512D03*
X1489547Y1072701D03*
X1491397Y1069512D03*
X1496948Y1072701D03*
Y1066323D03*
X1483995Y1075890D03*
X1489547Y1079079D03*
X1496948D03*
X1483995Y1088646D03*
X1491397D03*
X1496948Y1085457D03*
X1483995Y1082268D03*
X1491397D03*
X1489547Y1091835D03*
X1496948D03*
X1483995Y1095024D03*
Y1101402D03*
X1489547Y1098213D03*
X1491397Y1101402D03*
X1496948Y1098213D03*
Y1104591D03*
X1489547Y1110969D03*
X1496948D03*
X1483995Y1107780D03*
X1491397D03*
X1483995Y1114158D03*
X1489547Y1117347D03*
X1496948D03*
X1483995Y1120536D03*
X1491397D03*
X1496948Y1123725D03*
X1483995Y1126914D03*
X1491397D03*
X1483995Y1133292D03*
X1496948Y1130102D03*
X1489547Y1130103D03*
X1483995Y1139669D03*
X1489547Y1136480D03*
X1491397Y1139669D03*
X1496948Y1136480D03*
Y1142858D03*
X1483995Y1146047D03*
X1489547Y1149236D03*
X1491397Y1146047D03*
X1496948Y1149236D03*
X1487696Y1165181D03*
X1498799Y1158803D03*
X1483995Y1152425D03*
X1485846Y1155614D03*
X1489547D03*
X1493247D03*
X1496948D03*
X1483995Y1158803D03*
X1491397D03*
X1493247Y1161992D03*
X1495111Y1165289D03*
X1491410D03*
X1498812D03*
X1488648Y1540295D03*
X1487253Y1547243D03*
X1491978D03*
X1493372Y1540295D03*
X1496702Y1547243D03*
X1498096Y1540295D03*
X1496372Y1554453D03*
X1491648D03*
X1486923D03*
X1496923Y1561853D03*
X1492199D03*
X1487474D03*
X1488648Y1575641D03*
X1493372D03*
X1498096D03*
X1496422Y1569063D03*
X1486973D03*
X1489933Y1625380D03*
X1494193D03*
X1495953Y1635380D03*
X1488173D03*
X1495953Y1647292D03*
X1488173D03*
X1494193Y1657292D03*
X1489933D03*
X1504350Y1028055D03*
X1502499Y1031244D03*
X1509901D03*
X1504350Y1040811D03*
X1502499Y1037622D03*
X1504350Y1034433D03*
X1502499Y1044000D03*
X1509901Y1037622D03*
Y1044000D03*
X1504350Y1047189D03*
Y1053567D03*
X1502499Y1050378D03*
X1509901Y1056756D03*
Y1050378D03*
X1504350Y1059945D03*
X1508050D03*
X1506200Y1056756D03*
X1502499D03*
Y1063134D03*
X1509901D03*
X1502499Y1069512D03*
X1504350Y1072701D03*
Y1066323D03*
X1509901Y1069512D03*
X1502499Y1075890D03*
X1509901D03*
X1504350Y1079079D03*
Y1085457D03*
X1502499Y1088646D03*
X1509901D03*
X1502499Y1082268D03*
X1509901D03*
X1504350Y1091835D03*
X1502499Y1095024D03*
X1509901D03*
X1504350Y1098213D03*
X1502499Y1101402D03*
X1509901D03*
X1504350Y1104591D03*
X1502499Y1107780D03*
X1509901D03*
X1504350Y1110969D03*
X1509901Y1114158D03*
X1504350Y1117347D03*
X1502499Y1114158D03*
Y1120536D03*
X1504350Y1123725D03*
X1509901Y1120536D03*
X1502499Y1126914D03*
X1509901D03*
Y1133292D03*
X1502499D03*
X1504350Y1130103D03*
X1502499Y1139669D03*
X1504350Y1136480D03*
X1509901Y1139669D03*
X1504350Y1142858D03*
Y1149236D03*
X1502499Y1146047D03*
X1509901D03*
X1504350Y1155614D03*
X1502499Y1152425D03*
X1509901D03*
X1511751Y1155614D03*
X1502499Y1158803D03*
X1506200D03*
X1509901D03*
X1509914Y1165289D03*
X1506213D03*
X1502821Y1540295D03*
X1501427Y1547243D03*
X1506151D03*
X1507545Y1540295D03*
X1510875Y1547243D03*
X1512270Y1540295D03*
X1510545Y1554453D03*
X1505821D03*
X1501096D03*
X1511096Y1561853D03*
X1506372D03*
X1501647D03*
X1507545Y1575641D03*
X1512270D03*
X1510595Y1569063D03*
X1502821Y1575641D03*
X1501993Y1625380D03*
X1506253D03*
X1508013Y1635380D03*
X1500233D03*
X1512293D03*
X1508013Y1647292D03*
X1500233D03*
X1512293D03*
X1501993Y1657292D03*
X1506253D03*
X1513187Y1679320D03*
Y1683857D03*
X1505313Y1684454D03*
Y1679920D03*
Y1675383D03*
X1513187Y1688391D03*
Y1693493D03*
Y1698030D03*
X1505313Y1698627D03*
Y1694093D03*
Y1689556D03*
X1513187Y1716737D03*
Y1702564D03*
Y1707666D03*
Y1712203D03*
X1505313Y1712800D03*
Y1708266D03*
Y1703729D03*
X1513187Y1721840D03*
Y1726377D03*
Y1730911D03*
X1505313Y1726974D03*
Y1722440D03*
Y1717903D03*
X1522854Y1028055D03*
X1515452D03*
X1522854Y1034433D03*
Y1040811D03*
X1517302Y1044000D03*
X1528405Y1037622D03*
Y1044000D03*
X1515452Y1040811D03*
Y1034433D03*
X1517302Y1031244D03*
X1528405D03*
X1515452Y1053567D03*
Y1059945D03*
X1522854Y1047189D03*
Y1053567D03*
X1521003Y1056756D03*
X1517302Y1050378D03*
X1522854Y1059945D03*
X1519153D03*
X1528405Y1050378D03*
Y1056756D03*
X1517302Y1063134D03*
X1528405D03*
X1515452Y1072701D03*
X1522854Y1066323D03*
Y1072701D03*
X1517302Y1069512D03*
X1528405D03*
Y1075890D03*
X1515452Y1079079D03*
X1522854D03*
X1517302Y1082268D03*
X1528405D03*
X1522854Y1085457D03*
X1517302Y1088646D03*
X1528405D03*
X1515452Y1091835D03*
X1522854D03*
X1528405Y1095024D03*
X1522854Y1104591D03*
X1528405Y1101402D03*
X1515452Y1098213D03*
X1522854D03*
X1517302Y1101402D03*
Y1107780D03*
X1528405D03*
X1522854Y1110969D03*
X1515452D03*
X1522854Y1117347D03*
X1528405Y1114158D03*
X1515452Y1117347D03*
X1522854Y1123725D03*
X1517302Y1120536D03*
X1528405D03*
X1517302Y1126914D03*
X1528405D03*
Y1133292D03*
X1515452Y1130102D03*
X1522854Y1130103D03*
Y1142858D03*
Y1136480D03*
X1517302Y1139669D03*
X1528405D03*
X1515452Y1136480D03*
X1528405Y1146047D03*
X1515452Y1149236D03*
X1522854D03*
X1517302Y1146047D03*
X1528405Y1152425D03*
X1524704Y1158803D03*
X1528405D03*
X1515452Y1155614D03*
X1519153D03*
X1522854D03*
X1519153Y1161992D03*
X1521718Y1540295D03*
X1515600Y1547243D03*
X1516994Y1540295D03*
X1520324Y1547243D03*
X1526443Y1540295D03*
X1524719Y1554453D03*
X1519994D03*
X1515270D03*
X1525270Y1561853D03*
X1520545D03*
X1515821D03*
X1516994Y1575641D03*
X1526443D03*
X1521718D03*
X1520044Y1569063D03*
X1514053Y1625380D03*
X1518313D03*
X1526113D03*
X1520073Y1635380D03*
X1524353D03*
X1520073Y1647292D03*
X1524353D03*
X1518313Y1657292D03*
X1514053D03*
X1526113D03*
X1521061Y1684454D03*
Y1679920D03*
Y1675383D03*
Y1698627D03*
Y1694093D03*
Y1689556D03*
Y1712800D03*
Y1708266D03*
Y1703729D03*
Y1726974D03*
Y1722440D03*
Y1717903D03*
X1530255Y1028055D03*
X1541358D03*
X1530255Y1034433D03*
Y1040811D03*
X1541357D03*
Y1034433D03*
X1543208Y1031244D03*
Y1044000D03*
X1535806Y1031244D03*
Y1037622D03*
Y1044000D03*
X1530255Y1047189D03*
Y1053567D03*
Y1059945D03*
X1541357Y1053567D03*
Y1059945D03*
X1543208Y1050378D03*
X1532106Y1056756D03*
X1535806D03*
Y1050378D03*
X1533956Y1059945D03*
X1530255Y1066323D03*
Y1072701D03*
X1543208Y1063134D03*
X1535806D03*
X1543208Y1069512D03*
X1541357Y1072701D03*
X1535806Y1069512D03*
X1530255Y1079079D03*
Y1085457D03*
X1535806Y1075890D03*
X1541357Y1079079D03*
X1543208Y1082268D03*
Y1088646D03*
X1535806D03*
Y1082268D03*
X1530255Y1098213D03*
Y1104591D03*
X1541357Y1091835D03*
X1535806Y1095024D03*
X1543208Y1101402D03*
X1541357Y1098213D03*
X1535806Y1101402D03*
X1530255Y1091835D03*
Y1110969D03*
Y1117347D03*
X1543208Y1107780D03*
X1535806D03*
X1541357Y1110969D03*
Y1117347D03*
X1535806Y1114158D03*
X1530255Y1123725D03*
Y1130102D03*
X1543208Y1120536D03*
X1535806D03*
X1543208Y1126914D03*
X1535806D03*
X1541357Y1130102D03*
X1535806Y1133292D03*
X1530255Y1142858D03*
Y1136480D03*
Y1149236D03*
X1541357Y1136480D03*
X1543208Y1139669D03*
X1535806D03*
X1543208Y1146047D03*
X1541357Y1149236D03*
X1535806Y1146047D03*
X1530255Y1155614D03*
X1537657D03*
X1541357D03*
X1535806Y1152425D03*
X1532106Y1158803D03*
X1535806D03*
X1541357Y1161992D03*
X1532106Y1165181D03*
X1531167Y1540295D03*
X1529773Y1547243D03*
X1534188Y1554453D03*
X1529443D03*
X1529994Y1561853D03*
X1534824Y1569063D03*
X1531167Y1575641D03*
X1529493Y1569063D03*
X1530373Y1625380D03*
X1542433D03*
X1538173D03*
X1532133Y1635380D03*
X1536413D03*
X1532133Y1647292D03*
X1536413D03*
X1530373Y1657292D03*
X1542433D03*
X1538173D03*
X1528935Y1679320D03*
Y1683857D03*
X1536809Y1684454D03*
Y1679920D03*
Y1675383D03*
X1528935Y1688391D03*
Y1693493D03*
Y1698030D03*
X1536809Y1698627D03*
Y1694093D03*
Y1689556D03*
X1528935Y1712203D03*
X1536809Y1712800D03*
Y1708266D03*
Y1703729D03*
X1528935Y1716737D03*
Y1702564D03*
Y1707666D03*
Y1721840D03*
Y1726377D03*
Y1730911D03*
X1536809Y1726974D03*
Y1722440D03*
Y1717903D03*
X1553870Y906181D03*
Y912559D03*
Y918937D03*
Y925315D03*
Y931693D03*
Y938071D03*
Y944449D03*
Y950827D03*
Y957205D03*
Y963583D03*
Y969961D03*
Y976339D03*
Y982717D03*
Y989095D03*
Y995473D03*
Y1008229D03*
Y1001851D03*
X1548759Y1028055D03*
X1555051Y1030197D03*
X1548759Y1040811D03*
Y1034433D03*
X1555051Y1042953D03*
Y1036575D03*
X1546909Y1056756D03*
X1545058Y1059945D03*
X1548759Y1047189D03*
X1555051Y1049331D03*
X1548759Y1053567D03*
Y1059945D03*
X1555051Y1055709D03*
Y1062087D03*
X1548759Y1072701D03*
Y1066323D03*
X1555051Y1068465D03*
Y1074843D03*
X1548759Y1079079D03*
X1555051Y1081221D03*
X1548759Y1085457D03*
X1555051Y1087599D03*
X1548759Y1091835D03*
X1555051Y1093977D03*
X1548759Y1098213D03*
Y1104591D03*
X1555051Y1100355D03*
Y1106733D03*
X1548759Y1110969D03*
X1555051Y1113111D03*
X1548759Y1117347D03*
X1555051Y1119489D03*
Y1132245D03*
X1548759Y1123725D03*
X1555051Y1125867D03*
X1548759Y1130102D03*
Y1136480D03*
X1555051Y1138622D03*
X1548759Y1142858D03*
X1555051Y1145000D03*
X1548759Y1149236D03*
X1545058Y1155614D03*
X1548759D03*
X1555051Y1151378D03*
X1550609Y1158803D03*
X1554310D03*
X1550233Y1625380D03*
X1554493D03*
X1544193Y1635380D03*
X1556253D03*
X1548473D03*
X1544193Y1647292D03*
X1556253D03*
X1548473D03*
X1554493Y1657292D03*
X1550233D03*
X1544683Y1679320D03*
Y1683857D03*
X1552557Y1684454D03*
Y1679920D03*
Y1675383D03*
X1544683Y1688391D03*
Y1693493D03*
Y1698030D03*
X1552557Y1698627D03*
Y1694093D03*
Y1689556D03*
X1544683Y1716737D03*
Y1702564D03*
Y1707666D03*
Y1712203D03*
X1552557Y1712800D03*
Y1708266D03*
Y1703729D03*
X1544683Y1721840D03*
Y1726377D03*
Y1730911D03*
X1552557Y1726974D03*
Y1722440D03*
Y1717903D03*
X1562293Y1625380D03*
X1566553D03*
X1568313Y1635380D03*
X1560533D03*
X1572593D03*
X1568313Y1647292D03*
X1560533D03*
X1572593D03*
X1562293Y1657292D03*
X1566553D03*
X1572243Y1684454D03*
Y1679920D03*
Y1675383D03*
X1560431Y1679320D03*
Y1683857D03*
X1572243Y1698627D03*
Y1694093D03*
Y1689556D03*
X1560431Y1688391D03*
Y1693493D03*
Y1698030D03*
X1572243Y1712800D03*
Y1708266D03*
Y1703729D03*
X1560431Y1716737D03*
Y1702564D03*
Y1707666D03*
Y1712203D03*
X1572243Y1726974D03*
Y1722440D03*
Y1717903D03*
X1560431Y1721840D03*
Y1726377D03*
Y1730911D03*
X1583056Y1540514D03*
X1586969Y1547243D03*
X1585797Y1552195D03*
X1586639Y1554453D03*
X1587190Y1561853D03*
X1577688Y1556810D03*
Y1561725D03*
X1586688Y1569063D03*
X1583160Y1575425D03*
X1574353Y1625380D03*
X1578613D03*
X1586413D03*
X1580373Y1635380D03*
X1584653D03*
X1580373Y1647292D03*
X1584653D03*
X1574353Y1657292D03*
X1578613D03*
X1586413D03*
X1580117Y1679320D03*
Y1683857D03*
X1587991Y1684454D03*
Y1679920D03*
Y1675383D03*
X1580117Y1688391D03*
Y1693493D03*
Y1698030D03*
X1587991Y1698627D03*
Y1694093D03*
Y1689556D03*
X1580117Y1716737D03*
Y1702564D03*
Y1707666D03*
Y1712203D03*
X1587991Y1712800D03*
Y1708266D03*
Y1703729D03*
X1580117Y1721840D03*
Y1726377D03*
Y1730911D03*
X1587991Y1726974D03*
Y1722440D03*
Y1717903D03*
X1588363Y1540295D03*
X1591693Y1547243D03*
X1593088Y1540295D03*
X1596418Y1547243D03*
X1597812Y1540295D03*
X1601142Y1547243D03*
X1602536Y1540295D03*
X1600812Y1554453D03*
X1596088D03*
X1591363D03*
X1601363Y1561853D03*
X1596639D03*
X1591914D03*
X1602536Y1575641D03*
X1600862Y1569063D03*
X1597812Y1575641D03*
X1596138Y1569063D03*
X1593088Y1575641D03*
X1591413Y1569063D03*
X1588363Y1575641D03*
X1590673Y1625380D03*
X1602733D03*
X1598473D03*
X1592433Y1635380D03*
X1596713D03*
X1592433Y1647292D03*
X1596713D03*
X1590673Y1657292D03*
X1598473D03*
X1602733D03*
X1595865Y1679320D03*
Y1683857D03*
Y1688391D03*
Y1693493D03*
Y1698030D03*
Y1716737D03*
Y1702564D03*
Y1707666D03*
Y1712203D03*
Y1721840D03*
Y1726377D03*
Y1730911D03*
X1605867Y1547243D03*
X1607261Y1540295D03*
X1610591Y1547243D03*
X1611985Y1540295D03*
X1615315Y1547243D03*
X1616710Y1540295D03*
X1614985Y1554453D03*
X1610261D03*
X1605536D03*
X1615536Y1561853D03*
X1610812D03*
X1606087D03*
X1616710Y1575641D03*
X1615035Y1569063D03*
X1611985Y1575641D03*
X1607261D03*
X1610533Y1625380D03*
X1614793D03*
X1604493Y1635380D03*
X1616553D03*
X1608773D03*
X1604493Y1647292D03*
X1616553D03*
X1608773D03*
X1614793Y1657292D03*
X1610533D03*
X1611613Y1679320D03*
Y1683857D03*
X1603739Y1684454D03*
Y1679920D03*
Y1675383D03*
X1611613Y1688391D03*
Y1693493D03*
Y1698030D03*
X1603739Y1698627D03*
Y1694093D03*
Y1689556D03*
X1611613Y1702564D03*
Y1707666D03*
Y1712203D03*
X1603739Y1712800D03*
Y1708266D03*
Y1703729D03*
X1611613Y1716737D03*
Y1721840D03*
Y1726377D03*
Y1730911D03*
X1603739Y1726974D03*
Y1722440D03*
Y1717903D03*
X1620040Y1547243D03*
X1621434Y1540295D03*
X1624764Y1547243D03*
X1626158Y1540295D03*
X1629489Y1547243D03*
X1630883Y1540295D03*
X1629158Y1554453D03*
X1624434D03*
X1619710D03*
X1629709Y1561853D03*
X1624985D03*
X1620261D03*
X1630883Y1575641D03*
X1626158D03*
X1624484Y1569063D03*
X1621434Y1575641D03*
X1622593Y1625380D03*
X1626853D03*
X1628613Y1635380D03*
X1620833D03*
X1632893D03*
X1628613Y1647292D03*
X1620833D03*
X1632893D03*
X1622593Y1657292D03*
X1626853D03*
X1627361Y1679320D03*
Y1683857D03*
X1619487Y1684454D03*
Y1679920D03*
Y1675383D03*
X1627361Y1688391D03*
Y1693493D03*
Y1698030D03*
X1619487Y1698627D03*
Y1694093D03*
Y1689556D03*
Y1708266D03*
Y1703729D03*
X1627361Y1716737D03*
Y1702564D03*
Y1707666D03*
Y1712203D03*
X1619487Y1712800D03*
X1627361Y1721840D03*
Y1726377D03*
Y1730911D03*
X1619487Y1726974D03*
Y1722440D03*
Y1717903D03*
X1634213Y1547243D03*
X1635607Y1540295D03*
X1638937Y1547243D03*
X1640332Y1540295D03*
X1643662Y1547243D03*
X1645056Y1540295D03*
X1643332Y1554453D03*
X1638607D03*
X1633883D03*
X1643883Y1561853D03*
X1639158D03*
X1634434D03*
X1645056Y1575641D03*
X1640332D03*
X1638657Y1569063D03*
X1635607Y1575641D03*
X1634653Y1625380D03*
X1638923D03*
X1646713D03*
X1640673Y1635286D03*
X1644953Y1635380D03*
X1640673Y1647292D03*
X1644953D03*
X1634653Y1657292D03*
X1638913D03*
X1646713D03*
X1648386Y1547243D03*
X1649780Y1540295D03*
X1654505D03*
X1657835Y1547243D03*
X1659229Y1540295D03*
X1662250Y1554453D03*
X1657505D03*
X1652781D03*
X1648056D03*
X1658056Y1561853D03*
X1653332D03*
X1648607D03*
X1649780Y1575641D03*
X1648106Y1569063D03*
X1654505Y1575641D03*
X1657555Y1569063D03*
X1659229Y1575641D03*
X1652743Y1635380D03*
Y1647292D03*
X1662886Y1569063D03*
G54D37*
X274913Y1019214D03*
X320189Y838505D03*
Y1199923D03*
X561133Y838505D03*
Y1199923D03*
X606409Y1019214D03*
X841240Y1420331D03*
X1016240D03*
X1251055Y1019213D03*
X1296331Y838504D03*
Y1199922D03*
X1537275Y838504D03*
Y1199922D03*
X1582551Y1019213D03*
G54D44*
X393287Y-28508D03*
Y-18508D03*
X731757Y-20090D03*
X735010Y-20104D03*
X728717Y-18895D03*
X734995Y-17589D03*
X731742Y-17575D03*
X735041Y-14717D03*
X735026Y-12202D03*
X734996Y-7172D03*
X728718Y-8478D03*
X735011Y-9687D03*
X731743Y-7158D03*
X731758Y-9673D03*
X844766Y-24648D03*
Y5352D03*
Y15352D03*
X1180124Y-35569D03*
X1183149Y-34249D03*
X1183164Y-36764D03*
X1183139Y-26179D03*
X1180099Y-14984D03*
X1183124Y-13664D03*
X1183139Y-16179D03*
X1183124Y-23664D03*
X1180099Y-24984D03*
X1183139Y-6179D03*
X1183124Y-3664D03*
X1180099Y-4984D03*
Y15016D03*
X1183124Y16336D03*
X1183139Y13821D03*
X1180099Y5016D03*
X1183124Y6336D03*
X1183139Y3821D03*
X1183140Y24187D03*
X1183125Y26702D03*
X1180100Y25382D03*
X1186402Y-34263D03*
X1186417Y-36778D03*
X1186448Y-31442D03*
X1186433Y-28927D03*
X1186392Y-26193D03*
X1186377Y-13678D03*
X1186392Y-16193D03*
X1186377Y-23678D03*
X1186392Y-6193D03*
X1186377Y-3678D03*
Y16322D03*
X1186392Y13807D03*
X1186377Y6322D03*
X1186392Y3807D03*
X1186423Y19143D03*
X1186408Y21658D03*
X1186393Y24173D03*
X1186378Y26688D03*
X1248286Y-34648D03*
Y-4648D03*
Y5352D03*
X1438983Y-35569D03*
X1438959Y25382D03*
X1445292Y-28927D03*
X1445307Y-31442D03*
X1442023Y-36764D03*
X1442008Y-34249D03*
X1445276Y-36778D03*
X1445261Y-34263D03*
X1441909Y-19948D03*
X1445171D03*
X1441909Y-9948D03*
X1445171D03*
X1441909Y52D03*
X1445171D03*
X1441909Y10052D03*
X1445171D03*
X1445237Y26688D03*
X1445252Y24173D03*
X1441984Y26702D03*
X1441999Y24187D03*
X1445267Y21658D03*
X1445282Y19143D03*
X1541580Y-38849D03*
Y-28849D03*
X1735374Y-27916D03*
X1732349Y-29236D03*
X1735389Y-30431D03*
X1735390Y-20014D03*
X1735375Y-17499D03*
X1732350Y-18819D03*
X1738627Y-27930D03*
X1738642Y-30445D03*
X1738643Y-20028D03*
X1738628Y-17513D03*
X1738673Y-25058D03*
X1738658Y-22543D03*
G54D78*
X1900275Y-39973D03*
X1910275D03*
X1931395Y572237D03*
X1921395D03*
X1929766Y1198160D03*
X1919766D03*
X1942395Y-39783D03*
X1952395D03*
X1963362Y572379D03*
X1961856Y1198170D03*
X1973362Y572379D03*
X1971856Y1198170D03*
X1984482Y-39811D03*
X1994482D03*
X2005452Y572389D03*
X2003823Y1198312D03*
X2015452Y572389D03*
X2013823Y1198312D03*
X2036452Y-39631D03*
X2026452D03*
X2047419Y572531D03*
X2057419D03*
G54D21*
X57646Y12480D03*
X137272D03*
X186622D03*
X266858D03*
X315598D03*
X502528Y33267D03*
X582154D03*
X631504D03*
X711740D03*
X760480D03*
X1532055Y12480D03*
X1611681D03*
X1661031D03*
X1741267D03*
X1790007D03*
G54D41*
X326731Y663237D03*
X363731D03*
X754645Y1436735D03*
X1166535Y1422322D03*
X1291146Y1385558D03*
X1320516D03*
X1487677Y649988D03*
X1524437Y650208D03*
X1701285Y208455D03*
X1700840Y1434362D03*
X1731660Y208455D03*
X1770442Y294777D03*
X1800002D03*
G54D62*
X1077638Y133866D03*
G54D26*
X77394Y734588D03*
Y1021399D03*
Y1277698D03*
X107095Y734588D03*
Y1021399D03*
Y1277698D03*
X136795Y734588D03*
Y1021399D03*
Y1277698D03*
X166496Y734588D03*
Y1021399D03*
Y1277698D03*
X196197Y734588D03*
Y1021399D03*
Y1277698D03*
X225898Y734588D03*
Y1021399D03*
Y1277698D03*
X655425Y734588D03*
Y1021399D03*
Y1277698D03*
X685126Y734588D03*
Y1021399D03*
Y1277698D03*
X714827Y734588D03*
Y1021399D03*
Y1277698D03*
X744528Y734588D03*
Y1021399D03*
Y1277698D03*
X774229Y734588D03*
Y1021399D03*
Y1277698D03*
X803929Y734588D03*
Y1021399D03*
Y1277698D03*
X1053536Y734587D03*
Y1021398D03*
Y1277697D03*
X1083237Y734587D03*
Y1021398D03*
Y1277697D03*
X1112937Y734587D03*
Y1021398D03*
Y1277697D03*
X1142638Y734587D03*
Y1021398D03*
Y1277697D03*
X1172339Y734587D03*
Y1021398D03*
Y1277697D03*
X1202040Y734587D03*
Y1021398D03*
Y1277697D03*
X1631567Y734587D03*
Y1021398D03*
Y1277697D03*
X1661268Y734587D03*
Y1021398D03*
Y1277697D03*
X1690969Y734587D03*
Y1021398D03*
Y1277697D03*
X1720670Y734587D03*
Y1021398D03*
Y1277697D03*
X1750371Y734587D03*
Y1021398D03*
Y1277697D03*
X1780071Y734587D03*
Y1021398D03*
Y1277697D03*
G54D56*
X887519Y1528191D03*
G54D68*
X1299439Y112812D03*
G54D69*
X1454797Y87432D03*
G54D70*
X1550377Y581353D03*
G54D48*
X549016Y274272D03*
G54D57*
X900197Y175177D03*
X944685Y155197D03*
G54D77*
X1864706Y1722195D03*
X1887340Y424013D03*
X1887240Y796658D03*
X1887579Y1171532D03*
G54D75*
X1865648Y796913D03*
X1866790Y1171255D03*
X1886177Y1722507D03*
X2076128Y424013D03*
%LPC*%
G75*
G54D82*
G01X-476840Y-884638D02*
Y2768362D01*
X5911000D01*
Y-884638D01*
X-476840D01*
G01X8000Y-625138D02*
Y-630138D01*
G01X6543Y-625138D02*
X9457D01*
G01X14367Y-630138D02*
X11833D01*
Y-625138D01*
X14367D01*
G01X13353Y-627555D02*
X11833D01*
G01X16933Y-625138D02*
Y-630138D01*
X19467D01*
G01X23300Y-630305D02*
X23173Y-630221D01*
Y-630055D01*
X23300Y-629971D01*
X23427Y-630055D01*
Y-630221D01*
X23300Y-630305D01*
G01Y-628055D02*
X23173Y-627971D01*
Y-627805D01*
X23300Y-627721D01*
X23427Y-627805D01*
Y-627971D01*
X23300Y-628055D01*
G01X28083Y-631805D02*
X27450Y-630971D01*
X27133Y-630138D01*
Y-626805D01*
X27450Y-625971D01*
X28083Y-625138D01*
G01X33500D02*
X32993Y-625305D01*
X32613Y-625721D01*
X32360Y-626221D01*
X32170Y-626888D01*
X32107Y-627638D01*
X32170Y-628388D01*
X32360Y-629055D01*
X32613Y-629555D01*
X32993Y-629971D01*
X33500Y-630138D01*
X34007Y-629971D01*
X34387Y-629555D01*
X34640Y-629055D01*
X34830Y-628388D01*
X34893Y-627638D01*
X34830Y-626888D01*
X34640Y-626221D01*
X34387Y-625721D01*
X34007Y-625305D01*
X33500Y-625138D01*
G01X37207Y-629138D02*
X37587Y-629721D01*
X38093Y-630055D01*
X38663Y-630138D01*
X39170Y-630055D01*
X39677Y-629638D01*
X39993Y-629138D01*
X40057Y-628638D01*
X39930Y-628055D01*
X39487Y-627638D01*
X39043Y-627471D01*
X38473D01*
G01X39043D02*
X39423Y-627221D01*
X39740Y-626805D01*
X39867Y-626305D01*
X39740Y-625805D01*
X39423Y-625388D01*
X38853Y-625138D01*
X38283Y-625221D01*
X37713Y-625555D01*
G01X44017Y-631805D02*
X44650Y-630971D01*
X44967Y-630138D01*
Y-626805D01*
X44650Y-625971D01*
X44017Y-625138D01*
G01X47407Y-629138D02*
X47787Y-629721D01*
X48293Y-630055D01*
X48863Y-630138D01*
X49370Y-630055D01*
X49877Y-629638D01*
X50193Y-629138D01*
X50257Y-628638D01*
X50130Y-628055D01*
X49687Y-627638D01*
X49243Y-627471D01*
X48673D01*
G01X49243D02*
X49623Y-627221D01*
X49940Y-626805D01*
X50067Y-626305D01*
X49940Y-625805D01*
X49623Y-625388D01*
X49053Y-625138D01*
X48483Y-625221D01*
X47913Y-625555D01*
G01X52697Y-625971D02*
X53077Y-625471D01*
X53520Y-625221D01*
X54027Y-625138D01*
X54660Y-625305D01*
X55103Y-625721D01*
X55230Y-626221D01*
X55167Y-626721D01*
X54913Y-627138D01*
X53647Y-627971D01*
X53077Y-628555D01*
X52697Y-629388D01*
X52570Y-630138D01*
X55230D01*
G01X58873D02*
X59000Y-629055D01*
X59190Y-628138D01*
X59443Y-627305D01*
X59760Y-626388D01*
X60267Y-625138D01*
X57733D01*
G01X63277Y-628471D02*
X64923D01*
G01X67997Y-625971D02*
X68377Y-625471D01*
X68820Y-625221D01*
X69327Y-625138D01*
X69960Y-625305D01*
X70403Y-625721D01*
X70530Y-626221D01*
X70467Y-626721D01*
X70213Y-627138D01*
X68947Y-627971D01*
X68377Y-628555D01*
X67997Y-629388D01*
X67870Y-630138D01*
X70530D01*
G01X72907Y-629138D02*
X73287Y-629721D01*
X73793Y-630055D01*
X74363Y-630138D01*
X74870Y-630055D01*
X75377Y-629638D01*
X75693Y-629138D01*
X75757Y-628638D01*
X75630Y-628055D01*
X75187Y-627638D01*
X74743Y-627471D01*
X74173D01*
G01X74743D02*
X75123Y-627221D01*
X75440Y-626805D01*
X75567Y-626305D01*
X75440Y-625805D01*
X75123Y-625388D01*
X74553Y-625138D01*
X73983Y-625221D01*
X73413Y-625555D01*
G01X80160Y-630138D02*
Y-625138D01*
X77817Y-628721D01*
X80983D01*
G01X83107Y-629388D02*
X83487Y-629805D01*
X83930Y-630055D01*
X84500Y-630138D01*
X85070Y-629971D01*
X85513Y-629638D01*
X85830Y-629055D01*
X85893Y-628388D01*
X85767Y-627721D01*
X85450Y-627305D01*
X85007Y-626971D01*
X84563Y-626888D01*
X84120Y-626971D01*
X83550Y-627305D01*
X83740Y-625138D01*
X85450D01*
G01X93497Y-630138D02*
Y-625138D01*
X95903D01*
G01X95017Y-627555D02*
X93497D01*
G01X98217Y-630138D02*
X99800Y-625138D01*
X101383Y-630138D01*
G01X100813Y-628388D02*
X98787D01*
G01X103570Y-630138D02*
X106230Y-625138D01*
G01X103570D02*
X106230Y-630138D01*
G01X110000Y-630305D02*
X109873Y-630221D01*
Y-630055D01*
X110000Y-629971D01*
X110127Y-630055D01*
Y-630221D01*
X110000Y-630305D01*
G01Y-628055D02*
X109873Y-627971D01*
Y-627805D01*
X110000Y-627721D01*
X110127Y-627805D01*
Y-627971D01*
X110000Y-628055D01*
G01X114783Y-631805D02*
X114150Y-630971D01*
X113833Y-630138D01*
Y-626805D01*
X114150Y-625971D01*
X114783Y-625138D01*
G01X120200D02*
X119693Y-625305D01*
X119313Y-625721D01*
X119060Y-626221D01*
X118870Y-626888D01*
X118807Y-627638D01*
X118870Y-628388D01*
X119060Y-629055D01*
X119313Y-629555D01*
X119693Y-629971D01*
X120200Y-630138D01*
X120707Y-629971D01*
X121087Y-629555D01*
X121340Y-629055D01*
X121530Y-628388D01*
X121593Y-627638D01*
X121530Y-626888D01*
X121340Y-626221D01*
X121087Y-625721D01*
X120707Y-625305D01*
X120200Y-625138D01*
G01X123907Y-629138D02*
X124287Y-629721D01*
X124793Y-630055D01*
X125363Y-630138D01*
X125870Y-630055D01*
X126377Y-629638D01*
X126693Y-629138D01*
X126757Y-628638D01*
X126630Y-628055D01*
X126187Y-627638D01*
X125743Y-627471D01*
X125173D01*
G01X125743D02*
X126123Y-627221D01*
X126440Y-626805D01*
X126567Y-626305D01*
X126440Y-625805D01*
X126123Y-625388D01*
X125553Y-625138D01*
X124983Y-625221D01*
X124413Y-625555D01*
G01X130717Y-631805D02*
X131350Y-630971D01*
X131667Y-630138D01*
Y-626805D01*
X131350Y-625971D01*
X130717Y-625138D01*
G01X134107Y-629138D02*
X134487Y-629721D01*
X134993Y-630055D01*
X135563Y-630138D01*
X136070Y-630055D01*
X136577Y-629638D01*
X136893Y-629138D01*
X136957Y-628638D01*
X136830Y-628055D01*
X136387Y-627638D01*
X135943Y-627471D01*
X135373D01*
G01X135943D02*
X136323Y-627221D01*
X136640Y-626805D01*
X136767Y-626305D01*
X136640Y-625805D01*
X136323Y-625388D01*
X135753Y-625138D01*
X135183Y-625221D01*
X134613Y-625555D01*
G01X139523Y-629555D02*
X139967Y-629971D01*
X140473Y-630138D01*
X140980Y-629971D01*
X141423Y-629471D01*
X141740Y-628721D01*
X141867Y-627971D01*
Y-627055D01*
X141740Y-626305D01*
X141423Y-625638D01*
X141043Y-625305D01*
X140600Y-625138D01*
X140093Y-625305D01*
X139713Y-625638D01*
X139460Y-626138D01*
X139333Y-626805D01*
X139460Y-627388D01*
X139777Y-627971D01*
X140157Y-628305D01*
X140600Y-628388D01*
X141107Y-628221D01*
X141487Y-627805D01*
X141867Y-627055D01*
G01X145573Y-630138D02*
X145700Y-629055D01*
X145890Y-628138D01*
X146143Y-627305D01*
X146460Y-626388D01*
X146967Y-625138D01*
X144433D01*
G01X149977Y-628471D02*
X151623D01*
G01X154507Y-629138D02*
X154887Y-629721D01*
X155393Y-630055D01*
X155963Y-630138D01*
X156470Y-630055D01*
X156977Y-629638D01*
X157293Y-629138D01*
X157357Y-628638D01*
X157230Y-628055D01*
X156787Y-627638D01*
X156343Y-627471D01*
X155773D01*
G01X156343D02*
X156723Y-627221D01*
X157040Y-626805D01*
X157167Y-626305D01*
X157040Y-625805D01*
X156723Y-625388D01*
X156153Y-625138D01*
X155583Y-625221D01*
X155013Y-625555D01*
G01X159797Y-628055D02*
X160240Y-627471D01*
X160620Y-627138D01*
X161127Y-626971D01*
X161570Y-627138D01*
X161887Y-627471D01*
X162140Y-627971D01*
X162203Y-628555D01*
X162140Y-629055D01*
X161887Y-629555D01*
X161507Y-629971D01*
X161063Y-630138D01*
X160557Y-629971D01*
X160113Y-629471D01*
X159860Y-628721D01*
X159797Y-627888D01*
X159923Y-626805D01*
X160113Y-626221D01*
X160430Y-625638D01*
X160873Y-625221D01*
X161317Y-625138D01*
X161760Y-625305D01*
X162077Y-625721D01*
G01X166100Y-630138D02*
Y-625138D01*
X165340Y-626138D01*
G01Y-630138D02*
X166860D01*
G01X171960D02*
Y-625138D01*
X169617Y-628721D01*
X172783D01*
G01X-4000Y-560138D02*
Y-635138D01*
X496000D01*
Y-560138D01*
X-4000D01*
G01X191000D02*
Y-635138D01*
G01Y-610138D02*
X294000D01*
Y-585138D01*
G01X191000D02*
X294000D01*
G01X296000Y-560138D02*
Y-635138D01*
G01X294000Y-560138D02*
Y-635138D01*
G01X301507Y-620138D02*
Y-615138D01*
X302773D01*
X303280Y-615388D01*
X303660Y-615721D01*
X303977Y-616221D01*
X304230Y-616805D01*
X304293Y-617638D01*
X304230Y-618471D01*
X303977Y-619055D01*
X303660Y-619555D01*
X303280Y-619888D01*
X302773Y-620138D01*
X301507D01*
G01X306417D02*
X308000Y-615138D01*
X309583Y-620138D01*
G01X309013Y-618388D02*
X306987D01*
G01X313100Y-615138D02*
Y-620138D01*
G01X311643Y-615138D02*
X314557D01*
G01X319467Y-620138D02*
X316933D01*
Y-615138D01*
X319467D01*
G01X318453Y-617555D02*
X316933D01*
G01X323300Y-620305D02*
X323173Y-620221D01*
Y-620055D01*
X323300Y-619971D01*
X323427Y-620055D01*
Y-620221D01*
X323300Y-620305D01*
G01Y-618055D02*
X323173Y-617971D01*
Y-617805D01*
X323300Y-617721D01*
X323427Y-617805D01*
Y-617971D01*
X323300Y-618055D01*
G01X296000Y-610138D02*
X496000D01*
G01X301633Y-595138D02*
Y-590138D01*
X303153D01*
X303660Y-590388D01*
X304040Y-590971D01*
X304167Y-591638D01*
X304040Y-592305D01*
X303723Y-592805D01*
X303153Y-593055D01*
X301633D01*
G01X306860Y-595305D02*
X309140Y-590138D01*
G01X311643Y-595138D02*
Y-590138D01*
X314557Y-595138D01*
Y-590138D01*
G01X318200Y-595305D02*
X318073Y-595221D01*
Y-595055D01*
X318200Y-594971D01*
X318327Y-595055D01*
Y-595221D01*
X318200Y-595305D01*
G01Y-593055D02*
X318073Y-592971D01*
Y-592805D01*
X318200Y-592721D01*
X318327Y-592805D01*
Y-592971D01*
X318200Y-593055D01*
G01X296000Y-585138D02*
X496000D01*
G01X301633Y-570138D02*
Y-565138D01*
X303153D01*
X303660Y-565388D01*
X304040Y-565971D01*
X304167Y-566638D01*
X304040Y-567305D01*
X303723Y-567805D01*
X303153Y-568055D01*
X301633D01*
G01X306733Y-570138D02*
Y-565138D01*
X308317D01*
X308823Y-565388D01*
X309140Y-565721D01*
X309267Y-566388D01*
X309140Y-567055D01*
X308760Y-567471D01*
X308317Y-567721D01*
X306733D01*
G01X308317D02*
X309267Y-570138D01*
G01X313100D02*
X312593Y-570055D01*
X312150Y-569721D01*
X311770Y-569221D01*
X311517Y-568638D01*
X311390Y-567971D01*
Y-567305D01*
X311517Y-566638D01*
X311770Y-566055D01*
X312150Y-565555D01*
X312593Y-565221D01*
X313100Y-565138D01*
X313607Y-565221D01*
X314050Y-565555D01*
X314430Y-566055D01*
X314683Y-566638D01*
X314810Y-567305D01*
Y-567971D01*
X314683Y-568638D01*
X314430Y-569221D01*
X314050Y-569721D01*
X313607Y-570055D01*
X313100Y-570138D01*
G01X316933Y-569138D02*
X317250Y-569638D01*
X317630Y-569971D01*
X318073Y-570138D01*
X318580Y-569971D01*
X318960Y-569638D01*
X319340Y-569138D01*
X319467Y-568471D01*
Y-565138D01*
G01X324567Y-570138D02*
X322033D01*
Y-565138D01*
X324567D01*
G01X323553Y-567555D02*
X322033D01*
G01X329793Y-565555D02*
X329413Y-565305D01*
X328970Y-565138D01*
X328463D01*
X327893Y-565388D01*
X327450Y-565805D01*
X327133Y-566305D01*
X326880Y-567138D01*
X326817Y-567888D01*
X326943Y-568638D01*
X327133Y-569138D01*
X327513Y-569638D01*
X327957Y-569971D01*
X328400Y-570138D01*
X328843D01*
X329287Y-569971D01*
X329667Y-569721D01*
X329983Y-569388D01*
G01X333500Y-565138D02*
Y-570138D01*
G01X332043Y-565138D02*
X334957D01*
G01X338600Y-570305D02*
X338473Y-570221D01*
Y-570055D01*
X338600Y-569971D01*
X338727Y-570055D01*
Y-570221D01*
X338600Y-570305D01*
G01Y-568055D02*
X338473Y-567971D01*
Y-567805D01*
X338600Y-567721D01*
X338727Y-567805D01*
Y-567971D01*
X338600Y-568055D01*
G01X411000Y-610138D02*
Y-635138D01*
G01X413633Y-612638D02*
Y-617638D01*
X416167D01*
G01X419240Y-612638D02*
X420760D01*
G01X420000D02*
Y-617638D01*
G01X419240D02*
X420760D01*
G01X425607Y-614971D02*
X425860Y-614721D01*
X426050Y-614305D01*
X426177Y-613721D01*
X426050Y-613221D01*
X425797Y-612888D01*
X425353Y-612638D01*
X423643D01*
Y-617638D01*
X425733D01*
X426177Y-617305D01*
X426430Y-616805D01*
X426557Y-616221D01*
X426430Y-615638D01*
X426050Y-615138D01*
X425607Y-614971D01*
X423643D01*
G01X430200Y-617805D02*
X430073Y-617721D01*
Y-617555D01*
X430200Y-617471D01*
X430327Y-617555D01*
Y-617721D01*
X430200Y-617805D01*
G01Y-615555D02*
X430073Y-615471D01*
Y-615305D01*
X430200Y-615221D01*
X430327Y-615305D01*
Y-615471D01*
X430200Y-615555D01*
G01X454000Y-610138D02*
Y-635138D01*
G01Y-585138D02*
Y-610138D01*
G01X459013Y-637305D02*
X459120Y-637180D01*
X459200Y-636971D01*
X459253Y-636680D01*
X459200Y-636430D01*
X459093Y-636263D01*
X458907Y-636138D01*
X458187D01*
Y-638638D01*
X459067D01*
X459253Y-638471D01*
X459360Y-638221D01*
X459413Y-637930D01*
X459360Y-637638D01*
X459200Y-637388D01*
X459013Y-637305D01*
X458187D01*
G01X461480Y-638638D02*
Y-636971D01*
G01Y-637263D02*
X461373Y-637096D01*
X461213Y-637013D01*
X461027Y-636971D01*
X460840Y-637055D01*
X460680Y-637221D01*
X460573Y-637471D01*
X460520Y-637805D01*
X460573Y-638138D01*
X460680Y-638388D01*
X460840Y-638555D01*
X461027Y-638638D01*
X461213Y-638596D01*
X461373Y-638471D01*
X461480Y-638305D01*
G01X462800Y-638346D02*
X462933Y-638513D01*
X463120Y-638638D01*
X463280D01*
X463440Y-638555D01*
X463547Y-638430D01*
X463600Y-638263D01*
X463573Y-638013D01*
X463467Y-637888D01*
X462987Y-637638D01*
X462880Y-637346D01*
X462933Y-637138D01*
X463040Y-637013D01*
X463200Y-636971D01*
X463360Y-637013D01*
X463520Y-637138D01*
G01X465000Y-637513D02*
X465853D01*
X465773Y-637221D01*
X465640Y-637055D01*
X465453Y-636971D01*
X465267Y-637013D01*
X465107Y-637138D01*
X465000Y-637430D01*
X464947Y-637680D01*
Y-637930D01*
X465000Y-638180D01*
X465133Y-638430D01*
X465293Y-638596D01*
X465480Y-638638D01*
X465667Y-638555D01*
X465853Y-638305D01*
G01X467120Y-638638D02*
Y-636138D01*
G01Y-637388D02*
X467253Y-637138D01*
X467413Y-637013D01*
X467573Y-636971D01*
X467813Y-637055D01*
X467973Y-637221D01*
X468080Y-637513D01*
Y-637846D01*
X468027Y-638180D01*
X467920Y-638430D01*
X467733Y-638596D01*
X467573Y-638638D01*
X467413Y-638596D01*
X467253Y-638471D01*
X467120Y-638263D01*
G01X469800Y-638638D02*
X469640Y-638596D01*
X469480Y-638430D01*
X469373Y-638138D01*
X469320Y-637805D01*
X469373Y-637471D01*
X469480Y-637180D01*
X469640Y-637013D01*
X469800Y-636971D01*
X469960Y-637013D01*
X470120Y-637180D01*
X470227Y-637471D01*
X470253Y-637805D01*
X470227Y-638138D01*
X470120Y-638430D01*
X469960Y-638596D01*
X469800Y-638638D01*
G01X472480D02*
Y-636971D01*
G01Y-637263D02*
X472373Y-637096D01*
X472213Y-637013D01*
X472027Y-636971D01*
X471840Y-637055D01*
X471680Y-637221D01*
X471573Y-637471D01*
X471520Y-637805D01*
X471573Y-638138D01*
X471680Y-638388D01*
X471840Y-638555D01*
X472027Y-638638D01*
X472213Y-638596D01*
X472373Y-638471D01*
X472480Y-638305D01*
G01X473827Y-638638D02*
Y-636971D01*
G01Y-637305D02*
X473960Y-637138D01*
X474093Y-637013D01*
X474280Y-636971D01*
X474413Y-637013D01*
X474573Y-637138D01*
G01X476880Y-636138D02*
Y-638638D01*
G01Y-638263D02*
X476773Y-638471D01*
X476613Y-638596D01*
X476427Y-638638D01*
X476213Y-638555D01*
X476053Y-638346D01*
X475947Y-638096D01*
X475920Y-637805D01*
X475947Y-637513D01*
X476053Y-637263D01*
X476213Y-637055D01*
X476427Y-636971D01*
X476613Y-637013D01*
X476747Y-637096D01*
X476880Y-637263D01*
G01X480267Y-638638D02*
Y-636138D01*
X480933D01*
X481147Y-636263D01*
X481280Y-636430D01*
X481333Y-636763D01*
X481280Y-637096D01*
X481120Y-637305D01*
X480933Y-637430D01*
X480267D01*
G01X480933D02*
X481333Y-638638D01*
G01X482600Y-637513D02*
X483453D01*
X483373Y-637221D01*
X483240Y-637055D01*
X483053Y-636971D01*
X482867Y-637013D01*
X482707Y-637138D01*
X482600Y-637430D01*
X482547Y-637680D01*
Y-637930D01*
X482600Y-638180D01*
X482733Y-638430D01*
X482893Y-638596D01*
X483080Y-638638D01*
X483267Y-638555D01*
X483453Y-638305D01*
G01X484720Y-636971D02*
X485200Y-638638D01*
X485680Y-636971D01*
G01X487400Y-638721D02*
X487347Y-638680D01*
Y-638596D01*
X487400Y-638555D01*
X487453Y-638596D01*
Y-638680D01*
X487400Y-638721D01*
G01X489147Y-638346D02*
X489333Y-638555D01*
X489547Y-638638D01*
X489760Y-638555D01*
X489947Y-638305D01*
X490080Y-637930D01*
X490133Y-637555D01*
Y-637096D01*
X490080Y-636721D01*
X489947Y-636388D01*
X489787Y-636221D01*
X489600Y-636138D01*
X489387Y-636221D01*
X489227Y-636388D01*
X489120Y-636638D01*
X489067Y-636971D01*
X489120Y-637263D01*
X489253Y-637555D01*
X489413Y-637721D01*
X489600Y-637763D01*
X489813Y-637680D01*
X489973Y-637471D01*
X490133Y-637096D01*
G01X492013Y-637305D02*
X492120Y-637180D01*
X492200Y-636971D01*
X492253Y-636680D01*
X492200Y-636430D01*
X492093Y-636263D01*
X491907Y-636138D01*
X491187D01*
Y-638638D01*
X492067D01*
X492253Y-638471D01*
X492360Y-638221D01*
X492413Y-637930D01*
X492360Y-637638D01*
X492200Y-637388D01*
X492013Y-637305D01*
X491187D01*
G01X457900Y-612638D02*
Y-617638D01*
G01X456443Y-612638D02*
X459357D01*
G01X463000Y-617638D02*
X462620Y-617555D01*
X462240Y-617221D01*
X461987Y-616638D01*
X461860Y-615971D01*
X461987Y-615305D01*
X462240Y-614721D01*
X462620Y-614388D01*
X463000Y-614305D01*
X463380Y-614388D01*
X463760Y-614721D01*
X464013Y-615305D01*
X464077Y-615971D01*
X464013Y-616638D01*
X463760Y-617221D01*
X463380Y-617555D01*
X463000Y-617638D01*
G01X468100D02*
X467720Y-617555D01*
X467340Y-617221D01*
X467087Y-616638D01*
X466960Y-615971D01*
X467087Y-615305D01*
X467340Y-614721D01*
X467720Y-614388D01*
X468100Y-614305D01*
X468480Y-614388D01*
X468860Y-614721D01*
X469113Y-615305D01*
X469177Y-615971D01*
X469113Y-616638D01*
X468860Y-617221D01*
X468480Y-617555D01*
X468100Y-617638D01*
G01X473200D02*
Y-612638D01*
G01X478300Y-617805D02*
X478173Y-617721D01*
Y-617555D01*
X478300Y-617471D01*
X478427Y-617555D01*
Y-617721D01*
X478300Y-617805D01*
G01Y-615555D02*
X478173Y-615471D01*
Y-615305D01*
X478300Y-615221D01*
X478427Y-615305D01*
Y-615471D01*
X478300Y-615555D01*
G01X456633Y-592638D02*
Y-587638D01*
X458217D01*
X458723Y-587888D01*
X459040Y-588221D01*
X459167Y-588888D01*
X459040Y-589555D01*
X458660Y-589971D01*
X458217Y-590221D01*
X456633D01*
G01X458217D02*
X459167Y-592638D01*
G01X464267D02*
X461733D01*
Y-587638D01*
X464267D01*
G01X463253Y-590055D02*
X461733D01*
G01X466517Y-587638D02*
X468100Y-592638D01*
X469683Y-587638D01*
G01X473200Y-592805D02*
X473073Y-592721D01*
Y-592555D01*
X473200Y-592471D01*
X473327Y-592555D01*
Y-592721D01*
X473200Y-592805D01*
G01Y-590555D02*
X473073Y-590471D01*
Y-590305D01*
X473200Y-590221D01*
X473327Y-590305D01*
Y-590471D01*
X473200Y-590555D01*
G01X-476840Y-884638D02*
Y2768362D01*
X5911000D01*
Y-884638D01*
X-476840D01*
G01X8820Y-607488D02*
X10387D01*
Y-609378D01*
X9917Y-610008D01*
X9368Y-610428D01*
X8585Y-610638D01*
X7802Y-610428D01*
X7253Y-610008D01*
X6783Y-609378D01*
X6470Y-608643D01*
X6313Y-607803D01*
Y-607068D01*
X6470Y-606438D01*
X6783Y-605703D01*
X7253Y-605073D01*
X7723Y-604653D01*
X8350Y-604338D01*
X8898D01*
X9525Y-604548D01*
X9995Y-604968D01*
G01X12927Y-604338D02*
Y-608853D01*
X13240Y-609798D01*
X13867Y-610428D01*
X14650Y-610638D01*
X15433Y-610428D01*
X16060Y-609798D01*
X16373Y-608853D01*
Y-604338D01*
G01X20010D02*
X21890D01*
G01X20950D02*
Y-610638D01*
G01X20010D02*
X21890D01*
G01X25605Y-609798D02*
X26232Y-610323D01*
X26937Y-610638D01*
X27563D01*
X28190Y-610323D01*
X28660Y-609798D01*
X28895Y-609063D01*
X28738Y-608328D01*
X28347Y-607698D01*
X27642Y-607278D01*
X26702Y-607068D01*
X26153Y-606648D01*
X25918Y-605913D01*
X26075Y-605178D01*
X26467Y-604653D01*
X27015Y-604338D01*
X27563D01*
X28112Y-604548D01*
X28582Y-605073D01*
G01X31905Y-610638D02*
Y-604338D01*
G01X35195D02*
Y-610638D01*
G01Y-607488D02*
X31905D01*
G01X37892Y-610638D02*
X39850Y-604338D01*
X41808Y-610638D01*
G01X41103Y-608433D02*
X38597D01*
G01X44348Y-610638D02*
Y-604338D01*
X47952Y-610638D01*
Y-604338D01*
G01X57027Y-610638D02*
Y-604338D01*
X58593D01*
X59220Y-604653D01*
X59690Y-605073D01*
X60082Y-605703D01*
X60395Y-606438D01*
X60473Y-607488D01*
X60395Y-608538D01*
X60082Y-609273D01*
X59690Y-609903D01*
X59220Y-610323D01*
X58593Y-610638D01*
X57027D01*
G01X64110Y-604338D02*
X65990D01*
G01X65050D02*
Y-610638D01*
G01X64110D02*
X65990D01*
G01X69705Y-609798D02*
X70332Y-610323D01*
X71037Y-610638D01*
X71663D01*
X72290Y-610323D01*
X72760Y-609798D01*
X72995Y-609063D01*
X72838Y-608328D01*
X72447Y-607698D01*
X71742Y-607278D01*
X70802Y-607068D01*
X70253Y-606648D01*
X70018Y-605913D01*
X70175Y-605178D01*
X70567Y-604653D01*
X71115Y-604338D01*
X71663D01*
X72212Y-604548D01*
X72682Y-605073D01*
G01X77650Y-604338D02*
Y-610638D01*
G01X75848Y-604338D02*
X79452D01*
G01X83950Y-610848D02*
X83793Y-610743D01*
Y-610533D01*
X83950Y-610428D01*
X84107Y-610533D01*
Y-610743D01*
X83950Y-610848D01*
G01X90093Y-611793D02*
X90407Y-610428D01*
G01X96550Y-604338D02*
Y-610638D01*
G01X94748Y-604338D02*
X98352D01*
G01X100892Y-610638D02*
X102850Y-604338D01*
X104808Y-610638D01*
G01X104103Y-608433D02*
X101597D01*
G01X109150Y-610638D02*
X108523Y-610533D01*
X107975Y-610113D01*
X107505Y-609483D01*
X107192Y-608748D01*
X107035Y-607908D01*
Y-607068D01*
X107192Y-606228D01*
X107505Y-605493D01*
X107975Y-604863D01*
X108523Y-604443D01*
X109150Y-604338D01*
X109777Y-604443D01*
X110325Y-604863D01*
X110795Y-605493D01*
X111108Y-606228D01*
X111265Y-607068D01*
Y-607908D01*
X111108Y-608748D01*
X110795Y-609483D01*
X110325Y-610113D01*
X109777Y-610533D01*
X109150Y-610638D01*
G01X115450D02*
Y-607803D01*
X113883Y-604338D01*
G01X117017D02*
X115450Y-607803D01*
G01X120027Y-604338D02*
Y-608853D01*
X120340Y-609798D01*
X120967Y-610428D01*
X121750Y-610638D01*
X122533Y-610428D01*
X123160Y-609798D01*
X123473Y-608853D01*
Y-604338D01*
G01X126092Y-610638D02*
X128050Y-604338D01*
X130008Y-610638D01*
G01X129303Y-608433D02*
X126797D01*
G01X132548Y-610638D02*
Y-604338D01*
X136152Y-610638D01*
Y-604338D01*
G01X10073Y-614863D02*
X9603Y-614548D01*
X9055Y-614338D01*
X8428D01*
X7723Y-614653D01*
X7175Y-615178D01*
X6783Y-615808D01*
X6470Y-616858D01*
X6392Y-617803D01*
X6548Y-618748D01*
X6783Y-619378D01*
X7253Y-620008D01*
X7802Y-620428D01*
X8350Y-620638D01*
X8898D01*
X9447Y-620428D01*
X9917Y-620113D01*
X10308Y-619693D01*
G01X13710Y-614338D02*
X15590D01*
G01X14650D02*
Y-620638D01*
G01X13710D02*
X15590D01*
G01X20950Y-614338D02*
Y-620638D01*
G01X19148Y-614338D02*
X22752D01*
G01X27250Y-620638D02*
Y-617803D01*
X25683Y-614338D01*
G01X28817D02*
X27250Y-617803D01*
G01X38127Y-619378D02*
X38597Y-620113D01*
X39223Y-620533D01*
X39928Y-620638D01*
X40555Y-620533D01*
X41182Y-620008D01*
X41573Y-619378D01*
X41652Y-618748D01*
X41495Y-618013D01*
X40947Y-617488D01*
X40398Y-617278D01*
X39693D01*
G01X40398D02*
X40868Y-616963D01*
X41260Y-616438D01*
X41417Y-615808D01*
X41260Y-615178D01*
X40868Y-614653D01*
X40163Y-614338D01*
X39458Y-614443D01*
X38753Y-614863D01*
G01X44427Y-619378D02*
X44897Y-620113D01*
X45523Y-620533D01*
X46228Y-620638D01*
X46855Y-620533D01*
X47482Y-620008D01*
X47873Y-619378D01*
X47952Y-618748D01*
X47795Y-618013D01*
X47247Y-617488D01*
X46698Y-617278D01*
X45993D01*
G01X46698D02*
X47168Y-616963D01*
X47560Y-616438D01*
X47717Y-615808D01*
X47560Y-615178D01*
X47168Y-614653D01*
X46463Y-614338D01*
X45758Y-614443D01*
X45053Y-614863D01*
G01X50727Y-619378D02*
X51197Y-620113D01*
X51823Y-620533D01*
X52528Y-620638D01*
X53155Y-620533D01*
X53782Y-620008D01*
X54173Y-619378D01*
X54252Y-618748D01*
X54095Y-618013D01*
X53547Y-617488D01*
X52998Y-617278D01*
X52293D01*
G01X52998D02*
X53468Y-616963D01*
X53860Y-616438D01*
X54017Y-615808D01*
X53860Y-615178D01*
X53468Y-614653D01*
X52763Y-614338D01*
X52058Y-614443D01*
X51353Y-614863D01*
G01X58593Y-620638D02*
X58750Y-619273D01*
X58985Y-618118D01*
X59298Y-617068D01*
X59690Y-615913D01*
X60317Y-614338D01*
X57183D01*
G01X64893Y-620638D02*
X65050Y-619273D01*
X65285Y-618118D01*
X65598Y-617068D01*
X65990Y-615913D01*
X66617Y-614338D01*
X63483D01*
G01X71193Y-621793D02*
X71507Y-620428D01*
G01X77650Y-614338D02*
Y-620638D01*
G01X75848Y-614338D02*
X79452D01*
G01X81992Y-620638D02*
X83950Y-614338D01*
X85908Y-620638D01*
G01X85203Y-618433D02*
X82697D01*
G01X89310Y-614338D02*
X91190D01*
G01X90250D02*
Y-620638D01*
G01X89310D02*
X91190D01*
G01X94200Y-614338D02*
X95297Y-620638D01*
X96550Y-614338D01*
X97803Y-620638D01*
X98900Y-614338D01*
G01X100892Y-620638D02*
X102850Y-614338D01*
X104808Y-620638D01*
G01X104103Y-618433D02*
X101597D01*
G01X107348Y-620638D02*
Y-614338D01*
X110952Y-620638D01*
Y-614338D01*
G01X121358Y-622738D02*
X120575Y-621688D01*
X120183Y-620638D01*
Y-616438D01*
X120575Y-615388D01*
X121358Y-614338D01*
G01X132783Y-620638D02*
Y-614338D01*
X134742D01*
X135368Y-614653D01*
X135760Y-615073D01*
X135917Y-615913D01*
X135760Y-616753D01*
X135290Y-617278D01*
X134742Y-617593D01*
X132783D01*
G01X134742D02*
X135917Y-620638D01*
G01X140650Y-620848D02*
X140493Y-620743D01*
Y-620533D01*
X140650Y-620428D01*
X140807Y-620533D01*
Y-620743D01*
X140650Y-620848D01*
G01X146950Y-620638D02*
X146323Y-620533D01*
X145775Y-620113D01*
X145305Y-619483D01*
X144992Y-618748D01*
X144835Y-617908D01*
Y-617068D01*
X144992Y-616228D01*
X145305Y-615493D01*
X145775Y-614863D01*
X146323Y-614443D01*
X146950Y-614338D01*
X147577Y-614443D01*
X148125Y-614863D01*
X148595Y-615493D01*
X148908Y-616228D01*
X149065Y-617068D01*
Y-617908D01*
X148908Y-618748D01*
X148595Y-619483D01*
X148125Y-620113D01*
X147577Y-620533D01*
X146950Y-620638D01*
G01X153250Y-620848D02*
X153093Y-620743D01*
Y-620533D01*
X153250Y-620428D01*
X153407Y-620533D01*
Y-620743D01*
X153250Y-620848D01*
G01X161273Y-614863D02*
X160803Y-614548D01*
X160255Y-614338D01*
X159628D01*
X158923Y-614653D01*
X158375Y-615178D01*
X157983Y-615808D01*
X157670Y-616858D01*
X157592Y-617803D01*
X157748Y-618748D01*
X157983Y-619378D01*
X158453Y-620008D01*
X159002Y-620428D01*
X159550Y-620638D01*
X160098D01*
X160647Y-620428D01*
X161117Y-620113D01*
X161508Y-619693D01*
G01X165850Y-620848D02*
X165693Y-620743D01*
Y-620533D01*
X165850Y-620428D01*
X166007Y-620533D01*
Y-620743D01*
X165850Y-620848D01*
G01X172542Y-622738D02*
X173325Y-621688D01*
X173717Y-620638D01*
Y-616438D01*
X173325Y-615388D01*
X172542Y-614338D01*
G01X6548Y-600638D02*
Y-594338D01*
X10152Y-600638D01*
Y-594338D01*
G01X14650Y-600638D02*
X14023Y-600533D01*
X13475Y-600113D01*
X13005Y-599483D01*
X12692Y-598748D01*
X12535Y-597908D01*
Y-597068D01*
X12692Y-596228D01*
X13005Y-595493D01*
X13475Y-594863D01*
X14023Y-594443D01*
X14650Y-594338D01*
X15277Y-594443D01*
X15825Y-594863D01*
X16295Y-595493D01*
X16608Y-596228D01*
X16765Y-597068D01*
Y-597908D01*
X16608Y-598748D01*
X16295Y-599483D01*
X15825Y-600113D01*
X15277Y-600533D01*
X14650Y-600638D01*
G01X20950Y-600848D02*
X20793Y-600743D01*
Y-600533D01*
X20950Y-600428D01*
X21107Y-600533D01*
Y-600743D01*
X20950Y-600848D01*
G01X25762Y-595388D02*
X26232Y-594758D01*
X26780Y-594443D01*
X27407Y-594338D01*
X28190Y-594548D01*
X28738Y-595073D01*
X28895Y-595703D01*
X28817Y-596333D01*
X28503Y-596858D01*
X26937Y-597908D01*
X26232Y-598643D01*
X25762Y-599693D01*
X25605Y-600638D01*
X28895D01*
G01X33550D02*
Y-594338D01*
X32610Y-595598D01*
G01Y-600638D02*
X34490D01*
G01X39850D02*
Y-594338D01*
X38910Y-595598D01*
G01Y-600638D02*
X40790D01*
G01X45993Y-601793D02*
X46307Y-600428D01*
G01X50100Y-594338D02*
X51197Y-600638D01*
X52450Y-594338D01*
X53703Y-600638D01*
X54800Y-594338D01*
G01X60317Y-600638D02*
X57183D01*
Y-594338D01*
X60317D01*
G01X59063Y-597383D02*
X57183D01*
G01X63248Y-600638D02*
Y-594338D01*
X66852Y-600638D01*
Y-594338D01*
G01X69705Y-600638D02*
Y-594338D01*
G01X72995D02*
Y-600638D01*
G01Y-597488D02*
X69705D01*
G01X75927Y-594338D02*
Y-598853D01*
X76240Y-599798D01*
X76867Y-600428D01*
X77650Y-600638D01*
X78433Y-600428D01*
X79060Y-599798D01*
X79373Y-598853D01*
Y-594338D01*
G01X81992Y-600638D02*
X83950Y-594338D01*
X85908Y-600638D01*
G01X85203Y-598433D02*
X82697D01*
G01X95062Y-595388D02*
X95532Y-594758D01*
X96080Y-594443D01*
X96707Y-594338D01*
X97490Y-594548D01*
X98038Y-595073D01*
X98195Y-595703D01*
X98117Y-596333D01*
X97803Y-596858D01*
X96237Y-597908D01*
X95532Y-598643D01*
X95062Y-599693D01*
X94905Y-600638D01*
X98195D01*
G01X101048D02*
Y-594338D01*
X104652Y-600638D01*
Y-594338D01*
G01X107427Y-600638D02*
Y-594338D01*
X108993D01*
X109620Y-594653D01*
X110090Y-595073D01*
X110482Y-595703D01*
X110795Y-596438D01*
X110873Y-597488D01*
X110795Y-598538D01*
X110482Y-599273D01*
X110090Y-599903D01*
X109620Y-600323D01*
X108993Y-600638D01*
X107427D01*
G01X120183D02*
Y-594338D01*
X122142D01*
X122768Y-594653D01*
X123160Y-595073D01*
X123317Y-595913D01*
X123160Y-596753D01*
X122690Y-597278D01*
X122142Y-597593D01*
X120183D01*
G01X122142D02*
X123317Y-600638D01*
G01X126327D02*
Y-594338D01*
X127893D01*
X128520Y-594653D01*
X128990Y-595073D01*
X129382Y-595703D01*
X129695Y-596438D01*
X129773Y-597488D01*
X129695Y-598538D01*
X129382Y-599273D01*
X128990Y-599903D01*
X128520Y-600323D01*
X127893Y-600638D01*
X126327D01*
G01X134350Y-600848D02*
X134193Y-600743D01*
Y-600533D01*
X134350Y-600428D01*
X134507Y-600533D01*
Y-600743D01*
X134350Y-600848D01*
G01X30650Y-589938D02*
X28130Y-589521D01*
X25925Y-587855D01*
X24035Y-585355D01*
X22775Y-582438D01*
X22145Y-579105D01*
Y-575771D01*
X22775Y-572438D01*
X24035Y-569521D01*
X25925Y-567022D01*
X28130Y-565355D01*
X30650Y-564938D01*
X33170Y-565355D01*
X35375Y-567022D01*
X37265Y-569521D01*
X38525Y-572438D01*
X39155Y-575771D01*
Y-579105D01*
X38525Y-582438D01*
X37265Y-585355D01*
X35375Y-587855D01*
X33170Y-589521D01*
X30650Y-589938D01*
G01X33170Y-583271D02*
X36950Y-589938D01*
G01X50495Y-573272D02*
Y-584938D01*
X51755Y-587855D01*
X53645Y-589521D01*
X55850Y-589938D01*
X58055Y-589521D01*
X59945Y-587855D01*
X61205Y-584938D01*
G01Y-589938D02*
Y-573272D01*
G01X86720Y-589938D02*
Y-573272D01*
G01Y-576188D02*
X85460Y-574522D01*
X83570Y-573688D01*
X81365Y-573272D01*
X79160Y-574105D01*
X77270Y-575771D01*
X76010Y-578272D01*
X75380Y-581605D01*
X76010Y-584938D01*
X77270Y-587439D01*
X79160Y-589105D01*
X81365Y-589938D01*
X83570Y-589521D01*
X85460Y-588272D01*
X86720Y-586605D01*
G01X100895Y-589938D02*
Y-573272D01*
G01Y-577438D02*
X102155Y-575355D01*
X104045Y-573688D01*
X106565Y-573272D01*
X108770Y-573688D01*
X110660Y-575355D01*
X111605Y-578272D01*
Y-589938D01*
G01X131450Y-564938D02*
Y-589938D01*
G01X127040Y-573272D02*
X135860D01*
G01X162320Y-589938D02*
Y-573272D01*
G01Y-576188D02*
X161060Y-574522D01*
X159170Y-573688D01*
X156965Y-573272D01*
X154760Y-574105D01*
X152870Y-575771D01*
X151610Y-578272D01*
X150980Y-581605D01*
X151610Y-584938D01*
X152870Y-587439D01*
X154760Y-589105D01*
X156965Y-589938D01*
X159170Y-589521D01*
X161060Y-588272D01*
X162320Y-586605D01*
G01X202000Y-569638D02*
Y-577638D01*
X206000D01*
G01X213800D02*
Y-572305D01*
G01Y-573238D02*
X213400Y-572705D01*
X212800Y-572438D01*
X212100Y-572305D01*
X211400Y-572571D01*
X210800Y-573105D01*
X210400Y-573905D01*
X210200Y-574971D01*
X210400Y-576038D01*
X210800Y-576838D01*
X211400Y-577371D01*
X212100Y-577638D01*
X212800Y-577505D01*
X213400Y-577105D01*
X213800Y-576572D01*
G01X217900Y-580038D02*
X218500Y-580305D01*
X219300Y-580038D01*
X219800Y-579505D01*
X220200Y-578838D01*
X220800Y-576705D01*
X222100Y-572305D01*
G01X218900D02*
X220800Y-576705D01*
G01X226500Y-574038D02*
X229700D01*
X229400Y-573105D01*
X228900Y-572571D01*
X228200Y-572305D01*
X227500Y-572438D01*
X226900Y-572838D01*
X226500Y-573771D01*
X226300Y-574572D01*
Y-575371D01*
X226500Y-576171D01*
X227000Y-576971D01*
X227600Y-577505D01*
X228300Y-577638D01*
X229000Y-577371D01*
X229700Y-576572D01*
G01X234600Y-577638D02*
Y-572305D01*
G01Y-573371D02*
X235100Y-572838D01*
X235600Y-572438D01*
X236300Y-572305D01*
X236800Y-572438D01*
X237400Y-572838D01*
G01X226000Y-626038D02*
X226500Y-626838D01*
X227100Y-627371D01*
X227800Y-627638D01*
X228600Y-627371D01*
X229200Y-626838D01*
X229800Y-626038D01*
X230000Y-624971D01*
Y-619638D01*
G01X237800Y-627638D02*
Y-622305D01*
G01Y-623238D02*
X237400Y-622705D01*
X236800Y-622438D01*
X236100Y-622305D01*
X235400Y-622571D01*
X234800Y-623105D01*
X234400Y-623905D01*
X234200Y-624971D01*
X234400Y-626038D01*
X234800Y-626838D01*
X235400Y-627371D01*
X236100Y-627638D01*
X236800Y-627505D01*
X237400Y-627105D01*
X237800Y-626572D01*
G01X245600Y-622971D02*
X244900Y-622438D01*
X244300Y-622305D01*
X243500Y-622571D01*
X242900Y-623105D01*
X242500Y-624038D01*
X242400Y-624971D01*
X242500Y-625905D01*
X242900Y-626705D01*
X243500Y-627371D01*
X244300Y-627638D01*
X245000Y-627371D01*
X245600Y-626838D01*
G01X250300Y-627638D02*
Y-619638D01*
G01X253500Y-622305D02*
X250300Y-625371D01*
G01X251600Y-624171D02*
X253700Y-627638D01*
G01X238600Y-596138D02*
X240600D01*
Y-598538D01*
X240000Y-599338D01*
X239300Y-599871D01*
X238300Y-600138D01*
X237300Y-599871D01*
X236600Y-599338D01*
X236000Y-598538D01*
X235600Y-597605D01*
X235400Y-596538D01*
Y-595605D01*
X235600Y-594805D01*
X236000Y-593871D01*
X236600Y-593071D01*
X237200Y-592538D01*
X238000Y-592138D01*
X238700D01*
X239500Y-592405D01*
X240100Y-592938D01*
G01X243700Y-600138D02*
Y-592138D01*
X248300Y-600138D01*
Y-592138D01*
G01X251800Y-600138D02*
Y-592138D01*
X253800D01*
X254600Y-592538D01*
X255200Y-593071D01*
X255700Y-593871D01*
X256100Y-594805D01*
X256200Y-596138D01*
X256100Y-597471D01*
X255700Y-598405D01*
X255200Y-599205D01*
X254600Y-599738D01*
X253800Y-600138D01*
X251800D01*
G01X259800Y-598538D02*
X260400Y-599471D01*
X261200Y-600005D01*
X262100Y-600138D01*
X262900Y-600005D01*
X263700Y-599338D01*
X264200Y-598538D01*
X264300Y-597738D01*
X264100Y-596805D01*
X263400Y-596138D01*
X262700Y-595871D01*
X261800D01*
G01X262700D02*
X263300Y-595471D01*
X263800Y-594805D01*
X264000Y-594005D01*
X263800Y-593205D01*
X263300Y-592538D01*
X262400Y-592138D01*
X261500Y-592271D01*
X260600Y-592805D01*
G01X266000Y-577638D02*
X266700Y-577505D01*
X267500Y-577105D01*
X268000Y-576438D01*
X268200Y-575505D01*
X268000Y-574572D01*
X267400Y-573771D01*
X266500Y-573371D01*
X265500D01*
X264900Y-573105D01*
X264400Y-572438D01*
X264200Y-571505D01*
X264500Y-570571D01*
X265200Y-569905D01*
X266000Y-569638D01*
X266800Y-569905D01*
X267500Y-570571D01*
X267800Y-571505D01*
X267600Y-572438D01*
X267100Y-573105D01*
X266500Y-573371D01*
X265500D01*
X264600Y-573771D01*
X264000Y-574572D01*
X263800Y-575505D01*
X264000Y-576438D01*
X264500Y-577105D01*
X265300Y-577505D01*
X266000Y-577638D01*
G01X328600Y-620971D02*
X329200Y-620171D01*
X329900Y-619771D01*
X330700Y-619638D01*
X331700Y-619905D01*
X332400Y-620571D01*
X332600Y-621371D01*
X332500Y-622172D01*
X332100Y-622838D01*
X330100Y-624171D01*
X329200Y-625105D01*
X328600Y-626438D01*
X328400Y-627638D01*
X332600D01*
G01X338500Y-619638D02*
X337700Y-619905D01*
X337100Y-620571D01*
X336700Y-621371D01*
X336400Y-622438D01*
X336300Y-623638D01*
X336400Y-624838D01*
X336700Y-625905D01*
X337100Y-626705D01*
X337700Y-627371D01*
X338500Y-627638D01*
X339300Y-627371D01*
X339900Y-626705D01*
X340300Y-625905D01*
X340600Y-624838D01*
X340700Y-623638D01*
X340600Y-622438D01*
X340300Y-621371D01*
X339900Y-620571D01*
X339300Y-619905D01*
X338500Y-619638D01*
G01X344600Y-620971D02*
X345200Y-620171D01*
X345900Y-619771D01*
X346700Y-619638D01*
X347700Y-619905D01*
X348400Y-620571D01*
X348600Y-621371D01*
X348500Y-622172D01*
X348100Y-622838D01*
X346100Y-624171D01*
X345200Y-625105D01*
X344600Y-626438D01*
X344400Y-627638D01*
X348600D01*
G01X352300Y-626038D02*
X352900Y-626971D01*
X353700Y-627505D01*
X354600Y-627638D01*
X355400Y-627505D01*
X356200Y-626838D01*
X356700Y-626038D01*
X356800Y-625238D01*
X356600Y-624305D01*
X355900Y-623638D01*
X355200Y-623371D01*
X354300D01*
G01X355200D02*
X355800Y-622971D01*
X356300Y-622305D01*
X356500Y-621505D01*
X356300Y-620705D01*
X355800Y-620038D01*
X354900Y-619638D01*
X354000Y-619771D01*
X353100Y-620305D01*
G01X360700Y-627905D02*
X364300Y-619638D01*
G01X370500D02*
X369700Y-619905D01*
X369100Y-620571D01*
X368700Y-621371D01*
X368400Y-622438D01*
X368300Y-623638D01*
X368400Y-624838D01*
X368700Y-625905D01*
X369100Y-626705D01*
X369700Y-627371D01*
X370500Y-627638D01*
X371300Y-627371D01*
X371900Y-626705D01*
X372300Y-625905D01*
X372600Y-624838D01*
X372700Y-623638D01*
X372600Y-622438D01*
X372300Y-621371D01*
X371900Y-620571D01*
X371300Y-619905D01*
X370500Y-619638D01*
G01X379700Y-627638D02*
Y-619638D01*
X376000Y-625371D01*
X381000D01*
G01X384700Y-627905D02*
X388300Y-619638D01*
G01X394500Y-627638D02*
Y-619638D01*
X393300Y-621238D01*
G01Y-627638D02*
X395700D01*
G01X402300D02*
X402500Y-625905D01*
X402800Y-624438D01*
X403200Y-623105D01*
X403700Y-621638D01*
X404500Y-619638D01*
X400500D01*
G01X328300Y-602638D02*
Y-594638D01*
X330300D01*
X331100Y-595038D01*
X331700Y-595571D01*
X332200Y-596371D01*
X332600Y-597305D01*
X332700Y-598638D01*
X332600Y-599971D01*
X332200Y-600905D01*
X331700Y-601705D01*
X331100Y-602238D01*
X330300Y-602638D01*
X328300D01*
G01X336000D02*
X338500Y-594638D01*
X341000Y-602638D01*
G01X340100Y-599838D02*
X336900D01*
G01X344600Y-602638D02*
Y-594638D01*
X348400D01*
G01X347000Y-598505D02*
X344600D01*
G01X354500Y-594638D02*
X353700Y-594905D01*
X353100Y-595571D01*
X352700Y-596371D01*
X352400Y-597438D01*
X352300Y-598638D01*
X352400Y-599838D01*
X352700Y-600905D01*
X353100Y-601705D01*
X353700Y-602371D01*
X354500Y-602638D01*
X355300Y-602371D01*
X355900Y-601705D01*
X356300Y-600905D01*
X356600Y-599838D01*
X356700Y-598638D01*
X356600Y-597438D01*
X356300Y-596371D01*
X355900Y-595571D01*
X355300Y-594905D01*
X354500Y-594638D01*
G01X362500D02*
Y-602638D01*
G01X360200Y-594638D02*
X364800D01*
G01X367900Y-602638D02*
Y-594638D01*
X370500Y-601305D01*
X373100Y-594638D01*
Y-602638D01*
G01X379300Y-598371D02*
X379700Y-597971D01*
X380000Y-597305D01*
X380200Y-596371D01*
X380000Y-595571D01*
X379600Y-595038D01*
X378900Y-594638D01*
X376200D01*
Y-602638D01*
X379500D01*
X380200Y-602105D01*
X380600Y-601305D01*
X380800Y-600371D01*
X380600Y-599438D01*
X380000Y-598638D01*
X379300Y-598371D01*
X376200D01*
G01X384300Y-601038D02*
X384900Y-601971D01*
X385700Y-602505D01*
X386600Y-602638D01*
X387400Y-602505D01*
X388200Y-601838D01*
X388700Y-601038D01*
X388800Y-600238D01*
X388600Y-599305D01*
X387900Y-598638D01*
X387200Y-598371D01*
X386300D01*
G01X387200D02*
X387800Y-597971D01*
X388300Y-597305D01*
X388500Y-596505D01*
X388300Y-595705D01*
X387800Y-595038D01*
X386900Y-594638D01*
X386000Y-594771D01*
X385100Y-595305D01*
G01X393300Y-594638D02*
X395700D01*
G01X394500D02*
Y-602638D01*
G01X393300D02*
X395700D01*
G01X404700Y-595305D02*
X404100Y-594905D01*
X403400Y-594638D01*
X402600D01*
X401700Y-595038D01*
X401000Y-595705D01*
X400500Y-596505D01*
X400100Y-597838D01*
X400000Y-599038D01*
X400200Y-600238D01*
X400500Y-601038D01*
X401100Y-601838D01*
X401800Y-602371D01*
X402500Y-602638D01*
X403200D01*
X403900Y-602371D01*
X404500Y-601971D01*
X405000Y-601438D01*
G01X410500Y-594638D02*
X409700Y-594905D01*
X409100Y-595571D01*
X408700Y-596371D01*
X408400Y-597438D01*
X408300Y-598638D01*
X408400Y-599838D01*
X408700Y-600905D01*
X409100Y-601705D01*
X409700Y-602371D01*
X410500Y-602638D01*
X411300Y-602371D01*
X411900Y-601705D01*
X412300Y-600905D01*
X412600Y-599838D01*
X412700Y-598638D01*
X412600Y-597438D01*
X412300Y-596371D01*
X411900Y-595571D01*
X411300Y-594905D01*
X410500Y-594638D01*
G01X346100Y-577638D02*
Y-569638D01*
X349900D01*
G01X348500Y-573505D02*
X346100D01*
G01X356000Y-569638D02*
X355200Y-569905D01*
X354600Y-570571D01*
X354200Y-571371D01*
X353900Y-572438D01*
X353800Y-573638D01*
X353900Y-574838D01*
X354200Y-575905D01*
X354600Y-576705D01*
X355200Y-577371D01*
X356000Y-577638D01*
X356800Y-577371D01*
X357400Y-576705D01*
X357800Y-575905D01*
X358100Y-574838D01*
X358200Y-573638D01*
X358100Y-572438D01*
X357800Y-571371D01*
X357400Y-570571D01*
X356800Y-569905D01*
X356000Y-569638D01*
G01X364000D02*
Y-577638D01*
G01X361700Y-569638D02*
X366300D01*
G01X372600Y-573638D02*
X374600D01*
Y-576038D01*
X374000Y-576838D01*
X373300Y-577371D01*
X372300Y-577638D01*
X371300Y-577371D01*
X370600Y-576838D01*
X370000Y-576038D01*
X369600Y-575105D01*
X369400Y-574038D01*
Y-573105D01*
X369600Y-572305D01*
X370000Y-571371D01*
X370600Y-570571D01*
X371200Y-570038D01*
X372000Y-569638D01*
X372700D01*
X373500Y-569905D01*
X374100Y-570438D01*
G01X377000Y-580305D02*
X383000D01*
G01X385400Y-577638D02*
Y-569638D01*
X388000Y-576305D01*
X390600Y-569638D01*
Y-577638D01*
G01X396800Y-573371D02*
X397200Y-572971D01*
X397500Y-572305D01*
X397700Y-571371D01*
X397500Y-570571D01*
X397100Y-570038D01*
X396400Y-569638D01*
X393700D01*
Y-577638D01*
X397000D01*
X397700Y-577105D01*
X398100Y-576305D01*
X398300Y-575371D01*
X398100Y-574438D01*
X397500Y-573638D01*
X396800Y-573371D01*
X393700D01*
G01X417000Y-630638D02*
Y-622638D01*
X415800Y-624238D01*
G01Y-630638D02*
X418200D01*
G01X423100Y-627305D02*
X423800Y-626371D01*
X424400Y-625838D01*
X425200Y-625571D01*
X425900Y-625838D01*
X426400Y-626371D01*
X426800Y-627171D01*
X426900Y-628105D01*
X426800Y-628905D01*
X426400Y-629705D01*
X425800Y-630371D01*
X425100Y-630638D01*
X424300Y-630371D01*
X423600Y-629572D01*
X423200Y-628371D01*
X423100Y-627038D01*
X423300Y-625305D01*
X423600Y-624371D01*
X424100Y-623438D01*
X424800Y-622771D01*
X425500Y-622638D01*
X426200Y-622905D01*
X426700Y-623571D01*
G01X433000Y-630905D02*
X432800Y-630771D01*
Y-630505D01*
X433000Y-630371D01*
X433200Y-630505D01*
Y-630771D01*
X433000Y-630905D01*
G01X439100Y-627305D02*
X439800Y-626371D01*
X440400Y-625838D01*
X441200Y-625571D01*
X441900Y-625838D01*
X442400Y-626371D01*
X442800Y-627171D01*
X442900Y-628105D01*
X442800Y-628905D01*
X442400Y-629705D01*
X441800Y-630371D01*
X441100Y-630638D01*
X440300Y-630371D01*
X439600Y-629572D01*
X439200Y-628371D01*
X439100Y-627038D01*
X439300Y-625305D01*
X439600Y-624371D01*
X440100Y-623438D01*
X440800Y-622771D01*
X441500Y-622638D01*
X442200Y-622905D01*
X442700Y-623571D01*
G01X462000Y-630638D02*
Y-622638D01*
X460800Y-624238D01*
G01Y-630638D02*
X463200D01*
G01X469800D02*
X470000Y-628905D01*
X470300Y-627438D01*
X470700Y-626105D01*
X471200Y-624638D01*
X472000Y-622638D01*
X468000D01*
G01X478000Y-630905D02*
X477800Y-630771D01*
Y-630505D01*
X478000Y-630371D01*
X478200Y-630505D01*
Y-630771D01*
X478000Y-630905D01*
G01X484100Y-623971D02*
X484700Y-623171D01*
X485400Y-622771D01*
X486200Y-622638D01*
X487200Y-622905D01*
X487900Y-623571D01*
X488100Y-624371D01*
X488000Y-625172D01*
X487600Y-625838D01*
X485600Y-627171D01*
X484700Y-628105D01*
X484100Y-629438D01*
X483900Y-630638D01*
X488100D01*
G01X486200Y-598305D02*
X485600Y-597905D01*
X484900Y-597638D01*
X484100D01*
X483200Y-598038D01*
X482500Y-598705D01*
X482000Y-599505D01*
X481600Y-600838D01*
X481500Y-602038D01*
X481700Y-603238D01*
X482000Y-604038D01*
X482600Y-604838D01*
X483300Y-605371D01*
X484000Y-605638D01*
X484700D01*
X485400Y-605371D01*
X486000Y-604971D01*
X486500Y-604438D01*
M02*
